FILE_TYPE=PINLIST;
{ Packager-XL run on 16-Jun-2017 AT 17:50:48 }
TIME=' COMPILATION ON 16-Jun-2017 AT 17:50:48';
primitive '120R2F-GP_RCL_GP-120R2F-GP,64.A';body '120R2F-GP';
    '1':'(1)';
    '2':'(2)';
end_primitive;
primitive '18KR2F-GP_RCL_GP-18KR2F-GP,64.A';body '18KR2F-GP';
    '1':'(1)';
    '2':'(2)';
end_primitive;
primitive '1K82R2F-1-GP_SMD-RG-1K82R2F-1-A';body '1K82R2F-1-GP';
    '1':'(1)';
    '2':'(2)';
end_primitive;
primitive '1MR2F-L-GP_SMD-RG1-1MR2F-L-GP,A';body '1MR2F-L-GP';
    '1':'(1)';
    '2':'(2)';
end_primitive;
primitive '1R3F-GP_RCL_GP-1R3F-GP,64.1R00A';body '1R3F-GP';
    '1':'(1)';
    '2':'(2)';
end_primitive;
primitive '200R2F-L1-GP_SMD-RG4-200R2F-L1A';body '200R2F-L1-GP';
    '1':'(1)';
    '2':'(2)';
end_primitive;
primitive '21K5R2F-GP_RCL_GP-21K5R2F-GP,6A';body '21K5R2F-GP';
    '1':'(1)';
    '2':'(2)';
end_primitive;
primitive '232KR2F-2-GP_SMD-RG1-232KR2F-2A';body '232KR2F-2-GP';
    '1':'(1)';
    '2':'(2)';
end_primitive;
primitive '270KR2F-GP_RCL_GP-270KR2F-GP,6A';body '270KR2F-GP';
    '1':'(1)';
    '2':'(2)';
end_primitive;
primitive '2K15R2F-1-GP_SMD-RG1-2K15R2F-1A';body '2K15R2F-1-GP';
    '1':'(1)';
    '2':'(2)';
end_primitive;
primitive '2SB2907A-B0-00001-GP_DISCRET-GA';body '2SB2907A-B0-00001-GP';
    'C':'(C)';
    'B':'(B)';
    'E':'(E)';
end_primitive;
primitive '374R2F-1-GP_SMD-RG-374R2F-1-GPA';body '374R2F-1-GP';
    '1':'(1)';
    '2':'(2)';
end_primitive;
primitive '47KR2F-GP_RCL_GP-47KR2F-GP,64.A';body '47KR2F-GP';
    '1':'(1)';
    '2':'(2)';
end_primitive;
primitive '4D02R2F-GP_SMD-RG2-4D02R2F-GP,A';body '4D02R2F-GP';
    '1':'(1)';
    '2':'(2)';
end_primitive;
primitive '4K42R2F-GP_SMD-RG-4K42R2F-GP,6A';body '4K42R2F-GP';
    '1':'(1)';
    '2':'(2)';
end_primitive;
primitive '5K1R2F-2-GP_SMD-RG-5K1R2F-2-GPA';body '5K1R2F-2-GP';
    '1':'(1)';
    '2':'(2)';
end_primitive;
primitive '649R2F-GP_RCL_GP-649R2F-GP,64.A';body '649R2F-GP';
    '1':'(1)';
    '2':'(2)';
end_primitive;
primitive '665KR2B-GP_SMD-RG2-665KR2B-GP,A';body '665KR2B-GP';
    '1':'(1)';
    '2':'(2)';
end_primitive;
primitive '665KR5B-1-GP_SMD-RG3-665KR5B-1A';body '665KR5B-1-GP';
    '1':'(1)';
    '2':'(2)';
end_primitive;
primitive '74CBTLV1G125_SMLF-IC,C88177-00A';body '74CBTLV1G125';
    'B':'(4)';OUT;
    'OE_N':'(1)';IN;
    'A':'(2)';IN;
end_primitive;
primitive '82KR2F-1-GP_SMD-RG-82KR2F-1-GPA';body '82KR2F-1-GP';
    '1':'(1)';
    '2':'(2)';
end_primitive;
primitive '887R2F-L-GP_SMD-RG-887R2F-L-GPA';body '887R2F-L-GP';
    '1':'(1)';
    '2':'(2)';
end_primitive;
primitive 'ADM1085_SMT-IC,H46130-001';body 'ADM1085';
    'CEXT':'(5)';
    'ENIN':'(1)';IN;
    'ENOUT':'(4)';OUT;
    'GND':'(2)';
    'VCC':'(6)';
    'VIN':'(3)';IN;
end_primitive;
primitive 'ADM1278_SM-IC,G99251-001';body 'ADM1278';
    'ADR1':'(7)';
    'ADR2':'(8)';
    'CSOUT':'(19)';OUT;
    'ENABLE':'(12)';IN;
    'EP':'(33)';
    'FAULT_N':'(6)';
    'GATE':'(24)';OUT;
    'GND':'(22)';
    'GPO1_ALERT1_N_CONV':'(13)';BIDI;
    'GPO2_ALERT2_N':'(14)';BIDI;
    'HSN':'(27)';IN;
    'HSP':'(28)';IN;
    'ISET':'(3)';IN;
    'ISTART':'(4)';IN;
    'MCLK':'(10)';OUT;
    'MDAT':'(11)';OUT;
    'MON':'(26)';IN;
    'MOP':'(29)';IN;
    'OV':'(32)';IN;
    'PGND':'(23)';
    'PSET':'(1)';IN;
    'PWGIN':'(21)';IN;
    'PWRGD':'(18)';
    'RETRY_N':'(17)';
    'SCL':'(16)';IN;
    'SDA':'(15)';BIDI;
    'SPISS_N':'(9)';
    'TEMP':'(25)';IN;
    'TIMER':'(5)';
    'UV':'(31)';IN;
    'VCAP':'(2)';IN;
    'VCC':'(30)';
    'VOUT':'(20)';OUT;
end_primitive;
primitive 'ADM809_SMLF-IC,D23047-001-GND=A';body 'ADM809';
    'VCC':'(3)';
    'RESET_N':'(2)';OUT;
end_primitive;
primitive 'AST2520A1-GP-GP_ASIC2-GB1-AST2A';body 'AST2520A1-GP-GP';
    'MDQ4':'(U9,0,0,0,0,0,0)';$S;BIDI;
    'MDQ3':'(AA10,0,0,0,0,0,0)';$S;BIDI;
    'MDQ2':'(Y10,0,0,0,0,0,0)';$S;BIDI;
    'MDQ1':'(W10,0,0,0,0,0,0)';$S;BIDI;
    'MDQ0':'(U10,0,0,0,0,0,0)';$S;BIDI;
    'MA15':'(U15,0,0,0,0,0,0)';$S;OUT;
    'MDQ15':'(U7,0,0,0,0,0,0)';$S;BIDI;
    'MDQ14':'(V7,0,0,0,0,0,0)';$S;BIDI;
    'MDM1':'(AB8,0,0,0,0,0,0)';$S;OUT;
    'MIOZ':'(W11,0,0,0,0,0,0)';$S;
    'MCAS#':'(AB13,0,0,0,0,0,0)';$S;OUT;
    'MA10':'(U13,0,0,0,0,0,0)';$S;OUT;
    'MA11':'(AA14,0,0,0,0,0,0)';$S;OUT;
    'MVREF':'(T9,0,0,0,0,0,0)';$S;
    'MDQ9':'(Y8,0,0,0,0,0,0)';$S;BIDI;
    'MODT':'(V11,0,0,0,0,0,0)';$S;OUT;
    'MCKE':'(Y11,0,0,0,0,0,0)';$S;OUT;
    'MCKN':'(AB12,0,0,0,0,0,0)';$S;OUT;
    'MBA2_MBG0':'(W13,0,0,0,0,0,0)';$S;OUT;
    'MBA1':'(Y13,0,0,0,0,0,0)';$S;OUT;
    'MBA0':'(U12,0,0,0,0,0,0)';$S;OUT;
    'MA9':'(Y16,0,0,0,0,0,0)';$S;OUT;
    'MA8':'(W16,0,0,0,0,0,0)';$S;OUT;
    'MA7':'(AA16,0,0,0,0,0,0)';$S;OUT;
    'MA6':'(AB16,0,0,0,0,0,0)';$S;OUT;
    'MA5':'(V15,0,0,0,0,0,0)';$S;OUT;
    'MA4':'(W15,0,0,0,0,0,0)';$S;OUT;
    'MA3':'(U14,0,0,0,0,0,0)';$S;OUT;
    'MA2':'(W14,0,0,0,0,0,0)';$S;OUT;
    'MA12':'(Y14,0,0,0,0,0,0)';$S;OUT;
    'MA1':'(AB14,0,0,0,0,0,0)';$S;OUT;
    'MA0':'(V13,0,0,0,0,0,0)';$S;OUT;
    'MDQS1P':'(AB7,0,0,0,0,0,0)';$S;BIDI;
    'MDQS1N':'(AB6,0,0,0,0,0,0)';$S;BIDI;
    'MDQS0P':'(AB9,0,0,0,0,0,0)';$S;BIDI;
    'MDQS0N':'(AB10,0,0,0,0,0,0)';$S;BIDI;
    'MDQ6':'(W9,0,0,0,0,0,0)';$S;BIDI;
    'MDQ5':'(Y9,0,0,0,0,0,0)';$S;BIDI;
    'MDQ13':'(W7,0,0,0,0,0,0)';$S;BIDI;
    'MDQ12':'(AA6,0,0,0,0,0,0)';$S;BIDI;
    'MDM0':'(U8,0,0,0,0,0,0)';$S;OUT;
    'MA13':'(AB15,0,0,0,0,0,0)';$S;OUT;
    'MA14_MACT#':'(Y15,0,0,0,0,0,0)';$S;OUT;
    'MDQ11':'(W8,0,0,0,0,0,0)';$S;BIDI;
    'MDQ10':'(Y7,0,0,0,0,0,0)';$S;BIDI;
    'MWE#':'(Y12,0,0,0,0,0,0)';$S;OUT;
    'MRAS#':'(W12,0,0,0,0,0,0)';$S;OUT;
    'MDQ7':'(V9,0,0,0,0,0,0)';$S;BIDI;
    'MDQ8':'(AA8,0,0,0,0,0,0)';$S;BIDI;
    'MCKP':'(AB11,0,0,0,0,0,0)';$S;OUT;
    'MCS#':'(AA12,0,0,0,0,0,0)';$S;OUT;
    'GPIOB6_LPCPME#':'(0,H22,0,0,0,0,0)';$S;BIDI;
    'GPIOB4_USBCKI':'(0,J20,0,0,0,0,0)';$S;BIDI;
    'GPIOY4_SCL1':'(0,M18,0,0,0,0,0)';$S;BIDI;
    'GPIOI7_SPI1MISO_VBMISO':'(0,A15,0,0,0,0,0)';$S;BIDI;
    'DACRSET':'(0,K4,0,0,0,0,0)';$S;
    'DACR':'(0,J4,0,0,0,0,0)';$S;OUT;
    'DACG':'(0,J3,0,0,0,0,0)';$S;OUT;
    'TMS':'(0,C8,0,0,0,0,0)';$S;BIDI;
    'TDI':'(0,D12,0,0,0,0,0)';$S;BIDI;
    'TCK':'(0,C10,0,0,0,0,0)';$S;BIDI;
    'RTCK':'(0,C9,0,0,0,0,0)';$S;OUT;
    'NTRST':'(0,E11,0,0,0,0,0)';$S;BIDI;
    'GPIOI1_SYSCK':'(0,E15,0,0,0,0,0)';$S;BIDI;
    'GPIOI0_SYSCS#':'(0,C18,0,0,0,0,0)';$S;BIDI;
    'GPIOI5_SPI1CK_VBCK':'(0,C15,0,0,0,0,0)';$S;BIDI;
    'GPIOI4_SPI1CS0#_VBCS#':'(0,B15,0,0,0,0,0)';$S;BIDI;
    'GPIOI6_SPI1MOSI_VBMOSI':'(0,A14,0,0,0,0,0)';$S;BIDI;
    'GPIOJ1_SGPMLD':'(0,L2,0,0,0,0,0)';$S;BIDI;
    'GPIOJ0_SGPMCK':'(0,R2,0,0,0,0,0)';$S;BIDI;
    'GPIOJ2_SGPMO':'(0,N3,0,0,0,0,0)';$S;BIDI;
    'GPIOG3_SGPS1I1':'(0,E16,0,0,0,0,0)';$S;BIDI;
    'GPIOG2_SGPS1I0':'(0,C19,0,0,0,0,0)';$S;BIDI;
    'DACB':'(0,J2,0,0,0,0,0)';$S;OUT;
    'GPIOY5_SDA1':'(0,M19,0,0,0,0,0)';$S;BIDI;
    'TDO':'(0,D11,0,0,0,0,0)';$S;BIDI;
    'GPIOB0':'(0,K19,0,0,0,0,0)';$S;BIDI;
    'GPIOB1':'(0,L19,0,0,0,0,0)';$S;BIDI;
    'GPIOB2':'(0,L18,0,0,0,0,0)';$S;BIDI;
    'GPIOB3':'(0,K18,0,0,0,0,0)';$S;BIDI;
    'GPIOB7':'(0,H20,0,0,0,0,0)';$S;BIDI;
    'GPIOY6_SCL2':'(0,M20,0,0,0,0,0)';$S;BIDI;
    'GPIOY7_SDA2':'(0,P20,0,0,0,0,0)';$S;BIDI;
    'GPIOQ0_SCL3':'(0,A11,0,0,0,0,0)';$S;BIDI;
    'GPIOQ1_SDA3':'(0,A10,0,0,0,0,0)';$S;BIDI;
    'GPIOQ2_SCL4':'(0,A9,0,0,0,0,0)';$S;BIDI;
    'GPIOQ3_SDA4':'(0,B9,0,0,0,0,0)';$S;BIDI;
    'GPIOK0_SCL5':'(0,L3,0,0,0,0,0)';$S;BIDI;
    'GPIOK1_SDA5':'(0,L4,0,0,0,0,0)';$S;BIDI;
    'GPIOK2_SCL6':'(0,L1,0,0,0,0,0)';$S;BIDI;
    'GPIOK3_SDA6':'(0,N2,0,0,0,0,0)';$S;BIDI;
    'GPIOG1_SGPS1LD':'(0,E19,0,0,0,0,0)';$S;BIDI;
    'GPIOG0_SGPS1CK':'(0,A19,0,0,0,0,0)';$S;BIDI;
    'GPIOJ3_SGPMI':'(0,N4,0,0,0,0,0)';$S;BIDI;
    'GPIOI2_SYSMOSI':'(0,B16,0,0,0,0,0)';$S;BIDI;
    'GPIOI3_SYSMISO':'(0,C16,0,0,0,0,0)';$S;BIDI;
    'GPIOA5_TIMER6_SDA9':'(0,A13,0,0,0,0,0)';$S;BIDI;
    'GPIOA4_TIMER5_SCL9':'(0,C14,0,0,0,0,0)';$S;BIDI;
    'GPIOK7_SDA8':'(0,R1,0,0,0,0,0)';$S;BIDI;
    'GPIOK6_SCL8':'(0,P2,0,0,0,0,0)';$S;BIDI;
    'GPIOK5_SDA7':'(0,P1,0,0,0,0,0)';$S;BIDI;
    'GPIOK4_SCL7':'(0,N1,0,0,0,0,0)';$S;BIDI;
    'GPIOB5_LPCPD#_LPCSMI#':'(0,H21,0,0,0,0,0)';$S;BIDI;
    'GPIOQ4_SCL14':'(0,N21,0,0,0,0,0)';$S;BIDI;
    'GPIOQ5_SDA14':'(0,N22,0,0,0,0,0)';$S;BIDI;
    'GPIOC2_SD1DAT0_SCL11':'(0,0,B12,0,0,0,0)';$S;BIDI;
    'GPIOC3_SD1DAT1_SDA11':'(0,0,D9,0,0,0,0)';$S;BIDI;
    'GPIOC1_SD1CMD_SDA10':'(0,0,A12,0,0,0,0)';$S;BIDI;
    'GPIOC0_SD1CLK_SCL10':'(0,0,C12,0,0,0,0)';$S;BIDI;
    'GPIOA0_MAC1LINK':'(0,0,B14,0,0,0,0)';$S;BIDI;
    'GPIOA1_MAC2LINK':'(0,0,D14,0,0,0,0)';$S;BIDI;
    'GPIOY3_SIOONCTRL#':'(0,0,P21,0,0,0,0)';$S;BIDI;
    'GPIOG6_SGPS2I0_SALT3':'(0,0,D15,0,0,0,0)';$S;BIDI;
    'GPIOC6_SD1CD#_SCL13':'(0,0,C11,0,0,0,0)';$S;BIDI;
    'GPIOC4_SD1DAT2_SCL12':'(0,0,D10,0,0,0,0)';$S;BIDI;
    'GPIOG7_SGPS2I1_SALT4':'(0,0,E14,0,0,0,0)';$S;BIDI;
    'GPIOA2_TIMER3_SPI1CS1#':'(0,0,D13,0,0,0,0)';$S;BIDI;
    'GPIOG5_SGPS2LD_SALT2':'(0,0,D16,0,0,0,0)';$S;BIDI;
    'GPIOG4_SGPS2CK_SALT1':'(0,0,E17,0,0,0,0)';$S;BIDI;
    'GPIOF5_NRTS4_LHFRAME#':'(0,0,H19,0,0,0,0)';$S;BIDI;
    'GPIOF7_RXD4_LHRST#':'(0,0,H18,0,0,0,0)';$S;BIDI;
    'GPIOL2_NDSR1':'(0,0,U1,0,0,0,0)';$S;BIDI;
    'GPIOL3_NRI1_VPIHS':'(0,0,U2,0,0,0,0)';$S;BIDI;
    'GPIOL4_NDTR1_VPIVS':'(0,0,P4,0,0,0,0)';$S;BIDI;
    'PEREFCLKN':'(0,0,K22,0,0,0,0)';$S;IN;
    'PEREFCLKP':'(0,0,K21,0,0,0,0)';$S;IN;
    'RXD5':'(0,0,K2,0,0,0,0)';$S;IN;
    'PECI':'(0,0,AB18,0,0,0,0)';$S;BIDI;
    'GPIOD3_SD2DAT1':'(0,0,D20,0,0,0,0)';$S;BIDI;
    'GPIOD4_SD2DAT2':'(0,0,D21,0,0,0,0)';$S;BIDI;
    'GPIOD1_SD2CMD':'(0,0,E21,0,0,0,0)';$S;BIDI;
    'CLKIN':'(0,0,W18,0,0,0,0)';$S;IN;
    'SRST#':'(0,0,U18,0,0,0,0)';$S;IN;
    'GPIOA3_TIMER4':'(0,0,E13,0,0,0,0)';$S;BIDI;
    'PERST#':'(0,0,L20,0,0,0,0)';$S;BIDI;
    'PERXN':'(0,0,M22,0,0,0,0)';$S;IN;
    'PERXP':'(0,0,M21,0,0,0,0)';$S;IN;
    'GPIOM0_NCTS2_VPIB2':'(0,0,Y1,0,0,0,0)';$S;BIDI;
    'GPIOM1_NDCD2_VPIB3':'(0,0,AB2,0,0,0,0)';$S;BIDI;
    'GPIOM2_NDSR2_VPIB4':'(0,0,AA1,0,0,0,0)';$S;BIDI;
    'GPIOM3_NRI2_VPIB5':'(0,0,Y2,0,0,0,0)';$S;BIDI;
    'GPIOM4_NDTR2_VPIB6':'(0,0,AA2,0,0,0,0)';$S;BIDI;
    'GPIOM5_NRTS2_VPIB7':'(0,0,P5,0,0,0,0)';$S;BIDI;
    'GPIOM6_TXD2_VPIB8':'(0,0,R5,0,0,0,0)';$S;BIDI;
    'GPIOM7_RXD2_VPIB9':'(0,0,T5,0,0,0,0)';$S;BIDI;
    'GPIOL1_NDCD1_VPIDE':'(0,0,T1,0,0,0,0)';$S;BIDI;
    'GPIOL5_NRTS1_VPICLK':'(0,0,P3,0,0,0,0)';$S;BIDI;
    'GPIOL7_RXD1':'(0,0,W1,0,0,0,0)';$S;BIDI;
    'GPIOF0_NCTS4_LHAD0':'(0,0,J19,0,0,0,0)';$S;BIDI;
    'GPIOF1_NDCD4_LHAD1':'(0,0,J18,0,0,0,0)';$S;BIDI;
    'GPIOF2_NDSR4_LHAD2':'(0,0,B22,0,0,0,0)';$S;BIDI;
    'GPIOE2_NDSR3':'(0,0,F18,0,0,0,0)';$S;BIDI;
    'GPIOE3_NRI3':'(0,0,F17,0,0,0,0)';$S;BIDI;
    'GPIOE4_NDTR3':'(0,0,E18,0,0,0,0)';$S;BIDI;
    'GPIOE6_TXD3':'(0,0,A20,0,0,0,0)';$S;BIDI;
    'GPIOE7_RXD3':'(0,0,B19,0,0,0,0)';$S;BIDI;
    'TXD5':'(0,0,K1,0,0,0,0)';$S;OUT;
    'PEREXT':'(0,0,K20,0,0,0,0)';$S;
    'PETXN':'(0,0,L22,0,0,0,0)';$S;OUT;
    'PETXP':'(0,0,L21,0,0,0,0)';$S;OUT;
    'GPIOE5_NRTS3':'(0,0,D19,0,0,0,0)';$S;BIDI;
    'GPIOE1_NDCD3':'(0,0,C20,0,0,0,0)';$S;BIDI;
    'GPIOE0_NCTS3':'(0,0,B20,0,0,0,0)';$S;BIDI;
    'GPIOD0_SD2CLK':'(0,0,F19,0,0,0,0)';$S;BIDI;
    'GPIOD2_SD2DAT0':'(0,0,F20,0,0,0,0)';$S;BIDI;
    'GPIOD7_SD2WP#':'(0,0,C21,0,0,0,0)';$S;BIDI;
    'GPIOC7_SD1WP#_SDA13':'(0,0,B11,0,0,0,0)';$S;BIDI;
    'GPIOC5_SD1DAT3_SDA12':'(0,0,E12,0,0,0,0)';$S;BIDI;
    'GPIOL0_NCTS1':'(0,0,T2,0,0,0,0)';$S;BIDI;
    'GPIOF3_NRI4_LHAD3':'(0,0,B21,0,0,0,0)';$S;BIDI;
    'GPIOF4_NDTR4_LHCLK':'(0,0,A21,0,0,0,0)';$S;BIDI;
    'GPIOF6_TXD4_LHSIRQ#':'(0,0,G17,0,0,0,0)';$S;BIDI;
    'GPIOL6_TXD1':'(0,0,V1,0,0,0,0)';$S;BIDI;
    'GPIOD6_SD2CD#':'(0,0,G18,0,0,0,0)';$S;BIDI;
    'GPIOD5_SD2DAT3':'(0,0,E20,0,0,0,0)';$S;BIDI;
    'USB2BVRES':'(0,0,0,B7,0,0,0)';$S;
    'USB2AVRES':'(0,0,0,B8,0,0,0)';$S;
    'GPIOH0_NCTS6':'(0,0,0,A18,0,0,0)';$S;BIDI;
    'GPIOH2_NDSR6':'(0,0,0,D17,0,0,0)';$S;BIDI;
    'GPIOH1_NDCD6':'(0,0,0,B18,0,0,0)';$S;BIDI;
    'GPIOH4_NDTR6':'(0,0,0,A17,0,0,0)';$S;BIDI;
    'GPIOH3_NRI6':'(0,0,0,C17,0,0,0)';$S;BIDI;
    'GPIOH5_NRTS6':'(0,0,0,B17,0,0,0)';$S;BIDI;
    'GPIOH7_RXD6':'(0,0,0,D18,0,0,0)';$S;BIDI;
    'GPIOH6_TXD6':'(0,0,0,A16,0,0,0)';$S;BIDI;
    'GPIOS0_VPOB2_SPI2CS1#':'(0,0,0,V20,0,0,0)';$S;BIDI;
    'GPIOS2_VPOB4_SALT5':'(0,0,0,R18,0,0,0)';$S;BIDI;
    'GPIOZ1_VPOG3_NORA1_SIOPWRGD':'(0,0,0,AB20,0,0,0)';$S;BIDI;
    'GPIOZ2_VPOG4_NORA2_SIOPBO#':'(0,0,0,AB21,0,0,0)';$S;BIDI;
    'GPIOZ3_VPOG5_NORA3_SIOSCI#':'(0,0,0,AA21,0,0,0)';$S;BIDI;
    'GPIOZ4_VPOG6_NORA4':'(0,0,0,U21,0,0,0)';$S;BIDI;
    'GPIOZ5_VPOG7_NORA5':'(0,0,0,W22,0,0,0)';$S;BIDI;
    'GPIOZ6_VPOG8_NORA6':'(0,0,0,V22,0,0,0)';$S;BIDI;
    'GPIOZ7_VPOG9_NORA7':'(0,0,0,W21,0,0,0)';$S;BIDI;
    'GPIOAA0_VPOR2_NORD0_SALT7':'(0,0,0,Y21,0,0,0)';$S;BIDI;
    'GPIOS3_VPOB5_SALT6':'(0,0,0,P18,0,0,0)';$S;BIDI;
    'GPIOS7_VPOB9':'(0,0,0,AA20,0,0,0)';$S;BIDI;
    'GPIOZ0_VPOG2_NORA0_SIOPBI#':'(0,0,0,Y20,0,0,0)';$S;BIDI;
    'GPIOAA2_VPOR4_NORD2_SALT9':'(0,0,0,Y22,0,0,0)';$S;BIDI;
    'USB2A_DP':'(0,0,0,A7,0,0,0)';$S;BIDI;
    'USB2A_DN':'(0,0,0,A8,0,0,0)';$S;BIDI;
    'USB2B_DP':'(0,0,0,B6,0,0,0)';$S;BIDI;
    'USB2B_DN':'(0,0,0,A6,0,0,0)';$S;BIDI;
    'GPIOS6_VPOB8':'(0,0,0,U20,0,0,0)';$S;BIDI;
    'GPIOS5_VPOB7':'(0,0,0,W20,0,0,0)';$S;BIDI;
    'GPIOS4_VPOB6':'(0,0,0,R19,0,0,0)';$S;BIDI;
    'GPIOS1_VPOB3_BMCINT':'(0,0,0,U19,0,0,0)';$S;BIDI;
    'GPIOAA1_VPOR3_NORD1_SALT8':'(0,0,0,V21,0,0,0)';$S;BIDI;
    'GPIOAA7_VPOR9_NORD7_SALT14':'(0,0,0,P19,0,0,0)';$S;BIDI;
    'GPIOAA6_VPOR8_NORD6_SALT13':'(0,0,0,N18,0,0,0)';$S;BIDI;
    'GPIOAA5_VPOR7_NORD5_SALT12':'(0,0,0,T20,0,0,0)';$S;BIDI;
    'GPIOAA4_VPOR6_NORD4_SALT11':'(0,0,0,U22,0,0,0)';$S;BIDI;
    'GPIOAA3_VPOR5_NORD3_SALT10':'(0,0,0,AA22,0,0,0)';$S;BIDI;
    'GPIOAC7_ESPIRST#_LPCRST#':'(0,0,0,0,G22,0,0)';$S;BIDI;
    'ENTEST':'(0,0,0,0,K3,0,0)';$S;IN;
    'EXTRST#':'(0,0,0,0,V18,0,0)';$S;IN;
    'GPIOQ6_OSCCLK':'(0,0,0,0,B10,0,0)';$S;BIDI;
    'GPIOQ7_PEWAKE#':'(0,0,0,0,N20,0,0)';$S;BIDI;
    'GPIOR5_SPI2MISO':'(0,0,0,0,V19,0,0)';$S;BIDI;
    'GPIOR2_SPI2CS0#':'(0,0,0,0,T17,0,0)';$S;BIDI;
    'GPIOR1_FWSPICS2#':'(0,0,0,0,T19,0,0)';$S;BIDI;
    'GPIOR0_FWSPICS1#':'(0,0,0,0,AA19,0,0)';$S;BIDI;
    'MRESET#':'(0,0,0,0,AB17,0,0)';$S;OUT;
    'MALERT#':'(0,0,0,0,U16,0,0)';$S;BIDI;
    'HBLED#':'(0,0,0,0,Y18,0,0)';$S;OUT;
    'GPIOJ4_VGAHS':'(0,0,0,0,N5,0,0)';$S;BIDI;
    'FWSPIMOSI':'(0,0,0,0,U17,0,0)';$S;BIDI;
    'FWSPICK':'(0,0,0,0,AA18,0,0)';$S;BIDI;
    'GPIOJ7_DDCDAT':'(0,0,0,0,T3,0,0)';$S;BIDI;
    'GPIOJ6_DDCCLK':'(0,0,0,0,R3,0,0)';$S;BIDI;
    'GPIOJ5_VGAVS':'(0,0,0,0,R4,0,0)';$S;BIDI;
    'GPIOAB3_VPOCLK_WDTRST2':'(0,0,0,0,R20,0,0)';$S;BIDI;
    'GPIOAB2_VPOVS_WDTRST1':'(0,0,0,0,T22,0,0)';$S;BIDI;
    'GPIOAB1_VPOHS_NORWE#':'(0,0,0,0,T21,0,0)';$S;BIDI;
    'GPIOAB0_VPODE_NOROE#':'(0,0,0,0,N19,0,0)';$S;BIDI;
    'GPIOAC4_ESPICK_LCLK':'(0,0,0,0,C22,0,0)';$S;BIDI;
    'GPIOAC3_ESPID3_LAD3':'(0,0,0,0,E22,0,0)';$S;BIDI;
    'GPIOAC2_ESPID2_LAD2':'(0,0,0,0,D22,0,0)';$S;BIDI;
    'GPIOAC1_ESPID1_LAD1':'(0,0,0,0,G20,0,0)';$S;BIDI;
    'GPIOAC0_ESPID0_LAD0':'(0,0,0,0,G21,0,0)';$S;BIDI;
    'FWSPIMISO':'(0,0,0,0,T18,0,0)';$S;BIDI;
    'FWSPICS0#':'(0,0,0,0,AB19,0,0)';$S;BIDI;
    'GPIOAC6_ESPIALT#_LSIRQ#':'(0,0,0,0,F22,0,0)';$S;BIDI;
    'GPIOAC5_ESPICS#_LFRAME#':'(0,0,0,0,F21,0,0)';$S;BIDI;
    'GPIOR3_SPI2CK':'(0,0,0,0,Y19,0,0)';$S;BIDI;
    'GPIOR4_SPI2MOSI':'(0,0,0,0,W19,0,0)';$S;BIDI;
    'ADC8_GPIX0':'(0,0,0,0,0,F2,0)';$S;IN;
    'ADC7_GPIW7':'(0,0,0,0,0,G4,0)';$S;IN;
    'GPIOA6_TIMER7_MDC2':'(0,0,0,0,0,C13,0)';$S;BIDI;
    'GPIOA7_TIMER8_MDIO2':'(0,0,0,0,0,B13,0)';$S;BIDI;
    'RGMIICK':'(0,0,0,0,0,D3,0)';$S;IN;
    'GPION6_PWM6_VPIG6':'(0,0,0,0,0,Y3,0)';$S;BIDI;
    'GPION7_PWM7_VPIG7':'(0,0,0,0,0,T4,0)';$S;BIDI;
    'GPION4_PWM4_VPIG4':'(0,0,0,0,0,W3,0)';$S;BIDI;
    'GPION5_PWM5_VPIG5':'(0,0,0,0,0,AA3,0)';$S;BIDI;
    'GPION3_PWM3_VPIG3':'(0,0,0,0,0,U3,0)';$S;BIDI;
    'GPION1_PWM1':'(0,0,0,0,0,W2,0)';$S;BIDI;
    'GPION2_PWM2_VPIG2':'(0,0,0,0,0,V3,0)';$S;BIDI;
    'GPION0_PWM0':'(0,0,0,0,0,V2,0)';$S;BIDI;
    'ADCVREFP':'(0,0,0,0,0,H2,0)';$S;OUT;
    'ADCREXT':'(0,0,0,0,0,J1,0)';$S;OUT;
    'ADCVREFN':'(0,0,0,0,0,H1,0)';$S;OUT;
    'ADC14_GPIX6':'(0,0,0,0,0,H3,0)';$S;IN;
    'ADC15_GPIX7':'(0,0,0,0,0,H4,0)';$S;IN;
    'ADC13_GPIX5':'(0,0,0,0,0,G1,0)';$S;IN;
    'ADC12_GPIX4':'(0,0,0,0,0,H5,0)';$S;IN;
    'ADC11_GPIX3':'(0,0,0,0,0,F1,0)';$S;IN;
    'ADC9_GPIX1':'(0,0,0,0,0,G3,0)';$S;IN;
    'ADC10_GPIX2':'(0,0,0,0,0,G2,0)';$S;IN;
    'ADC6_GPIW6':'(0,0,0,0,0,G5,0)';$S;IN;
    'ADC4_GPIW4':'(0,0,0,0,0,F3,0)';$S;IN;
    'ADC5_GPIW5':'(0,0,0,0,0,E3,0)';$S;IN;
    'ADC3_GPIW3':'(0,0,0,0,0,E1,0)';$S;IN;
    'ADC2_GPIW2':'(0,0,0,0,0,E2,0)';$S;IN;
    'ADC1_GPIW1':'(0,0,0,0,0,F5,0)';$S;IN;
    'ADC0_GPIW0':'(0,0,0,0,0,F4,0)';$S;IN;
    'GPIOP7_TACH15':'(0,0,0,0,0,V6,0)';$S;BIDI;
    'GPIOP6_TACH14':'(0,0,0,0,0,W6,0)';$S;BIDI;
    'GPIOP3_TACH11_VPIR9':'(0,0,0,0,0,AB5,0)';$S;BIDI;
    'GPIOP4_TACH12':'(0,0,0,0,0,Y6,0)';$S;BIDI;
    'GPIOP5_TACH13':'(0,0,0,0,0,Y5,0)';$S;BIDI;
    'GPIOP2_TACH10_VPIR8':'(0,0,0,0,0,AA5,0)';$S;BIDI;
    'GPIOP1_TACH9_VPIR7':'(0,0,0,0,0,W5,0)';$S;BIDI;
    'GPIOO6_TACH6_VPIR4':'(0,0,0,0,0,AA4,0)';$S;BIDI;
    'GPIOO7_TACH7_VPIR5':'(0,0,0,0,0,W4,0)';$S;BIDI;
    'GPIOP0_TACH8_VPIR6':'(0,0,0,0,0,V4,0)';$S;BIDI;
    'GPIOO4_TACH4_VPIR2':'(0,0,0,0,0,AB3,0)';$S;BIDI;
    'GPIOO5_TACH5_VPIR3':'(0,0,0,0,0,Y4,0)';$S;BIDI;
    'GPIOO3_TACH3':'(0,0,0,0,0,AB4,0)';$S;BIDI;
    'GPIOO1_TACH1_VPIG9':'(0,0,0,0,0,U4,0)';$S;BIDI;
    'GPIOO2_TACH2':'(0,0,0,0,0,V5,0)';$S;BIDI;
    'GPIOO0_TACH0_VPIG8':'(0,0,0,0,0,U5,0)';$S;BIDI;
    'RGMII2TXCTL_RMII2TXEN_GPIOT7':'(0,0,0,0,0,B1,0)';$S;OUT;
    'RGMII2TXCK_RMII2RCLKO_GPIOT6':'(0,0,0,0,0,B2,0)';$S;OUT;
    'RGMII2TXD2_GPIOU2':'(0,0,0,0,0,D5,0)';$S;OUT;
    'RGMII2TXD3_GPIOU3':'(0,0,0,0,0,D4,0)';$S;OUT;
    'RGMII2TXD1_RMII2TXD1_GPIOU1':'(0,0,0,0,0,B3,0)';$S;OUT;
    'RGMII2TXD0_RMII2TXD0_GPIOU0':'(0,0,0,0,0,A2,0)';$S;OUT;
    'RGMII1TXCK_RMII1RCLKO_GPIOT0':'(0,0,0,0,0,B5,0)';$S;OUT;
    'RGMII1TXCTL_RMII1TXEN_GPIOT1':'(0,0,0,0,0,E9,0)';$S;OUT;
    'RGMII1TXD2_GPIOT4':'(0,0,0,0,0,E7,0)';$S;OUT;
    'RGMII1TXD3_GPIOT5':'(0,0,0,0,0,D7,0)';$S;OUT;
    'RGMII1TXD0_RMII1TXD0_GPIOT2':'(0,0,0,0,0,F9,0)';$S;OUT;
    'RGMII1TXD1_RMII1TXD1_GPIOT3':'(0,0,0,0,0,A5,0)';$S;OUT;
    'RGMII2RXCTL_GPIOV3':'(0,0,0,0,0,C1,0)';$S;BIDI;
    'GPIOR6_MDC1':'(0,0,0,0,0,D8,0)';$S;BIDI;
    'GPIOR7_MDIO1':'(0,0,0,0,0,E10,0)';$S;BIDI;
    'RGMII1RXD0_RMII1RXD0_GPIOU6':'(0,0,0,0,0,A3,0)';$S;BIDI;
    'RGMII1RXD1_RMII1RXD1_GPIOU7':'(0,0,0,0,0,D6,0)';$S;BIDI;
    'RGMII1RXD2_RMII1CRSDV_GPIOV0':'(0,0,0,0,0,C5,0)';$S;BIDI;
    'RGMII1RXD3_RMII1RXER_GPIOV1':'(0,0,0,0,0,C4,0)';$S;BIDI;
    'RGMII1RXCTL_GPIOU5':'(0,0,0,0,0,A4,0)';$S;BIDI;
    'RGMII1RXCK_RMII1RCLKI_GPIOU4':'(0,0,0,0,0,B4,0)';$S;BIDI;
    'RGMII2RXD0_RMII2RXD0_GPIOV4':'(0,0,0,0,0,C3,0)';$S;BIDI;
    'RGMII2RXD1_RMII2RXD1_GPIOV5':'(0,0,0,0,0,D1,0)';$S;BIDI;
    'RGMII2RXD2_RMII2CRSDV_GPIOV6':'(0,0,0,0,0,D2,0)';$S;BIDI;
    'RGMII2RXD3_RMII2RXER_GPIOV7':'(0,0,0,0,0,E6,0)';$S;BIDI;
    'RGMII2RXCK_RMII2RCLKI_GPIOV2':'(0,0,0,0,0,C2,0)';$S;BIDI;
    'LPVDD1':'(0,0,0,0,0,0,K17)';$S;
    'LPVDD0':'(0,0,0,0,0,0,J17)';$S;
    'GND68':'(0,0,0,0,0,0,E5)';$S;
    'DACAV33':'(0,0,0,0,0,0,K6)';$S;
    'PV33D0':'(0,0,0,0,0,0,F12)';$S;
    'MVDD4':'(0,0,0,0,0,0,T8)';$S;
    'GPIOY2_SIOPWREQ#':'(0,0,0,0,0,0,P22)';$S;BIDI;
    'GPIOY1_SIOS5#':'(0,0,0,0,0,0,R21)';$S;BIDI;
    'GPIOY0_SIOS3#':'(0,0,0,0,0,0,R22)';$S;BIDI;
    'IV11D0':'(0,0,0,0,0,0,F6)';$S;
    'IV11D1':'(0,0,0,0,0,0,G10)';$S;
    'IV11D2':'(0,0,0,0,0,0,G11)';$S;
    'IV11D3':'(0,0,0,0,0,0,G12)';$S;
    'IV11D4':'(0,0,0,0,0,0,G13)';$S;
    'IV11D5':'(0,0,0,0,0,0,G14)';$S;
    'IV11D6':'(0,0,0,0,0,0,G15)';$S;
    'IV11D7':'(0,0,0,0,0,0,G7)';$S;
    'IV11D8':'(0,0,0,0,0,0,G8)';$S;
    'IV11D9':'(0,0,0,0,0,0,G9)';$S;
    'IV11D10':'(0,0,0,0,0,0,H16)';$S;
    'IV11D11':'(0,0,0,0,0,0,J16)';$S;
    'IV11D12':'(0,0,0,0,0,0,L7)';$S;
    'IV11D13':'(0,0,0,0,0,0,N16)';$S;
    'IV11D14':'(0,0,0,0,0,0,N7)';$S;
    'IV11D15':'(0,0,0,0,0,0,P10)';$S;
    'IV11D16':'(0,0,0,0,0,0,P11)';$S;
    'IV11D17':'(0,0,0,0,0,0,P12)';$S;
    'IV11D18':'(0,0,0,0,0,0,P13)';$S;
    'IV11D19':'(0,0,0,0,0,0,P14)';$S;
    'IV11D20':'(0,0,0,0,0,0,P16)';$S;
    'IV11D21':'(0,0,0,0,0,0,P7)';$S;
    'IV11D22':'(0,0,0,0,0,0,P9)';$S;
    'IV11D23':'(0,0,0,0,0,0,R16)';$S;
    'IV11D24':'(0,0,0,0,0,0,R7)';$S;
    'VPLLAV110':'(0,0,0,0,0,0,L5)';$S;
    'VPLLAV111':'(0,0,0,0,0,0,L6)';$S;
    'PEAV11':'(0,0,0,0,0,0,L17)';$S;
    'PLLDV11':'(0,0,0,0,0,0,V17)';$S;
    'PECIVDD':'(0,0,0,0,0,0,AA17)';$S;
    'MVDD0':'(0,0,0,0,0,0,T10)';$S;
    'MVDD1':'(0,0,0,0,0,0,T12)';$S;
    'MVDD2':'(0,0,0,0,0,0,T13)';$S;
    'MVDD3':'(0,0,0,0,0,0,T14)';$S;
    'PV33D1':'(0,0,0,0,0,0,F13)';$S;
    'PV33D2':'(0,0,0,0,0,0,F14)';$S;
    'PV33D3':'(0,0,0,0,0,0,F15)';$S;
    'PV33D4':'(0,0,0,0,0,0,G16)';$S;
    'PV33D5':'(0,0,0,0,0,0,H17)';$S;
    'PV33D6':'(0,0,0,0,0,0,K7)';$S;
    'PV33D7':'(0,0,0,0,0,0,N17)';$S;
    'PV33D8':'(0,0,0,0,0,0,N6)';$S;
    'PV33D9':'(0,0,0,0,0,0,P17)';$S;
    'PV33D10':'(0,0,0,0,0,0,P6)';$S;
    'PV33D11':'(0,0,0,0,0,0,R17)';$S;
    'PV33D12':'(0,0,0,0,0,0,R6)';$S;
    'PV33D13':'(0,0,0,0,0,0,T11)';$S;
    'PV33D14':'(0,0,0,0,0,0,T15)';$S;
    'PLLAV330':'(0,0,0,0,0,0,Y17)';$S;
    'PLLAV331':'(0,0,0,0,0,0,W17)';$S;
    'VPLLAV330':'(0,0,0,0,0,0,J7)';$S;
    'VPLLAV331':'(0,0,0,0,0,0,H7)';$S;
    'PEAV33':'(0,0,0,0,0,0,L16)';$S;
    'BATVDD':'(0,0,0,0,0,0,E4)';$S;
    'USB2AV33':'(0,0,0,0,0,0,C7)';$S;
    'DACDV33':'(0,0,0,0,0,0,K5)';$S;
    'ADCAV33':'(0,0,0,0,0,0,J6)';$S;
    'R2VDD0':'(0,0,0,0,0,0,F7)';$S;
    'R2VDD1':'(0,0,0,0,0,0,F8)';$S;
    'R1VDD0':'(0,0,0,0,0,0,F10)';$S;
    'R1VDD1':'(0,0,0,0,0,0,F11)';$S;
    'GND67':'(0,0,0,0,0,0,V8)';$S;
    'GND66':'(0,0,0,0,0,0,V16)';$S;
    'GND65':'(0,0,0,0,0,0,V14)';$S;
    'GND60':'(0,0,0,0,0,0,T7)';$S;
    'GND61':'(0,0,0,0,0,0,U11)';$S;
    'GND64':'(0,0,0,0,0,0,V12)';$S;
    'GND63':'(0,0,0,0,0,0,V10)';$S;
    'GND62':'(0,0,0,0,0,0,U6)';$S;
    'GND55':'(0,0,0,0,0,0,N13)';$S;
    'GND56':'(0,0,0,0,0,0,N14)';$S;
    'GND59':'(0,0,0,0,0,0,T6)';$S;
    'GND58':'(0,0,0,0,0,0,T16)';$S;
    'GND57':'(0,0,0,0,0,0,N9)';$S;
    'GND50':'(0,0,0,0,0,0,M7)';$S;
    'GND51':'(0,0,0,0,0,0,M9)';$S;
    'GND54':'(0,0,0,0,0,0,N12)';$S;
    'GND53':'(0,0,0,0,0,0,N11)';$S;
    'GND52':'(0,0,0,0,0,0,N10)';$S;
    'GND45':'(0,0,0,0,0,0,M2)';$S;
    'GND46':'(0,0,0,0,0,0,M3)';$S;
    'GND49':'(0,0,0,0,0,0,M6)';$S;
    'GND48':'(0,0,0,0,0,0,M5)';$S;
    'GND47':'(0,0,0,0,0,0,M4)';$S;
    'GND40':'(0,0,0,0,0,0,M12)';$S;
    'GND41':'(0,0,0,0,0,0,M13)';$S;
    'GND44':'(0,0,0,0,0,0,M17)';$S;
    'GND43':'(0,0,0,0,0,0,M16)';$S;
    'GND42':'(0,0,0,0,0,0,M14)';$S;
    'GND35':'(0,0,0,0,0,0,L14)';$S;
    'GND39':'(0,0,0,0,0,0,M11)';$S;
    'GND38':'(0,0,0,0,0,0,M10)';$S;
    'GND37':'(0,0,0,0,0,0,M1)';$S;
    'GND36':'(0,0,0,0,0,0,L9)';$S;
    'GND30':'(0,0,0,0,0,0,K9)';$S;
    'GND34':'(0,0,0,0,0,0,L13)';$S;
    'GND33':'(0,0,0,0,0,0,L12)';$S;
    'GND32':'(0,0,0,0,0,0,L11)';$S;
    'GND31':'(0,0,0,0,0,0,L10)';$S;
    'GND29':'(0,0,0,0,0,0,K16)';$S;
    'GND25':'(0,0,0,0,0,0,K11)';$S;
    'GND27':'(0,0,0,0,0,0,K13)';$S;
    'GND28':'(0,0,0,0,0,0,K14)';$S;
    'GND26':'(0,0,0,0,0,0,K12)';$S;
    'GND24':'(0,0,0,0,0,0,K10)';$S;
    'GND20':'(0,0,0,0,0,0,J21)';$S;
    'GND23':'(0,0,0,0,0,0,J9)';$S;
    'GND22':'(0,0,0,0,0,0,J5)';$S;
    'GND21':'(0,0,0,0,0,0,J22)';$S;
    'GND19':'(0,0,0,0,0,0,J14)';$S;
    'GND14':'(0,0,0,0,0,0,H6)';$S;
    'GND15':'(0,0,0,0,0,0,J10)';$S;
    'GND18':'(0,0,0,0,0,0,J13)';$S;
    'GND17':'(0,0,0,0,0,0,J12)';$S;
    'GND16':'(0,0,0,0,0,0,J11)';$S;
    'GND9':'(0,0,0,0,0,0,C6)';$S;
    'GND10':'(0,0,0,0,0,0,E8)';$S;
    'GND13':'(0,0,0,0,0,0,G6)';$S;
    'GND12':'(0,0,0,0,0,0,G19)';$S;
    'GND11':'(0,0,0,0,0,0,F16)';$S;
    'GND4':'(0,0,0,0,0,0,AA15)';$S;
    'GND5':'(0,0,0,0,0,0,AA7)';$S;
    'GND7':'(0,0,0,0,0,0,AB1)';$S;
    'GND8':'(0,0,0,0,0,0,AB22)';$S;
    'GND6':'(0,0,0,0,0,0,AA9)';$S;
    'GND3':'(0,0,0,0,0,0,AA13)';$S;
    'GND2':'(0,0,0,0,0,0,AA11)';$S;
    'GND1':'(0,0,0,0,0,0,A22)';$S;
    'GND0':'(0,0,0,0,0,0,A1)';$S;
end_primitive;
primitive 'AT24C64_SOICLF-IC,C47049-001-GA';body 'AT24C64';
    'A0':'(1)';IN;
    'A1':'(2)';IN;
    'A2':'(3)';IN;
    'SCL':'(6)';IN;
    'WP':'(7)';IN;
    'SDA':'(5)';BIDI;
end_primitive;
primitive 'BATTERY_PLCLF-202168-001';body 'BATTERY';
end_primitive;
primitive 'BLM15AG121SN-1GP_DISCRET-G-BLMA';body 'BLM15AG121SN-1GP';
    '1':'(1)';
    '2':'(2)';
end_primitive;
primitive 'BLM31SN500SN1L-GP_DISCRET-GB1-A';body 'BLM31SN500SN1L-GP';
    '1':'(1)';
    '2':'(2)';
end_primitive;
primitive 'BSL308C-H6327-GP_DISCRET-GB1-BA';body 'BSL308C-H6327-GP';
    'GATE#1':'(1)';
    'SOURCE#2':'(2)';
    'DRAIN#6':'(6)';
    'SOURCE#5':'(5)';
    'GATE#3':'(3)';
    'DRAIN#4':'(4)';
end_primitive;
primitive 'CAPP_2626-270UF,16V,20%,OSCON,A';body 'CAPP';
    'A':'(1)';
    'B':'(2)';
end_primitive;
primitive 'CAPP_3018-470UF,2.5V,20%,ALUM,A';body 'CAPP';
    'A':'(1)';
    'B':'(2)';
end_primitive;
primitive 'CAPP_3018-68UF,16V,20%,TANT,72A';body 'CAPP';
    'A':'(1)';
    'B':'(2)';
end_primitive;
primitive 'CAPP_4040LF-470UF,16V,20%,ALUMA';body 'CAPP';
    'A':'(1)';
    'B':'(2)';
end_primitive;
primitive 'CAPP_7343-220UF,4V,20%,POSCAP,A';body 'CAPP';
    'A':'(1)';
    'B':'(2)';
end_primitive;
primitive 'CAPP_7343HLF-330UF,10V,20%,POSA';body 'CAPP';
    'A':'(1)';
    'B':'(2)';
end_primitive;
primitive 'CAPP_7343LF-330UF,6.3V,20%,POSA';body 'CAPP';
    'A':'(1)';
    'B':'(2)';
end_primitive;
primitive 'CAPP_SM-470UF,2V,20%,ALUM,6990A';body 'CAPP';
    'A':'(1)';
    'B':'(2)';
end_primitive;
primitive 'CAP_0402-0.027UF,16V,10%,X7R,AA';body 'CAP';
    'A':'(1)';
    'B':'(2)';
end_primitive;
primitive 'CAP_0402-0.047UF,25V,10%,X7R,AA';body 'CAP';
    'A':'(1)';
    'B':'(2)';
end_primitive;
primitive 'CAP_0402-0.220UF,16V,10%,X7R,AA';body 'CAP';
    'A':'(1)';
    'B':'(2)';
end_primitive;
primitive 'CAP_0402-0.22UF,16V,10%,X7R,A3A';body 'CAP';
    'A':'(1)';
    'B':'(2)';
end_primitive;
primitive 'CAP_0402-1.0UF,16V,10%,X6S,D97A';body 'CAP';
    'A':'(1)';
    'B':'(2)';
end_primitive;
primitive 'CAP_0402-1.0UF,16V,10%,X7S,G71A';body 'CAP';
    'A':'(1)';
    'B':'(2)';
end_primitive;
primitive 'CAP_0402-1.0UF,6.3V,10%,EMPTY,A';body 'CAP';
    'A':'(1)';
    'B':'(2)';
end_primitive;
primitive 'CAP_0402LF-0.022UF,16V,10%,X7RA';body 'CAP';
    'A':'(1)';
    'B':'(2)';
end_primitive;
primitive 'CAP_0402LF-0.039UF,25V,10%,X7RA';body 'CAP';
    'A':'(1)';
    'B':'(2)';
end_primitive;
primitive 'CAP_0402LF-10.0PF,50V,5%,COG,AA';body 'CAP';
    'A':'(1)';
    'B':'(2)';
end_primitive;
primitive 'CAP_0402LF-100.0PF,50V,5%,COG,A';body 'CAP';
    'A':'(1)';
    'B':'(2)';
end_primitive;
primitive 'CAP_0402LF-1000PF,50V,10%,EMPTA';body 'CAP';
    'A':'(1)';
    'B':'(2)';
end_primitive;
primitive 'CAP_0402LF-1000PF,50V,10%,X7R,A';body 'CAP';
    'A':'(1)';
    'B':'(2)';
end_primitive;
primitive 'CAP_0402LF-12.0PF,50V,5%,COG,AA';body 'CAP';
    'A':'(1)';
    'B':'(2)';
end_primitive;
primitive 'CAP_0402LF-15.0PF,50V,5%,COG,AA';body 'CAP';
    'A':'(1)';
    'B':'(2)';
end_primitive;
primitive 'CAP_0402LF-2200PF,50V,10%,X7R,A';body 'CAP';
    'A':'(1)';
    'B':'(2)';
end_primitive;
primitive 'CAP_0402LF-220PF,50V,10%,X7R,AA';body 'CAP';
    'A':'(1)';
    'B':'(2)';
end_primitive;
primitive 'CAP_0402LF-270PF,50V,10%,X7R,AA';body 'CAP';
    'A':'(1)';
    'B':'(2)';
end_primitive;
primitive 'CAP_0402LF-33.0PF,50V,5%,COG,AA';body 'CAP';
    'A':'(1)';
    'B':'(2)';
end_primitive;
primitive 'CAP_0402LF-3300PF,50V,10%,EMPTA';body 'CAP';
    'A':'(1)';
    'B':'(2)';
end_primitive;
primitive 'CAP_0402LF-47.0PF,50V,5%,COG,AA';body 'CAP';
    'A':'(1)';
    'B':'(2)';
end_primitive;
primitive 'CAP_0402LF-47.0PF,50V,5%,EMPTYA';body 'CAP';
    'A':'(1)';
    'B':'(2)';
end_primitive;
primitive 'CAP_0402LF-4700PF,50V,10%,EMPTA';body 'CAP';
    'A':'(1)';
    'B':'(2)';
end_primitive;
primitive 'CAP_0402LF-470PF,50V,10%,EMPTYA';body 'CAP';
    'A':'(1)';
    'B':'(2)';
end_primitive;
primitive 'CAP_0402LF-470PF,50V,10%,X7R,AA';body 'CAP';
    'A':'(1)';
    'B':'(2)';
end_primitive;
primitive 'CAP_0603-10UF,6.3V,20%,X6S,E15A';body 'CAP';
    'A':'(1)';
    'B':'(2)';
end_primitive;
primitive 'CAP_0603-4.7UF,6.3V,10%,X6S,E1A';body 'CAP';
    'A':'(1)';
    'B':'(2)';
end_primitive;
primitive 'CAP_0603LF-0.033UF,50V,10%,X7RA';body 'CAP';
    'A':'(1)';
    'B':'(2)';
end_primitive;
primitive 'CAP_0603LF-0.1UF,25V,10%,X7R,6A';body 'CAP';
    'A':'(1)';
    'B':'(2)';
end_primitive;
primitive 'CAP_0603LF-10UF,4V,20%,X6S,E15A';body 'CAP';
    'A':'(1)';
    'B':'(2)';
end_primitive;
primitive 'CAP_0805-100UF,4V,20%,X5R,6024A';body 'CAP';
    'A':'(1)';
    'B':'(2)';
end_primitive;
primitive 'CAP_0805-10UF,16V,10%,EMPTY,C9A';body 'CAP';
    'A':'(1)';
    'B':'(2)';
end_primitive;
primitive 'CAP_0805-10UF,16V,10%,X6S,C953A';body 'CAP';
    'A':'(1)';
    'B':'(2)';
end_primitive;
primitive 'CAP_0805-10UF,16V,10%,X7R,G106A';body 'CAP';
    'A':'(1)';
    'B':'(2)';
end_primitive;
primitive 'CAP_0805-22UF,6.3V,20%,X6S,C95A';body 'CAP';
    'A':'(1)';
    'B':'(2)';
end_primitive;
primitive 'CAP_0805-47UF,4V,20%,X6S,C9533A';body 'CAP';
    'A':'(1)';
    'B':'(2)';
end_primitive;
primitive 'CAP_0805LF-22UF,4V,20%,X6S,C95A';body 'CAP';
    'A':'(1)';
    'B':'(2)';
end_primitive;
primitive 'CAP_1206-0.068UF,50V,20%,X7R,1A';body 'CAP';
    'A':'(1)';
    'B':'(2)';
end_primitive;
primitive 'CAP_1206LF-22UF,16V,10%,X6S,D3A';body 'CAP';
    'A':'(1)';
    'B':'(2)';
end_primitive;
primitive 'CAP_A_0402V-0.01UF,25V,10%,X7RA';body 'CAP_A';
    'A':'(1)';
    'B':'(2)';
end_primitive;
primitive 'CAP_A_0402V-0.1UF,16V,10%,EMPTA';body 'CAP_A';
    'A':'(1)';
    'B':'(2)';
end_primitive;
primitive 'CAP_A_0402V-0.1UF,16V,10%,X7R,A';body 'CAP_A';
    'A':'(1)';
    'B':'(2)';
end_primitive;
primitive 'CAP_A_0402V-1.0UF,6.3V,10%,X6SA';body 'CAP_A';
    'A':'(1)';
    'B':'(2)';
end_primitive;
primitive 'CAP_A_0603V-22.0UF,4V,20%,EMPTA';body 'CAP_A';
    'A':'(1)';
    'B':'(2)';
end_primitive;
primitive 'CAP_A_0603V-22.0UF,4V,20%,X6S,A';body 'CAP_A';
    'A':'(1)';
    'B':'(2)';
end_primitive;
primitive 'CAP_A_0603V-47UF,4V,20%,X5R,60A';body 'CAP_A';
    'A':'(1)';
    'B':'(2)';
end_primitive;
primitive 'CHOKE_4PIN_SMLF-90 OHM,IND,752A';body 'CHOKE_4PIN';
    'A1':'(1)';
    'A2':'(2)';
    'B1':'(3)';
    'B2':'(4)';
end_primitive;
primitive 'CHOKE_4PIN_SM_B-67 OHM,EMPTY,7A';body 'CHOKE_4PIN';
    '1':'(1)';
    '2':'(2)';
    '3':'(3)';
    '4':'(4)';
end_primitive;
primitive 'CLX-CONN3A-1-GP_CONN-G3-CLX-COA';body 'CLX-CONN3A-1-GP';
    '1':'(1)';
    '2':'(2)';
    '3':'(3)';
end_primitive;
primitive 'CONN12_C73564003_PIP-CONN,C735A';body 'CONN12_C73564003';
    'IO1':'(1)';BIDI;
    'IO10':'(10)';BIDI;
    'IO11':'(11)';BIDI;
    'IO12':'(12)';BIDI;
    'IO2':'(2)';BIDI;
    'IO3':'(3)';BIDI;
    'IO4':'(4)';BIDI;
    'IO5':'(5)';BIDI;
    'IO6':'(6)';BIDI;
    'IO7':'(7)';BIDI;
    'IO8':'(8)';BIDI;
    'IO9':'(9)';BIDI;
end_primitive;
primitive 'CONN14_H54902001_PIP-CONN,H549A';body 'CONN14_H54902001';
    'IO1':'(1)';BIDI;
    'IO10':'(10)';BIDI;
    'IO11':'(11)';BIDI;
    'IO12':'(12)';BIDI;
    'IO13':'(13)';BIDI;
    'IO14':'(14)';BIDI;
    'IO2':'(2)';BIDI;
    'IO3':'(3)';BIDI;
    'IO4':'(4)';BIDI;
    'IO5':'(5)';BIDI;
    'IO6':'(6)';BIDI;
    'IO7':'(7)';BIDI;
    'IO8':'(8)';BIDI;
    'IO9':'(9)';BIDI;
end_primitive;
primitive 'CONN3_C95678002_PIP-CONN,C9567A';body 'CONN3_C95678002';
    'IO1':'(1)';
    'IO2':'(2)';
    'IO3':'(3)';
end_primitive;
primitive 'CONN3_G98259001_PIP-CONN,G9825A';body 'CONN3_G98259001';
    'IO1':'(1)';BIDI;
    'IO2':'(2)';BIDI;
    'IO3':'(3)';BIDI;
end_primitive;
primitive 'CONN4_D42317002_PIP-CONN,D4231A';body 'CONN4_D42317002';
    'IO1':'(1)';BIDI;
    'IO2':'(2)';BIDI;
    'IO3':'(3)';BIDI;
    'IO4':'(4)';BIDI;
end_primitive;
primitive 'CONN6_C74770005_PIP-HDR,C74770A';body 'CONN6_C74770005';
    'IO1':'(1)';
    'IO2':'(2)';
    'IO3':'(3)';
    'IO4':'(4)';
    'IO5':'(5)';
    'IO6':'(6)';
end_primitive;
primitive 'CONN72_G97614002_A_CP-CONN,G97A';body 'CONN72_G97614002_A';
    'GND'<23>:'(1A3)';
    'GND'<22>:'(1A6)';
    'GND'<21>:'(1A9)';
    'GND'<20>:'(1B3)';
    'GND'<19>:'(1B6)';
    'GND'<18>:'(1B9)';
    'GND'<17>:'(1C3)';
    'GND'<16>:'(1C6)';
    'GND'<15>:'(1C9)';
    'GND'<14>:'(1D3)';
    'GND'<13>:'(1D6)';BIDI;
    'GND'<12>:'(1D9)';
    'GND'<11>:'(2A3)';
    'GND'<10>:'(2A6)';
    'GND'<9>:'(2A9)';
    'GND'<8>:'(2B3)';
    'GND'<7>:'(2B6)';
    'GND'<6>:'(2B9)';
    'GND'<5>:'(2C3)';
    'GND'<4>:'(2C6)';
    'GND'<3>:'(2C9)';
    'GND'<2>:'(2D3)';
    'GND'<1>:'(2D6)';BIDI;
    'GND'<0>:'(2D9)';
    'RXA0_DN':'(1B5)';BIDI;
    'RXA0_DP':'(1B4)';BIDI;
    'RXA1_DN':'(1A5)';BIDI;
    'RXA1_DP':'(1A4)';BIDI;
    'RXA2_DN':'(1B8)';BIDI;
    'RXA2_DP':'(1B7)';BIDI;
    'RXA3_DN':'(1A8)';BIDI;
    'RXA3_DP':'(1A7)';BIDI;
    'RXB0_DN':'(2B5)';BIDI;
    'RXB0_DP':'(2B4)';BIDI;
    'RXB1_DN':'(2A5)';BIDI;
    'RXB1_DP':'(2A4)';BIDI;
    'RXB2_DN':'(2B8)';BIDI;
    'RXB2_DP':'(2B7)';BIDI;
    'RXB3_DN':'(2A8)';BIDI;
    'RXB3_DP':'(2A7)';BIDI;
    'SIDEBANDA_0':'(1A2)';BIDI;
    'SIDEBANDA_1':'(1B2)';BIDI;
    'SIDEBANDA_2':'(1C2)';BIDI;
    'SIDEBANDA_3':'(1B1)';BIDI;
    'SIDEBANDA_4':'(1C1)';BIDI;
    'SIDEBANDA_5':'(1D1)';BIDI;
    'SIDEBANDA_6':'(1D2)';BIDI;
    'SIDEBANDA_7':'(1A1)';BIDI;
    'SIDEBANDB_0':'(2A2)';BIDI;
    'SIDEBANDB_1':'(2B2)';BIDI;
    'SIDEBANDB_2':'(2C2)';BIDI;
    'SIDEBANDB_3':'(2B1)';BIDI;
    'SIDEBANDB_4':'(2C1)';BIDI;
    'SIDEBANDB_5':'(2D1)';BIDI;
    'SIDEBANDB_6':'(2D2)';BIDI;
    'SIDEBANDB_7':'(2A1)';BIDI;
    'TXA0_DN':'(1D5)';BIDI;
    'TXA0_DP':'(1D4)';BIDI;
    'TXA1_DN':'(1C5)';BIDI;
    'TXA1_DP':'(1C4)';BIDI;
    'TXA2_DN':'(1D8)';BIDI;
    'TXA2_DP':'(1D7)';BIDI;
    'TXA3_DN':'(1C8)';BIDI;
    'TXA3_DP':'(1C7)';BIDI;
    'TXB0_DN':'(2D5)';BIDI;
    'TXB0_DP':'(2D4)';BIDI;
    'TXB1_DN':'(2C5)';BIDI;
    'TXB1_DP':'(2C4)';BIDI;
    'TXB2_DN':'(2D8)';BIDI;
    'TXB2_DP':'(2D7)';BIDI;
    'TXB3_DN':'(2C8)';BIDI;
    'TXB3_DP':'(2C7)';BIDI;
end_primitive;
primitive 'CONN8_C77962004_PIP-CONN,C7796A';body 'CONN8_C77962004';
    'IO1':'(1)';BIDI;
    'IO2':'(2)';BIDI;
    'IO3':'(3)';BIDI;
    'IO4':'(4)';BIDI;
    'IO5':'(5)';BIDI;
    'IO6':'(6)';BIDI;
    'IO7':'(7)';BIDI;
    'IO8':'(8)';BIDI;
end_primitive;
primitive 'CONN8_H62179001_PIP-CONN,H6217A';body 'CONN8_H62179001';
    'IO1':'(1)';BIDI;
    'IO2':'(2)';BIDI;
    'IO3':'(3)';BIDI;
    'IO4':'(4)';BIDI;
    'IO5':'(5)';BIDI;
    'IO6':'(6)';BIDI;
    'IO7':'(7)';BIDI;
    'IO8':'(8)';BIDI;
end_primitive;
primitive 'CONN9_H51826001_PIP2-CONN,H518A';body 'CONN9_H51826001';
    'DN':'(2)';BIDI;
    'DP':'(3)';BIDI;
    'GND':'(4)';
    'GND_DRAIN':'(7)';
    'MH1':'(MH1)';
    'MH2':'(MH2)';
    'MH3':'(MH3)';
    'MH4':'(MH4)';
    'STDA_SSRXN':'(5)';BIDI;
    'STDA_SSRXP':'(6)';BIDI;
    'STDA_SSTXN':'(8)';BIDI;
    'STDA_SSTXP':'(9)';BIDI;
    'VBUS':'(1)';BIDI;
end_primitive;
primitive 'CRYSTAL_2013-25.000MHZ,IC,D717A';body 'CRYSTAL';
    'A':'(1)';
    'B':'(3)';
end_primitive;
primitive 'CRYSTAL_2013-25.000MHZ,IC,H196A';body 'CRYSTAL';
    'A':'(1)';
    'B':'(3)';
end_primitive;
primitive 'CRYSTAL_2013-48.000MHZ,IC,D717A';body 'CRYSTAL';
    'A':'(1)';
    'B':'(3)';
end_primitive;
primitive 'CRYSTAL_2013LF-25.000MHZ,IC,D7B';body 'CRYSTAL';
    'A':'(1)';
    'B':'(3)';
end_primitive;
primitive 'CRYSTAL_SM-32.768KHZ,IC,C13544A';body 'CRYSTAL';
    'A':'(1)';
    'B':'(2)';
end_primitive;
primitive 'CSD87384M_SM-IC,H66258-001';body 'CSD87384M';
    'BG':'(4)';IN;
    'PGND':'(3)';
    'TG':'(1)';IN;
    'VIN':'(2)';IN;
    'VSW':'(5)';OUT;
end_primitive;
primitive 'DIODE2A_DUAL_SMLF-BAS70-05,DIOA';body 'DIODE2A_DUAL';
    'C':'(3)';
    'A1':'(1)';
    'A2':'(2)';
end_primitive;
primitive 'DIODEAC_DUAL_ARRAY_SM9-ESD3V3UA';body 'DIODEAC_DUAL_ARRAY';
    'AC0':'(1)';BIDI;
    'AC1':'(2)';BIDI;
    'AC2':'(4)';BIDI;
    'AC3':'(5)';BIDI;
    'GND'<0>:'(3)';
    'OUT0':'(9)';OUT;
    'OUT1':'(8)';OUT;
    'OUT2':'(7)';OUT;
    'OUT3':'(6)';OUT;
end_primitive;
primitive 'DIODE_SM-1N4148W,IC,D89194-001';body 'DIODE';
    'C':'(1)';
    'A':'(2)';
end_primitive;
primitive 'DIODE_SM-MBRS340T3G,EMPTY,C819A';body 'DIODE';
    'C':'(1)';
    'A':'(2)';
end_primitive;
primitive 'DIODE_SM-SDMK0340L,EMPTY,H7179A';body 'DIODE';
    'C':'(1)';
    'A':'(2)';
end_primitive;
primitive 'DIODE_SM-SDMK0340L,IC,H71799-0A';body 'DIODE';
    'C':'(1)';
    'A':'(2)';
end_primitive;
primitive 'DIODE_SMLF-1N5819HW,IC,D55839-A';body 'DIODE';
    'C':'(1)';
    'A':'(2)';
end_primitive;
primitive 'DIODE_SMLF-BAT54WS,IC,C73510-0A';body 'DIODE';
    'C':'(1)';
    'A':'(2)';
end_primitive;
primitive 'DM-FCI-CONN76-8R-GP-U-01_CONN-A';body 'DM-FCI-CONN76-8R-GP-U-01';
    'PCIE_RX_DP0':'(A1)';
    'GND1':'(A2)';
    'PCIE_RX_DP6':'(A3)';
    'FAN_TACH3':'(A4)';
    'MNG_TX_DP':'(A5)';
    'PMBUS_ALERT#':'(A6)';
    'PCIE_TX_DP3':'(A7)';
    'GND2':'(A8)';
    'PCIE_RX_DN0':'(B1)';
    'PCIE_RX_DP3':'(B2)';
    'PCIE_RX_DN6':'(B3)';
    'FAN_TACH2':'(B4)';
    'MNG_TX_DN':'(B5)';
    'PMBUS_DATA':'(B6)';
    'PCIE_TX_DN3':'(B7)';
    'PCIE_TX_DP0':'(B8)';
    'GND3':'(C1)';
    'PCIE_RX_DN3':'(C2)';
    'GND4':'(C3)';
    'FAN_TACH1':'(C4)';
    'GND5':'(C5)';
    'PMBUS_CLK':'(C6)';
    'GND6':'(C7)';
    'PCIE_TX_DN0':'(C8)';
    'PCIE_RX_DP1':'(D1)';
    'GND7':'(D2)';
    'PCIE_RX_DP7':'(D3)';
    'FAN_TACH0':'(D4)';
    'MNG_RX_DP':'(D5)';
    'GND8':'(D6)';
    'PCIE_TX_DP4':'(D7)';
    'GND9':'(D8)';
    'PCIE_RX_DN1':'(E1)';
    'PCIE_RX_DP4':'(E2)';
    'PCIE_RX_DN7':'(E3)';
    'MATED_IN#':'(E4)';
    'MNG_RX_DN':'(E5)';
    'PCIE_TX_DP6':'(E6)';
    'PCIE_TX_DN4':'(E7)';
    'PCIE_TX_DP1':'(E8)';
    'GND10':'(F1)';
    'PCIE_RX_DN4':'(F2)';
    'GND11':'(F3)';
    'FAN_PWM0':'(F4)';
    'MB_SLOT_ID0':'(F5)';
    'PCIE_TX_DN6':'(F6)';
    'GND12':'(F7)';
    'PCIE_TX_DN1':'(F8)';
    'PCIE_RX_DP2':'(G1)';
    'GND13':'(G2)';
    'COM_TX':'(G3)';
    'GND14':'(G4)';
    'MB_SLOT_ID1':'(G5)';
    'GND15':'(G6)';
    'PCIE_TX_DP5':'(G7)';
    'GND16':'(G8)';
    'PCIE_RX_DN2':'(H1)';
    'PCIE_RX_DP5':'(H2)';
    'COM_RX':'(H3)';
    'PCIE_CLK_100M_DP':'(H4)';
    'MB_SLOT_ID2':'(H5)';
    'PCIE_TX_DP7':'(H6)';
    'PCIE_TX_DN5':'(H7)';
    'PCIE_TX_DP2':'(H8)';
    'GND17':'(I1)';
    'PCIE_RX_DN5':'(I2)';
    'MB_ON#':'(I3)';
    'PCIE_CLK_100M_DN':'(I4)';
    'PCIE_PERST#':'(I5)';
    'PCIE_TX_DN7':'(I6)';
    'GND18':'(I7)';
    'PCIE_TX_DN2':'(I8)';
    'J2':'(J2)';
    'J4':'(J4)';
    'J6':'(J6)';
    'J8':'(J8)';
end_primitive;
primitive 'FCI-CONN12-2R-GP_CONN-G5-FCI-CA';body 'FCI-CONN12-2R-GP';
    '2_1':'(2_1)';
    '2_2':'(2_2)';
    '2_3':'(2_3)';
    '3_1':'(3_1)';
    '3_2':'(3_2)';
    '3_3':'(3_3)';
    'NP1':'(NP1)';
    '1_1':'(1_1)';
    '1_2':'(1_2)';
    '1_3':'(1_3)';
    '4_1':'(4_1)';
    '4_2':'(4_2)';
    '4_3':'(4_3)';
end_primitive;
primitive 'FERRITE_SM-120,FB,693286-027';body 'FERRITE';
    'A':'(1)';
    'B':'(2)';
end_primitive;
primitive 'FERRITE_SM-22,FB,656554-051';body 'FERRITE';
    'A':'(1)';
    'B':'(2)';
end_primitive;
primitive 'FERRITE_SMLF-30,FB,693286-021';body 'FERRITE';
    'A':'(1)';
    'B':'(2)';
end_primitive;
primitive 'FERRITE_SMLF-600,FB,656554-043';body 'FERRITE';
    'A':'(1)';
    'B':'(2)';
end_primitive;
primitive 'FET_N_DUAL_SMLF-2N7002DW,FET,DA';body 'FET_N_DUAL';
    'GATE'<0>:'(2,5)';$S;
    'SOURCE'<0>:'(1,4)';$S;
    'DRAIN'<0>:'(6,3)';$S;
end_primitive;
primitive 'FET_N_DUAL_SMLF-NTJD4001N,FET,A';body 'FET_N_DUAL';
    'GATE'<0>:'(2,5)';$S;
    'SOURCE'<0>:'(1,4)';$S;
    'DRAIN'<0>:'(6,3)';$S;
end_primitive;
primitive 'FET_N_SOT23LF-2N7002,FET,C7925A';body 'FET_N';
    'GATE':'(1)';
    'SRC':'(2)';
    'DRN':'(3)';
end_primitive;
primitive 'FSA3357_SM-IC,C63273-001';body 'FSA3357';
    'A':'(7)';BIDI;
    'B0':'(1)';BIDI;
    'B1':'(2)';BIDI;
    'B2':'(3)';BIDI;
    'GND':'(4)';
    'S1':'(6)';IN;
    'S2':'(5)';IN;
    'VCC':'(8)';
end_primitive;
primitive 'FUSE-3A75V-GP_DISCRET-G5-FUSE-A';body 'FUSE-3A75V-GP';
    '1':'(1)';
    '2':'(2)';
end_primitive;
primitive 'FUSE_SM-IC,C94311-016';body 'FUSE';
    'A'<0>:'(1)';
    'B'<0>:'(2)';
end_primitive;
primitive 'FUSE_SMT-IC,H45581-001';body 'FUSE';
    'A'<0>:'(1)';
    'B'<0>:'(2)';
end_primitive;
primitive 'GTL2014_SM-IC,D66151-001';body 'GTL2014';
    'A0':'(13)';BIDI;
    'A1':'(12)';BIDI;
    'A2':'(10)';BIDI;
    'A3':'(9)';BIDI;
    'B0':'(2)';BIDI;
    'B1':'(3)';BIDI;
    'B2':'(5)';BIDI;
    'B3':'(6)';BIDI;
    'DIR':'(1)';IN;
    'GND'<2>:'(11)';
    'GND'<1>:'(8)';
    'GND'<0>:'(7)';
    'VCC':'(14)';
    'VREF':'(4)';
end_primitive;
primitive 'H5AN4G6NAFR-TFC-GP_MEMORY-G2-HA';body 'H5AN4G6NAFR-TFC-GP';
    'VPP'<0>:'(B1)';
    'VDD'<0>:'(B3)';
    'VDD'<1>:'(B9)';
    'VDD'<2>:'(D1)';
    'VDD'<3>:'(G7)';
    'VDD'<4>:'(J1)';
    'VDD'<5>:'(J9)';
    'VDD'<6>:'(L1)';
    'VDD'<7>:'(L9)';
    'VDD'<8>:'(R1)';
    'VDD'<9>:'(T9)';
    'VDDQ'<0>:'(A1)';
    'VDDQ'<1>:'(A9)';
    'VDDQ'<2>:'(C1)';
    'VDDQ'<3>:'(D9)';
    'VDDQ'<4>:'(F2)';
    'VDDQ'<5>:'(F8)';
    'VDDQ'<6>:'(G1)';
    'VDDQ'<7>:'(G9)';
    'VDDQ'<8>:'(J2)';
    'VDDQ'<9>:'(J8)';
    'DQU4':'(C2)';
    'DQU5':'(C8)';
    'DQU6':'(D3)';
    'DQU7':'(D7)';
    'DQU0':'(A3)';
    'DQU1':'(B8)';
    'DQU2':'(C3)';
    'DQU3':'(C7)';
    'DQL1':'(F7)';
    'DQL0':'(G2)';
    'DQL4':'(H2)';
    'DQL2':'(H3)';
    'DQL3':'(H7)';
    'DQL5':'(H8)';
    'DQL6':'(J3)';
    'DQL7':'(J7)';
    'A0':'(P3)';IN;
    'A1':'(P7)';IN;
    'A2':'(R3)';IN;
    'A3':'(N7)';IN;
    'A4':'(N3)';IN;
    'A5':'(P8)';IN;
    'A6':'(P2)';IN;
    'A7':'(R8)';IN;
    'A8':'(R2)';IN;
    'A9':'(R7)';IN;
    'A10/AP':'(M3)';IN;
    'A11':'(T2)';IN;
    'A12/BC#':'(M7)';IN;
    'A13':'(T8)';IN;
    'WE#/A14':'(L2)';IN;
    'CAS#/A15':'(M8)';IN;
    'RAS#/A16':'(L8)';IN;
    'VREFCA':'(M1)';
    'ZQ':'(F9)';
    'CKE':'(K2)';IN;
    'ODT':'(K3)';IN;
    'BG0':'(M2)';IN;
    'TEN':'(N9)';IN;
    'PAR':'(T3)';IN;
    'NC#T7':'(T7)';
    'CK_T':'(K7)';IN;
    'CK_C':'(K8)';IN;
    'VPP'<1>:'(R9)';
    'ACT#':'(L3)';IN;
    'CS#':'(L7)';IN;
    'RESET#':'(P1)';IN;
    'ALERT#':'(P9)';OUT;
    'VSS'<0>:'(B2)';
    'VSS'<1>:'(E1)';
    'VSS'<2>:'(E9)';
    'VSS'<3>:'(G8)';
    'VSS'<4>:'(K1)';
    'VSS'<5>:'(K9)';
    'VSS'<6>:'(M9)';
    'VSS'<7>:'(N1)';
    'VSS'<8>:'(T1)';
    'VSSQ'<0>:'(A2)';
    'VSSQ'<1>:'(A8)';
    'VSSQ'<2>:'(C9)';
    'VSSQ'<3>:'(D2)';
    'VSSQ'<4>:'(D8)';
    'VSSQ'<5>:'(E3)';
    'VSSQ'<6>:'(E8)';
    'VSSQ'<7>:'(F1)';
    'VSSQ'<8>:'(H1)';
    'VSSQ'<9>:'(H9)';
    'DQSU_C':'(A7)';BIDI;
    'DQSU_T':'(B7)';BIDI;
    'DQSL_C':'(F3)';BIDI;
    'DQSL_T':'(G3)';BIDI;
    'DMU#/DBIU#':'(E2)';BIDI;
    'DML#/DBIL#':'(E7)';BIDI;
    'BA0':'(N2)';IN;
    'BA1':'(N8)';IN;
end_primitive;
primitive 'HCB1608KF-800T30-GP_DISCRET-G9A';body 'HCB1608KF-800T30-GP';
    '1':'(1)';
    '2':'(2)';
end_primitive;
primitive 'ICS9FGP204_MLFP-IC,E95226-001';body 'ICS9FGP204';
    'VDD32K':'(12)';
    '32KHZ':'(13)';OUT;
    'GND32K':'(14)';
    '25MHZ_0':'(16)';OUT;
    '25MHZ_1':'(17)';OUT;
    'RMII'<1>:'(32)';OUT;
    'RMII'<2>:'(29)';OUT;
    'RMII'<5>:'(24)';OUT;
    'RMII'<4>:'(25)';OUT;
    'RMII'<3>:'(28)';OUT;
    'RMII'<0>:'(33)';OUT;
    'GND'<1>:'(41)';
    'GND33':'(21)';
    'GND'<0>:'(1)';
    'DOT96SSC':'(4)';OUT;
    'DOT96SST':'(3)';OUT;
    'CPUCLKC0':'(8)';OUT;
    'GNDREF':'(18)';
    'CPUCLKT0':'(7)';OUT;
    'VDDREF':'(15)';
    'IREF':'(11)';OUT;
    'X1_25':'(19)';IN;
    'GNDRMII'<0>:'(27)';
    'VDDRMII'<0>:'(26)';
    'VDDRMII'<1>:'(31)';
    'GNDRMII'<1>:'(30)';
    '33MHZ_SMBADR':'(22)';BIDI;
    'VDD33':'(23)';
    'OE_96':'(5)';IN;
    'VDD96':'(2)';
    'OE_CPU':'(6)';IN;
    'GNDCPU':'(10)';
    'VDDCPU':'(9)';
    'VTTPWR_GD_PD_N':'(40)';IN;
    'SMBCLK':'(38)';IN;
    'X2_25':'(20)';OUT;
    'SMBDAT':'(39)';BIDI;
    'VDD_RGMII':'(34)';IN;
    'GND_RGMII':'(35)';
    'RGMII'<0>:'(37)';OUT;
    'RGMII'<1>:'(36)';OUT;
end_primitive;
primitive 'IND-100NH-35-GP_DISCRET-G8-INDA';body 'IND-100NH-35-GP';
    'S':'(1)';
    'F':'(2)';
end_primitive;
primitive 'IND-120NH-30-GP_DISCRET-GB2-INA';body 'IND-120NH-30-GP';
    'S':'(1)';
    'F':'(2)';
end_primitive;
primitive 'IND-150NH-56-GP_DISCRET-GA1-INA';body 'IND-150NH-56-GP';
    'S':'(1)';
    'F':'(2)';
end_primitive;
primitive 'IND-1UH-361-GP_DISCRET-GC1-INDA';body 'IND-1UH-361-GP';
    '1':'(1)';
    '2':'(2)';
end_primitive;
primitive 'IND-300NH-20-GP_DISCRET-GB1-INA';body 'IND-300NH-20-GP';
    'S':'(1)';
    'F':'(2)';
end_primitive;
primitive 'IND-68NH-15-GP_DISCRET-GC1-INDA';body 'IND-68NH-15-GP';
    '1':'(1)';
    '2':'(2)';
end_primitive;
primitive 'IND-80NH-1-GP_DISCRET-GC2-IND-A';body 'IND-80NH-1-GP';
    'S':'(1)';
    'F':'(2)';
end_primitive;
primitive 'INDUCTOR_SM-0.47UH,IND,E13358-A';body 'INDUCTOR';
    'INA':'(1)';
    'INB':'(2)';
end_primitive;
primitive 'INDUCTOR_SM-2.2UH,IND,E98761-0A';body 'INDUCTOR';
    'INA':'(1)';
    'INB':'(2)';
end_primitive;
primitive 'INDUCTOR_SMT-0.022UH,IND,72189A';body 'INDUCTOR';
    'INA':'(1)';
    'INB':'(2)';
end_primitive;
primitive 'IR354XX_SM-IR35411,IC,H73688-0A';body 'IR354XX';
    'BOOST':'(33)';BIDI;
    'EN':'(35)';BIDI;
    'GL'<1>:'(41)';BIDI;
    'GL'<0>:'(6)';BIDI;
    'IOUT':'(38)';OUT;
    'LGND':'(2)';
    'NC':'(31)';
    'OCSET':'(37)';BIDI;
    'PGND'<2>:'(40)';
    'PGND'<1>:'(7)';
    'PGND'<0>:'(5)';
    'PHASE':'(32)';BIDI;
    'PWM':'(34)';IN;
    'REFIN':'(39)';IN;
    'SW':'(10)';BIDI;
    'TOUT_FLT':'(36)';BIDI;
    'VCC':'(3)';
    'VDRV':'(4)';BIDI;
    'VIN'<1>:'(30)';
    'VIN'<0>:'(25)';
    'VOS':'(1)';BIDI;
end_primitive;
primitive 'IR354XX_SM-IR35412,IC,H73684-0A';body 'IR354XX';
    'BOOST':'(33)';BIDI;
    'EN':'(35)';BIDI;
    'GL'<1>:'(41)';BIDI;
    'GL'<0>:'(6)';BIDI;
    'IOUT':'(38)';OUT;
    'LGND':'(2)';
    'NC':'(31)';
    'OCSET':'(37)';BIDI;
    'PGND'<2>:'(40)';
    'PGND'<1>:'(7)';
    'PGND'<0>:'(5)';
    'PHASE':'(32)';BIDI;
    'PWM':'(34)';IN;
    'REFIN':'(39)';IN;
    'SW':'(10)';BIDI;
    'TOUT_FLT':'(36)';BIDI;
    'VCC':'(3)';
    'VDRV':'(4)';BIDI;
    'VIN'<1>:'(30)';
    'VIN'<0>:'(25)';
    'VOS':'(1)';BIDI;
end_primitive;
primitive 'LBG_CORE_QAT_EXT_D_BGA1-IC,H91A';body 'LBG_CORE_QAT_EXT_D';
    'CGC_DUT_DETECT_N':'(0,0,0,0,0,0,0,C70,0,0,0,0,0,0)';$S;BIDI;
    'CLKOUT_ITPXDPN':'(A39,0,0,0,0,0,0,0,0,0,0,0,0,0)';$S;BIDI;
    'CLKOUT_ITPXDPP':'(C39,0,0,0,0,0,0,0,0,0,0,0,0,0)';$S;BIDI;
    'CLKOUT_NSSCCAP0N':'(A32,0,0,0,0,0,0,0,0,0,0,0,0,0)';$S;BIDI;
    'CLKOUT_NSSCCAP0P':'(C32,0,0,0,0,0,0,0,0,0,0,0,0,0)';$S;BIDI;
    'CLKOUT_NSSCCAP1N':'(B38,0,0,0,0,0,0,0,0,0,0,0,0,0)';$S;BIDI;
    'CLKOUT_NSSCCAP1P':'(D38,0,0,0,0,0,0,0,0,0,0,0,0,0)';$S;BIDI;
    'CLKOUT_PLAT0N':'(B29,0,0,0,0,0,0,0,0,0,0,0,0,0)';$S;BIDI;
    'CLKOUT_PLAT0P':'(D29,0,0,0,0,0,0,0,0,0,0,0,0,0)';$S;BIDI;
    'CLKOUT_PLAT1N':'(B40,0,0,0,0,0,0,0,0,0,0,0,0,0)';$S;BIDI;
    'CLKOUT_PLAT1P':'(D40,0,0,0,0,0,0,0,0,0,0,0,0,0)';$S;BIDI;
    'CLKOUT_SRCN'<15>:'(K27,0,0,0,0,0,0,0,0,0,0,0,0,0)';BIDI;
    'CLKOUT_SRCN'<14>:'(C20,0,0,0,0,0,0,0,0,0,0,0,0,0)';BIDI;
    'CLKOUT_SRCN'<13>:'(C24,0,0,0,0,0,0,0,0,0,0,0,0,0)';BIDI;
    'CLKOUT_SRCN'<12>:'(K24,0,0,0,0,0,0,0,0,0,0,0,0,0)';BIDI;
    'CLKOUT_SRCN'<11>:'(B21,0,0,0,0,0,0,0,0,0,0,0,0,0)';BIDI;
    'CLKOUT_SRCN'<10>:'(B23,0,0,0,0,0,0,0,0,0,0,0,0,0)';BIDI;
    'CLKOUT_SRCN'<9>:'(J26,0,0,0,0,0,0,0,0,0,0,0,0,0)';BIDI;
    'CLKOUT_SRCN'<8>:'(D31,0,0,0,0,0,0,0,0,0,0,0,0,0)';BIDI;
    'CLKOUT_SRCN'<7>:'(H31,0,0,0,0,0,0,0,0,0,0,0,0,0)';BIDI;
    'CLKOUT_SRCN'<6>:'(D33,0,0,0,0,0,0,0,0,0,0,0,0,0)';BIDI;
    'CLKOUT_SRCN'<5>:'(J40,0,0,0,0,0,0,0,0,0,0,0,0,0)';BIDI;
    'CLKOUT_SRCN'<4>:'(A28,0,0,0,0,0,0,0,0,0,0,0,0,0)';BIDI;
    'CLKOUT_SRCN'<3>:'(K42,0,0,0,0,0,0,0,0,0,0,0,0,0)';BIDI;
    'CLKOUT_SRCN'<2>:'(J33,0,0,0,0,0,0,0,0,0,0,0,0,0)';BIDI;
    'CLKOUT_SRCN'<1>:'(K35,0,0,0,0,0,0,0,0,0,0,0,0,0)';BIDI;
    'CLKOUT_SRCN'<0>:'(K38,0,0,0,0,0,0,0,0,0,0,0,0,0)';BIDI;
    'CLKOUT_SRCP'<15>:'(H27,0,0,0,0,0,0,0,0,0,0,0,0,0)';BIDI;
    'CLKOUT_SRCP'<14>:'(A20,0,0,0,0,0,0,0,0,0,0,0,0,0)';BIDI;
    'CLKOUT_SRCP'<13>:'(A24,0,0,0,0,0,0,0,0,0,0,0,0,0)';BIDI;
    'CLKOUT_SRCP'<12>:'(H24,0,0,0,0,0,0,0,0,0,0,0,0,0)';BIDI;
    'CLKOUT_SRCP'<11>:'(D21,0,0,0,0,0,0,0,0,0,0,0,0,0)';BIDI;
    'CLKOUT_SRCP'<10>:'(D23,0,0,0,0,0,0,0,0,0,0,0,0,0)';BIDI;
    'CLKOUT_SRCP'<9>:'(G26,0,0,0,0,0,0,0,0,0,0,0,0,0)';BIDI;
    'CLKOUT_SRCP'<8>:'(B31,0,0,0,0,0,0,0,0,0,0,0,0,0)';BIDI;
    'CLKOUT_SRCP'<7>:'(K31,0,0,0,0,0,0,0,0,0,0,0,0,0)';BIDI;
    'CLKOUT_SRCP'<6>:'(B33,0,0,0,0,0,0,0,0,0,0,0,0,0)';BIDI;
    'CLKOUT_SRCP'<5>:'(G40,0,0,0,0,0,0,0,0,0,0,0,0,0)';BIDI;
    'CLKOUT_SRCP'<4>:'(C28,0,0,0,0,0,0,0,0,0,0,0,0,0)';BIDI;
    'CLKOUT_SRCP'<3>:'(H42,0,0,0,0,0,0,0,0,0,0,0,0,0)';BIDI;
    'CLKOUT_SRCP'<2>:'(G33,0,0,0,0,0,0,0,0,0,0,0,0,0)';BIDI;
    'CLKOUT_SRCP'<1>:'(H35,0,0,0,0,0,0,0,0,0,0,0,0,0)';BIDI;
    'CLKOUT_SRCP'<0>:'(H38,0,0,0,0,0,0,0,0,0,0,0,0,0)';BIDI;
    'CLOCKSE_BMCCLK':'(BW50,0,0,0,0,0,0,0,0,0,0,0,0,0)';$S;BIDI;
    'CLOCKSE_PMSYNCCLK1':'(BY51,0,0,0,0,0,0,0,0,0,0,0,0,0)';$S;BIDI;
    'CLOCKSE_PMSYNCCLK2':'(BV51,0,0,0,0,0,0,0,0,0,0,0,0,0)';$S;BIDI;
    'CPU_TRST_N':'(0,0,0,0,AT56,0,0,0,0,0,0,0,0,0)';$S;BIDI;
    'DMI_RXN'<3>:'(0,0,0,C45,0,0,0,0,0,0,0,0,0,0)';BIDI;
    'DMI_RXN'<2>:'(0,0,0,D44,0,0,0,0,0,0,0,0,0,0)';BIDI;
    'DMI_RXN'<1>:'(0,0,0,C43,0,0,0,0,0,0,0,0,0,0)';BIDI;
    'DMI_RXN'<0>:'(0,0,0,D42,0,0,0,0,0,0,0,0,0,0)';BIDI;
    'DMI_RXP'<3>:'(0,0,0,A45,0,0,0,0,0,0,0,0,0,0)';BIDI;
    'DMI_RXP'<2>:'(0,0,0,B44,0,0,0,0,0,0,0,0,0,0)';BIDI;
    'DMI_RXP'<1>:'(0,0,0,A43,0,0,0,0,0,0,0,0,0,0)';BIDI;
    'DMI_RXP'<0>:'(0,0,0,B42,0,0,0,0,0,0,0,0,0,0)';BIDI;
    'DMI_TXN'<3>:'(0,0,0,P52,0,0,0,0,0,0,0,0,0,0)';BIDI;
    'DMI_TXN'<2>:'(0,0,0,K50,0,0,0,0,0,0,0,0,0,0)';BIDI;
    'DMI_TXN'<1>:'(0,0,0,J48,0,0,0,0,0,0,0,0,0,0)';BIDI;
    'DMI_TXN'<0>:'(0,0,0,H46,0,0,0,0,0,0,0,0,0,0)';BIDI;
    'DMI_TXP'<3>:'(0,0,0,N54,0,0,0,0,0,0,0,0,0,0)';BIDI;
    'DMI_TXP'<2>:'(0,0,0,M52,0,0,0,0,0,0,0,0,0,0)';BIDI;
    'DMI_TXP'<1>:'(0,0,0,H50,0,0,0,0,0,0,0,0,0,0)';BIDI;
    'DMI_TXP'<0>:'(0,0,0,K46,0,0,0,0,0,0,0,0,0,0)';BIDI;
    'DSW_PWROK':'(0,0,0,0,K13,0,0,0,0,0,0,0,0,0)';$S;BIDI;
    'EXTCLKN':'(0,0,D66,0,0,0,0,0,0,0,0,0,0,0)';$S;BIDI;
    'EXTCLKP':'(0,0,E67,0,0,0,0,0,0,0,0,0,0,0)';$S;BIDI;
    'GPD0':'(0,0,0,0,G15,0,0,0,0,0,0,0,0,0)';$S;BIDI;
    'GPD10_SLP_S5_N':'(0,0,0,0,B14,0,0,0,0,0,0,0,0,0)';$S;BIDI;
    'GPD11_GBEPHY':'(0,0,0,0,A13,0,0,0,0,0,0,0,0,0)';$S;BIDI;
    'GPD1_ACPRESENT':'(0,0,0,0,H13,0,0,0,0,0,0,0,0,0)';$S;BIDI;
    'GPD2_GBE_WAKE_N':'(0,0,0,0,M11,0,0,0,0,0,0,0,0,0)';$S;BIDI;
    'GPD3_PWRBTN_N':'(0,0,0,0,C15,0,0,0,0,0,0,0,0,0)';$S;BIDI;
    'GPD4_SLP_S3_N':'(0,0,0,0,D14,0,0,0,0,0,0,0,0,0)';$S;BIDI;
    'GPD5_SLP_S4_N':'(0,0,0,0,B16,0,0,0,0,0,0,0,0,0)';$S;BIDI;
    'GPD6_SLP_A_N':'(0,0,0,0,G11,0,0,0,0,0,0,0,0,0)';$S;BIDI;
    'GPD7':'(0,0,0,0,H9,0,0,0,0,0,0,0,0,0)';$S;BIDI;
    'GPD8_SUSCLK':'(0,0,0,0,C13,0,0,0,0,0,0,0,0,0)';$S;BIDI;
    'GPD9':'(0,0,0,0,A15,0,0,0,0,0,0,0,0,0)';$S;BIDI;
    'GPIO_RCOMP_1P8_3P3':'(0,0,0,0,0,0,0,AM4,0,0,0,0,0,0)';$S;BIDI;
    'GPIO_RCOMP_3P3':'(0,0,0,0,0,0,BY25,0,0,0,0,0,0,0)';$S;BIDI;
    'GPP_A0_RCIN_N_ESPI_ALERT1_N':'(0,0,0,0,0,N3,0,0,0,0,0,0,0,0)';$S;BIDI;
    'GPP_A10_CLKOUT_LPC1':'(0,0,0,0,0,AA4,0,0,0,0,0,0,0,0)';$S;BIDI;
    'GPP_A11_PME_N':'(0,0,0,0,0,AC2,0,0,0,0,0,0,0,0)';$S;BIDI;
    'GPP_A12_BMBUSY_N_SXEXITHLDOFF_N':'(0,0,0,0,0,R1,0,0,0,0,0,0,0,0)';$S;BIDI;
    'GPP_A13_SUSWARN_N_SUSPWRDNACK':'(0,0,0,0,0,T4,0,0,0,0,0,0,0,0)';$S;BIDI;
    'GPP_A14_ESPI_RESET_N':'(0,0,0,0,0,AB3,0,0,0,0,0,0,0,0)';$S;BIDI;
    'GPP_A15_SUSACK_N':'(0,0,0,0,0,AC4,0,0,0,0,0,0,0,0)';$S;BIDI;
    'GPP_A16_CLKOUT_LPC2':'(0,0,0,0,0,T2,0,0,0,0,0,0,0,0)';$S;BIDI;
    'GPP_A17':'(0,0,0,0,0,AD1,0,0,0,0,0,0,0,0)';$S;BIDI;
    'GPP_A18':'(0,0,0,0,0,AD3,0,0,0,0,0,0,0,0)';$S;BIDI;
    'GPP_A19':'(0,0,0,0,0,V3,0,0,0,0,0,0,0,0)';$S;BIDI;
    'GPP_A1_LAD0_ESPI_IO0':'(0,0,0,0,0,Y3,0,0,0,0,0,0,0,0)';$S;BIDI;
    'GPP_A20':'(0,0,0,0,0,W4,0,0,0,0,0,0,0,0)';$S;BIDI;
    'GPP_A21':'(0,0,0,0,0,AE2,0,0,0,0,0,0,0,0)';$S;BIDI;
    'GPP_A22':'(0,0,0,0,0,AE4,0,0,0,0,0,0,0,0)';$S;BIDI;
    'GPP_A23':'(0,0,0,0,0,V1,0,0,0,0,0,0,0,0)';$S;BIDI;
    'GPP_A2_LAD1_ESPI_IO1':'(0,0,0,0,0,N1,0,0,0,0,0,0,0,0)';$S;BIDI;
    'GPP_A3_LAD2_ESPI_IO2':'(0,0,0,0,0,W2,0,0,0,0,0,0,0,0)';$S;BIDI;
    'GPP_A4_LAD3_ESPI_IO3':'(0,0,0,0,0,Y1,0,0,0,0,0,0,0,0)';$S;BIDI;
    'GPP_A5_LFRAME_N_ESPI_CS0_N':'(0,0,0,0,0,P4,0,0,0,0,0,0,0,0)';$S;BIDI;
    'GPP_A6_SERIRQ_ESPI_CS1_N':'(0,0,0,0,0,P2,0,0,0,0,0,0,0,0)';$S;BIDI;
    'GPP_A7_PIRQA_N_ESPI_ALERT0_N':'(0,0,0,0,0,AA2,0,0,0,0,0,0,0,0)';$S;BIDI;
    'GPP_A8_CLKRUN_N':'(0,0,0,0,0,AB1,0,0,0,0,0,0,0,0)';$S;BIDI;
    'GPP_A9_CLKOUT_LPC0_ESPI_CLK':'(0,0,0,0,0,R3,0,0,0,0,0,0,0,0)';$S;BIDI;
    'GPP_B0_CORE_VID0':'(0,0,0,0,0,BL7,0,0,0,0,0,0,0,0)';$S;BIDI;
    'GPP_B10_SRCCLKREQ5_N':'(0,0,0,0,0,BL11,0,0,0,0,0,0,0,0)';$S;BIDI;
    'GPP_B11':'(0,0,0,0,0,BK9,0,0,0,0,0,0,0,0)';$S;BIDI;
    'GPP_B12_GLB_RST_WARN_N':'(0,0,0,0,0,BL18,0,0,0,0,0,0,0,0)';$S;BIDI;
    'GPP_B13_PLTRST_N':'(0,0,0,0,0,BN18,0,0,0,0,0,0,0,0)';$S;BIDI;
    'GPP_B14_SPKR':'(0,0,0,0,0,BH13,0,0,0,0,0,0,0,0)';$S;BIDI;
    'GPP_B15':'(0,0,0,0,0,BK13,0,0,0,0,0,0,0,0)';$S;BIDI;
    'GPP_B16':'(0,0,0,0,0,BG22,0,0,0,0,0,0,0,0)';$S;BIDI;
    'GPP_B17':'(0,0,0,0,0,BG15,0,0,0,0,0,0,0,0)';$S;BIDI;
    'GPP_B18':'(0,0,0,0,0,BL15,0,0,0,0,0,0,0,0)';$S;BIDI;
    'GPP_B19':'(0,0,0,0,0,BK20,0,0,0,0,0,0,0,0)';$S;BIDI;
    'GPP_B1_CORE_VID1':'(0,0,0,0,0,BH9,0,0,0,0,0,0,0,0)';$S;BIDI;
    'GPP_B2':'(0,0,0,0,0,BN15,0,0,0,0,0,0,0,0)';$S;BIDI;
    'GPP_B20':'(0,0,0,0,0,BJ22,0,0,0,0,0,0,0,0)';$S;BIDI;
    'GPP_B21':'(0,0,0,0,0,BH17,0,0,0,0,0,0,0,0)';$S;BIDI;
    'GPP_B22':'(0,0,0,0,0,BR17,0,0,0,0,0,0,0,0)';$S;BIDI;
    'GPP_B23_MEIE_SML1ALRT_N_PHOT_N':'(0,0,0,0,0,BM20,0,0,0,0,0,0,0,0)';$S;BIDI;~

    'GPP_B3_CPU_GP2':'(0,0,0,0,0,BR9,0,0,0,0,0,0,0,0)';$S;BIDI;
    'GPP_B4_CPU_GP3':'(0,0,0,0,0,BN7,0,0,0,0,0,0,0,0)';$S;BIDI;
    'GPP_B5_SRCCLKREQ0_N':'(0,0,0,0,0,BK17,0,0,0,0,0,0,0,0)';$S;BIDI;
    'GPP_B6_SRCCLKREQ1_N':'(0,0,0,0,0,BG18,0,0,0,0,0,0,0,0)';$S;BIDI;
    'GPP_B7_SRCCLKREQ2_N':'(0,0,0,0,0,BR13,0,0,0,0,0,0,0,0)';$S;BIDI;
    'GPP_B8_SRCCLKREQ3_N':'(0,0,0,0,0,BN11,0,0,0,0,0,0,0,0)';$S;BIDI;
    'GPP_B9_SRCCLKREQ4_N':'(0,0,0,0,0,BH20,0,0,0,0,0,0,0,0)';$S;BIDI;
    'GPP_C0_SMBCLK':'(0,0,0,0,0,BW28,0,0,0,0,0,0,0,0)';$S;BIDI;
    'GPP_C10':'(0,0,0,0,0,BV31,0,0,0,0,0,0,0,0)';$S;BIDI;
    'GPP_C11':'(0,0,0,0,0,BV33,0,0,0,0,0,0,0,0)';$S;BIDI;
    'GPP_C12':'(0,0,0,0,0,CA30,0,0,0,0,0,0,0,0)';$S;BIDI;
    'GPP_C13':'(0,0,0,0,0,BV38,0,0,0,0,0,0,0,0)';$S;BIDI;
    'GPP_C14':'(0,0,0,0,0,BY38,0,0,0,0,0,0,0,0)';$S;BIDI;
    'GPP_C15':'(0,0,0,0,0,CA32,0,0,0,0,0,0,0,0)';$S;BIDI;
    'GPP_C16':'(0,0,0,0,0,BW37,0,0,0,0,0,0,0,0)';$S;BIDI;
    'GPP_C17':'(0,0,0,0,0,BY31,0,0,0,0,0,0,0,0)';$S;BIDI;
    'GPP_C18':'(0,0,0,0,0,BY35,0,0,0,0,0,0,0,0)';$S;BIDI;
    'GPP_C19':'(0,0,0,0,0,BW39,0,0,0,0,0,0,0,0)';$S;BIDI;
    'GPP_C1_SMBDATA':'(0,0,0,0,0,BV27,0,0,0,0,0,0,0,0)';$S;BIDI;
    'GPP_C20':'(0,0,0,0,0,CA39,0,0,0,0,0,0,0,0)';$S;BIDI;
    'GPP_C21':'(0,0,0,0,0,BY33,0,0,0,0,0,0,0,0)';$S;BIDI;
    'GPP_C22':'(0,0,0,0,0,CA34,0,0,0,0,0,0,0,0)';$S;BIDI;
    'GPP_C23':'(0,0,0,0,0,CA37,0,0,0,0,0,0,0,0)';$S;BIDI;
    'GPP_C2_SMBALERT_N':'(0,0,0,0,0,BY27,0,0,0,0,0,0,0,0)';$S;BIDI;
    'GPP_C3_SML0CLK_IE':'(0,0,0,0,0,BV29,0,0,0,0,0,0,0,0)';$S;BIDI;
    'GPP_C4_SML0DATA_IE':'(0,0,0,0,0,BW30,0,0,0,0,0,0,0,0)';$S;BIDI;
    'GPP_C5_SML0ALERT_IE_N':'(0,0,0,0,0,BW34,0,0,0,0,0,0,0,0)';$S;BIDI;
    'GPP_C6_SML1CLK_IE':'(0,0,0,0,0,CA28,0,0,0,0,0,0,0,0)';$S;BIDI;
    'GPP_C7_SML1DATA_IE':'(0,0,0,0,0,BV35,0,0,0,0,0,0,0,0)';$S;BIDI;
    'GPP_C8':'(0,0,0,0,0,BW32,0,0,0,0,0,0,0,0)';$S;BIDI;
    'GPP_C9':'(0,0,0,0,0,BY29,0,0,0,0,0,0,0,0)';$S;BIDI;
    'GPP_D0':'(0,0,0,0,0,BR42,0,0,0,0,0,0,0,0)';$S;BIDI;
    'GPP_D1':'(0,0,0,0,0,BK46,0,0,0,0,0,0,0,0)';$S;BIDI;
    'GPP_D10_SSATA_DEVSLP4':'(0,0,0,0,0,BV47,0,0,0,0,0,0,0,0)';$S;BIDI;
    'GPP_D11_SSATA_DEVSLP5':'(0,0,0,0,0,BY47,0,0,0,0,0,0,0,0)';$S;BIDI;
    'GPP_D12_SSATA_SDATAOUT1':'(0,0,0,0,0,BN40,0,0,0,0,0,0,0,0)';$S;BIDI;
    'GPP_D13_SML0BCLK_IE':'(0,0,0,0,0,BY44,0,0,0,0,0,0,0,0)';$S;BIDI;
    'GPP_D14_SML0BDATA_IE':'(0,0,0,0,0,BL44,0,0,0,0,0,0,0,0)';$S;BIDI;
    'GPP_D15_SSATA_SDATAOUT0':'(0,0,0,0,0,BW43,0,0,0,0,0,0,0,0)';$S;BIDI;
    'GPP_D16_SML0BALERT_IE_N':'(0,0,0,0,0,BV42,0,0,0,0,0,0,0,0)';$S;BIDI;
    'GPP_D17':'(0,0,0,0,0,BW48,0,0,0,0,0,0,0,0)';$S;BIDI;
    'GPP_D18':'(0,0,0,0,0,CA41,0,0,0,0,0,0,0,0)';$S;BIDI;
    'GPP_D19':'(0,0,0,0,0,CA43,0,0,0,0,0,0,0,0)';$S;BIDI;
    'GPP_D2':'(0,0,0,0,0,BJ44,0,0,0,0,0,0,0,0)';$S;BIDI;
    'GPP_D20':'(0,0,0,0,0,CA48,0,0,0,0,0,0,0,0)';$S;BIDI;
    'GPP_D21_IE_UART_RX':'(0,0,0,0,0,BV44,0,0,0,0,0,0,0,0)';$S;BIDI;
    'GPP_D22_IE_UART_TX':'(0,0,0,0,0,BR46,0,0,0,0,0,0,0,0)';$S;BIDI;
    'GPP_D23':'(0,0,0,0,0,BN44,0,0,0,0,0,0,0,0)';$S;BIDI;
    'GPP_D3':'(0,0,0,0,0,BW45,0,0,0,0,0,0,0,0)';$S;BIDI;
    'GPP_D4':'(0,0,0,0,0,BM42,0,0,0,0,0,0,0,0)';$S;BIDI;
    'GPP_D5':'(0,0,0,0,0,BM38,0,0,0,0,0,0,0,0)';$S;BIDI;
    'GPP_D6':'(0,0,0,0,0,BW41,0,0,0,0,0,0,0,0)';$S;BIDI;
    'GPP_D7':'(0,0,0,0,0,CA45,0,0,0,0,0,0,0,0)';$S;BIDI;
    'GPP_D8':'(0,0,0,0,0,BR38,0,0,0,0,0,0,0,0)';$S;BIDI;
    'GPP_D9_SSATA_DEVSLP3':'(0,0,0,0,0,BY42,0,0,0,0,0,0,0,0)';$S;BIDI;
    'GPP_E0_SATAXPCIE0_SATAGP0':'(0,0,0,0,0,0,BH50,0,0,0,0,0,0,0)';$S;BIDI;
    'GPP_E10_USB2_OC1_N':'(0,0,0,0,0,0,BN48,0,0,0,0,0,0,0)';$S;BIDI;
    'GPP_E11_USB2_OC2_N':'(0,0,0,0,0,0,AW54,0,0,0,0,0,0,0)';$S;BIDI;
    'GPP_E12_USB2_OC3_N':'(0,0,0,0,0,0,AU58,0,0,0,0,0,0,0)';$S;BIDI;
    'GPP_E1_SATAXPCIE1_SATAGP1':'(0,0,0,0,0,0,AY52,0,0,0,0,0,0,0)';$S;BIDI;
    'GPP_E2_SATAXPCIE2_SATAGP2':'(0,0,0,0,0,0,BG52,0,0,0,0,0,0,0)';$S;BIDI;
    'GPP_E3_CPU_GP0':'(0,0,0,0,0,0,BE52,0,0,0,0,0,0,0)';$S;BIDI;
    'GPP_E4_SATA_DEVSLP0':'(0,0,0,0,0,0,AV52,0,0,0,0,0,0,0)';$S;BIDI;
    'GPP_E5_SATA_DEVSLP1':'(0,0,0,0,0,0,AT52,0,0,0,0,0,0,0)';$S;BIDI;
    'GPP_E6_SATA_DEVSLP2':'(0,0,0,0,0,0,BB52,0,0,0,0,0,0,0)';$S;BIDI;
    'GPP_E7_CPU_GP1':'(0,0,0,0,0,0,BJ48,0,0,0,0,0,0,0)';$S;BIDI;
    'GPP_E8_SATA_LED_N':'(0,0,0,0,0,0,AV56,0,0,0,0,0,0,0)';$S;BIDI;
    'GPP_E9_USB2_OC0_N':'(0,0,0,0,0,0,BL48,0,0,0,0,0,0,0)';$S;BIDI;
    'GPP_F0_SATAXPCIE3_SATAGP3':'(0,0,0,0,0,0,AG7,0,0,0,0,0,0,0)';$S;BIDI;
    'GPP_F10_SATA_SCLOCK':'(0,0,0,0,0,0,AL7,0,0,0,0,0,0,0)';$S;BIDI;
    'GPP_F11_SATA_SLOAD':'(0,0,0,0,0,0,AR9,0,0,0,0,0,0,0)';$S;BIDI;
    'GPP_F12_SATA_SDATAOUT1':'(0,0,0,0,0,0,AP7,0,0,0,0,0,0,0)';$S;BIDI;
    'GPP_F13_SATA_SDATAOUT0':'(0,0,0,0,0,0,AP11,0,0,0,0,0,0,0)';$S;BIDI;
    'GPP_F14_SSATA_LED_N':'(0,0,0,0,0,0,AL11,0,0,0,0,0,0,0)';$S;BIDI;
    'GPP_F15_USB2_OC4_N':'(0,0,0,0,0,0,AR13,0,0,0,0,0,0,0)';$S;BIDI;
    'GPP_F16_USB2_OC5_N':'(0,0,0,0,0,0,AU13,0,0,0,0,0,0,0)';$S;BIDI;
    'GPP_F17_USB2_OC6_N':'(0,0,0,0,0,0,AP15,0,0,0,0,0,0,0)';$S;BIDI;
    'GPP_F18_USB2_OC7_N':'(0,0,0,0,0,0,AL15,0,0,0,0,0,0,0)';$S;BIDI;
    'GPP_F19_LAN_SMBCLK':'(0,0,0,0,0,0,AU9,0,0,0,0,0,0,0)';$S;BIDI;
    'GPP_F1_SATAXPCIE4_SATAGP4':'(0,0,0,0,0,0,AK9,0,0,0,0,0,0,0)';$S;BIDI;
    'GPP_F20_LAN_SMBDATA':'(0,0,0,0,0,0,AU20,0,0,0,0,0,0,0)';$S;BIDI;
    'GPP_F21_LAN_SMBALRT_N':'(0,0,0,0,0,0,AR17,0,0,0,0,0,0,0)';$S;BIDI;
    'GPP_F22_SSATA_SCLOCK':'(0,0,0,0,0,0,AP18,0,0,0,0,0,0,0)';$S;BIDI;
    'GPP_F23_SSATA_SLOAD':'(0,0,0,0,0,0,AU17,0,0,0,0,0,0,0)';$S;BIDI;
    'GPP_F2_SATAXPCIE5_SATAGP5':'(0,0,0,0,0,0,AK20,0,0,0,0,0,0,0)';$S;BIDI;
    'GPP_F3_SATAXPCIE6_SATAGP6':'(0,0,0,0,0,0,AK13,0,0,0,0,0,0,0)';$S;BIDI;
    'GPP_F4_SATAXPCIE7_SATAGP7':'(0,0,0,0,0,0,AH13,0,0,0,0,0,0,0)';$S;BIDI;
    'GPP_F5_SATA_DEVSLP3':'(0,0,0,0,0,0,AH17,0,0,0,0,0,0,0)';$S;BIDI;
    'GPP_F6_SATA_DEVSLP4':'(0,0,0,0,0,0,AL18,0,0,0,0,0,0,0)';$S;BIDI;
    'GPP_F7_SATA_DEVSLP5':'(0,0,0,0,0,0,AK17,0,0,0,0,0,0,0)';$S;BIDI;
    'GPP_F8_SATA_DEVSLP6':'(0,0,0,0,0,0,AH9,0,0,0,0,0,0,0)';$S;BIDI;
    'GPP_F9_SATA_DEVSLP7':'(0,0,0,0,0,0,AR20,0,0,0,0,0,0,0)';$S;BIDI;
    'GPP_G0_FANTACH0_FANTACH0IE':'(0,0,0,0,0,0,AY11,0,0,0,0,0,0,0)';$S;BIDI;
    'GPP_G10_FANPWM2_FANPWM2IE':'(0,0,0,0,0,0,BE11,0,0,0,0,0,0,0)';$S;BIDI;
    'GPP_G11_FANPWM3_FANPMW3IE':'(0,0,0,0,0,0,BA20,0,0,0,0,0,0,0)';$S;BIDI;
    'GPP_G12':'(0,0,0,0,0,0,BD13,0,0,0,0,0,0,0)';$S;BIDI;
    'GPP_G13':'(0,0,0,0,0,0,AY18,0,0,0,0,0,0,0)';$S;BIDI;
    'GPP_G14':'(0,0,0,0,0,0,AV7,0,0,0,0,0,0,0)';$S;BIDI;
    'GPP_G15':'(0,0,0,0,0,0,BE18,0,0,0,0,0,0,0)';$S;BIDI;
    'GPP_G16':'(0,0,0,0,0,0,BD17,0,0,0,0,0,0,0)';$S;BIDI;
    'GPP_G17_ADR_COMPLETE':'(0,0,0,0,0,0,BD9,0,0,0,0,0,0,0)';$S;BIDI;
    'GPP_G18_NMI_N':'(0,0,0,0,0,0,BE7,0,0,0,0,0,0,0)';$S;BIDI;
    'GPP_G19_SMI_N':'(0,0,0,0,0,0,BE15,0,0,0,0,0,0,0)';$S;BIDI;
    'GPP_G1_FANTACH1_FANTACH1IE':'(0,0,0,0,0,0,AV15,0,0,0,0,0,0,0)';$S;BIDI;
    'GPP_G20_SSATA_DEVSLP0':'(0,0,0,0,0,0,BA17,0,0,0,0,0,0,0)';$S;BIDI;
    'GPP_G21_SSATA_DEVSLP1':'(0,0,0,0,0,0,BG7,0,0,0,0,0,0,0)';$S;BIDI;
    'GPP_G22_SSATA_DEVSLP2':'(0,0,0,0,0,0,BD20,0,0,0,0,0,0,0)';$S;BIDI;
    'GPP_G23_SSATAXPCIE0_SSATAGP0':'(0,0,0,0,0,0,BA13,0,0,0,0,0,0,0)';$S;BIDI;
    'GPP_G2_FANTACH2_FANTACH2IE':'(0,0,0,0,0,0,BE22,0,0,0,0,0,0,0)';$S;BIDI;
    'GPP_G3_FANTACH3_FANTACH3IE':'(0,0,0,0,0,0,AY7,0,0,0,0,0,0,0)';$S;BIDI;
    'GPP_G4_FANTACH4_FANTACH4IE':'(0,0,0,0,0,0,BA9,0,0,0,0,0,0,0)';$S;BIDI;
    'GPP_G5_FANTACH5_FANTACH5IE':'(0,0,0,0,0,0,AW20,0,0,0,0,0,0,0)';$S;BIDI;
    'GPP_G6_FANTACH6_FANTACH6IE':'(0,0,0,0,0,0,AV18,0,0,0,0,0,0,0)';$S;BIDI;
    'GPP_G7_FANTACH7_FANTACH7IE':'(0,0,0,0,0,0,AY15,0,0,0,0,0,0,0)';$S;BIDI;
    'GPP_G8_FANPWM0_FANPWM0IE':'(0,0,0,0,0,0,BG11,0,0,0,0,0,0,0)';$S;BIDI;
    'GPP_G9_FANPWM1_FAMPWM1IE':'(0,0,0,0,0,0,AV11,0,0,0,0,0,0,0)';$S;BIDI;
    'GPP_H0_SRCCLKREQ6_N':'(0,0,0,0,0,0,AT4,0,0,0,0,0,0,0)';$S;BIDI;
    'GPP_H10_SML2CLK_IE':'(0,0,0,0,0,0,BA4,0,0,0,0,0,0,0)';$S;BIDI;
    'GPP_H11_SML2DATA_IE':'(0,0,0,0,0,0,BD1,0,0,0,0,0,0,0)';$S;BIDI;
    'GPP_H12_SML2ALERT_N_IE_N':'(0,0,0,0,0,0,BB1,0,0,0,0,0,0,0)';$S;BIDI;
    'GPP_H13_SML3CLK_IE':'(0,0,0,0,0,0,AY1,0,0,0,0,0,0,0)';$S;BIDI;
    'GPP_H14_SML3DATA_IE':'(0,0,0,0,0,0,BC2,0,0,0,0,0,0,0)';$S;BIDI;
    'GPP_H15_SML3ALERT_N_IE_N':'(0,0,0,0,0,0,BB3,0,0,0,0,0,0,0)';$S;BIDI;
    'GPP_H16_SML4CLK_IE':'(0,0,0,0,0,0,BF1,0,0,0,0,0,0,0)';$S;BIDI;
    'GPP_H17_SML4DATA_IE':'(0,0,0,0,0,0,BE4,0,0,0,0,0,0,0)';$S;BIDI;
    'GPP_H18_SML4ALERT_N_IE_N':'(0,0,0,0,0,0,BC4,0,0,0,0,0,0,0)';$S;BIDI;
    'GPP_H19_SSATAXPCIE1_SSATAGP1':'(0,0,0,0,0,0,BD3,0,0,0,0,0,0,0)';$S;BIDI;
    'GPP_H1_SRCCLKREQ7_N':'(0,0,0,0,0,0,AW4,0,0,0,0,0,0,0)';$S;BIDI;
    'GPP_H20_SSATAXPCIE2_SSATAGP2':'(0,0,0,0,0,0,BF3,0,0,0,0,0,0,0)';$S;BIDI;
    'GPP_H21_SSATAXPCIE3_SSATAGP3':'(0,0,0,0,0,0,BA2,0,0,0,0,0,0,0)';$S;BIDI;
    'GPP_H22_SSATAXPCIE4_SSATAGP4':'(0,0,0,0,0,0,BH2,0,0,0,0,0,0,0)';$S;BIDI;
    'GPP_H23_SSATAXPCIE5_SSATAGP5':'(0,0,0,0,0,0,BH4,0,0,0,0,0,0,0)';$S;BIDI;
    'GPP_H2_SRCCLKREQ8_N':'(0,0,0,0,0,0,AV3,0,0,0,0,0,0,0)';$S;BIDI;
    'GPP_H3_SRCCLKREQ9_N':'(0,0,0,0,0,0,AR1,0,0,0,0,0,0,0)';$S;BIDI;
    'GPP_H4_SRCCLKREQ10_N':'(0,0,0,0,0,0,AT2,0,0,0,0,0,0,0)';$S;BIDI;
    'GPP_H5_SRCCLKREQ11_N':'(0,0,0,0,0,0,AY3,0,0,0,0,0,0,0)';$S;BIDI;
    'GPP_H6_SRCCLKREQ12_N':'(0,0,0,0,0,0,AW2,0,0,0,0,0,0,0)';$S;BIDI;
    'GPP_H7_SRCCLKREQ13_N':'(0,0,0,0,0,0,AV1,0,0,0,0,0,0,0)';$S;BIDI;
    'GPP_H8_SRCCLKREQ14_N':'(0,0,0,0,0,0,AR3,0,0,0,0,0,0,0)';$S;BIDI;
    'GPP_H9_SRCCLKREQ15_N':'(0,0,0,0,0,0,BE2,0,0,0,0,0,0,0)';$S;BIDI;
    'GPP_I0_LAN_TDO':'(0,0,0,0,0,0,CA20,0,0,0,0,0,0,0)';$S;
    'GPP_I10':'(0,0,0,0,0,0,BV25,0,0,0,0,0,0,0)';$S;BIDI;
    'GPP_I1_LAN_TCK':'(0,0,0,0,0,0,BV21,0,0,0,0,0,0,0)';$S;
    'GPP_I2_LAN_TMS':'(0,0,0,0,0,0,CA22,0,0,0,0,0,0,0)';$S;
    'GPP_I3_LAN_TDI':'(0,0,0,0,0,0,BY23,0,0,0,0,0,0,0)';$S;
    'GPP_I4_DO_RESET_IN_N':'(0,0,0,0,0,0,BW20,0,0,0,0,0,0,0)';$S;BIDI;
    'GPP_I5_DO_RESET_OUT_N':'(0,0,0,0,0,0,BW24,0,0,0,0,0,0,0)';$S;BIDI;
    'GPP_I6_RESET_DONE':'(0,0,0,0,0,0,BV23,0,0,0,0,0,0,0)';$S;BIDI;
    'GPP_I7_LAN_TRST_N':'(0,0,0,0,0,0,CA24,0,0,0,0,0,0,0)';$S;
    'GPP_I8_PCI_DIS_N':'(0,0,0,0,0,0,BW22,0,0,0,0,0,0,0)';$S;
    'GPP_I9_LAN_DIS_N':'(0,0,0,0,0,0,BY21,0,0,0,0,0,0,0)';$S;
    'GPP_J0_LAN_LED_P0_0':'(0,0,0,0,0,0,BL1,0,0,0,0,0,0,0)';$S;BIDI;
    'GPP_J10_LAN_I2C_SCL_MDC_P1':'(0,0,0,0,0,0,BW5,0,0,0,0,0,0,0)';$S;BIDI;
    'GPP_J11_LAN_I2C_SDA_MDIO_P1':'(0,0,0,0,0,0,BV8,0,0,0,0,0,0,0)';$S;BIDI;
    'GPP_J12_LAN_I2C_SCL_MDC_P2':'(0,0,0,0,0,0,BT5,0,0,0,0,0,0,0)';$S;BIDI;
    'GPP_J13_LAN_I2C_SDA_MDIO_P2':'(0,0,0,0,0,0,BW11,0,0,0,0,0,0,0)';$S;BIDI;
    'GPP_J14_LAN_I2C_SCL_MDC_P3':'(0,0,0,0,0,0,BW6,0,0,0,0,0,0,0)';$S;BIDI;
    'GPP_J15_LAN_I2C_SDA_MDIO_P3':'(0,0,0,0,0,0,BW9,0,0,0,0,0,0,0)';$S;BIDI;
    'GPP_J16_LAN_SDP_P0_0':'(0,0,0,0,0,0,BV10,0,0,0,0,0,0,0)';$S;BIDI;
    'GPP_J17_LAN_SDP_P0_1':'(0,0,0,0,0,0,CA11,0,0,0,0,0,0,0)';$S;BIDI;
    'GPP_J18_LAN_SDP_P1_0':'(0,0,0,0,0,0,BY10,0,0,0,0,0,0,0)';$S;BIDI;
    'GPP_J19_LAN_SDP_P1_1':'(0,0,0,0,0,0,BY14,0,0,0,0,0,0,0)';$S;BIDI;
    'GPP_J1_LAN_LED_P0_1':'(0,0,0,0,0,0,BK4,0,0,0,0,0,0,0)';$S;BIDI;
    'GPP_J20_LAN_SDP_P2_0':'(0,0,0,0,0,0,BW13,0,0,0,0,0,0,0)';$S;BIDI;
    'GPP_J21_LAN_SDP_P2_1':'(0,0,0,0,0,0,BV12,0,0,0,0,0,0,0)';$S;BIDI;
    'GPP_J22_LAN_SDP_P3_0':'(0,0,0,0,0,0,BY12,0,0,0,0,0,0,0)';$S;BIDI;
    'GPP_J23_LAN_SDP_P3_1':'(0,0,0,0,0,0,BV14,0,0,0,0,0,0,0)';$S;BIDI;
    'GPP_J2_LAN_LED_P1_0':'(0,0,0,0,0,0,BP4,0,0,0,0,0,0,0)';$S;BIDI;
    'GPP_J3_LAN_LED_P1_1':'(0,0,0,0,0,0,BK2,0,0,0,0,0,0,0)';$S;BIDI;
    'GPP_J4_LAN_LED_P2_0':'(0,0,0,0,0,0,BL3,0,0,0,0,0,0,0)';$S;BIDI;
    'GPP_J5_LAN_LED_P2_1':'(0,0,0,0,0,0,BU6,0,0,0,0,0,0,0)';$S;BIDI;
    'GPP_J6_LAN_LED_P3_0':'(0,0,0,0,0,0,CA13,0,0,0,0,0,0,0)';$S;BIDI;
    'GPP_J7_LAN_LED_P3_1':'(0,0,0,0,0,0,BM2,0,0,0,0,0,0,0)';$S;BIDI;
    'GPP_J8_LAN_I2C_SCL_MDC_P0':'(0,0,0,0,0,0,BM4,0,0,0,0,0,0,0)';$S;BIDI;
    'GPP_J9_LAN_I2C_SDA_MDIO_P0':'(0,0,0,0,0,0,BN3,0,0,0,0,0,0,0)';$S;BIDI;
    'GPP_K0_LAN_NCSI_CLK_IN':'(0,0,0,0,0,0,0,AJ1,0,0,0,0,0,0)';$S;BIDI;
    'GPP_K10_PE_RST_N':'(0,0,0,0,0,0,0,AH4,0,0,0,0,0,0)';$S;BIDI;
    'GPP_K1_LAN_NCSI_TXD0':'(0,0,0,0,0,0,0,AM2,0,0,0,0,0,0)';$S;BIDI;
    'GPP_K2_LAN_NCSI_TXD1':'(0,0,0,0,0,0,0,AK2,0,0,0,0,0,0)';$S;BIDI;
    'GPP_K3_LAN_NCSI_TX_EN':'(0,0,0,0,0,0,0,AL3,0,0,0,0,0,0)';$S;BIDI;
    'GPP_K4_LAN_NCSI_CRS_DV':'(0,0,0,0,0,0,0,AN3,0,0,0,0,0,0)';$S;BIDI;
    'GPP_K5_LAN_NCSI_RXD0':'(0,0,0,0,0,0,0,AL1,0,0,0,0,0,0)';$S;BIDI;
    'GPP_K6_LAN_NCSI_RXD1':'(0,0,0,0,0,0,0,AN1,0,0,0,0,0,0)';$S;BIDI;
    'GPP_K7':'(0,0,0,0,0,0,0,AH2,0,0,0,0,0,0)';$S;BIDI;
    'GPP_K8_LAN_NCSI_ARB_IN':'(0,0,0,0,0,0,0,AJ3,0,0,0,0,0,0)';$S;BIDI;
    'GPP_K9_LAN_NCSI_ARB_OUT':'(0,0,0,0,0,0,0,AK4,0,0,0,0,0,0)';$S;BIDI;
    'GPP_L10_TESTCH0_CLK':'(0,0,0,0,0,0,0,AF20,0,0,0,0,0,0)';$S;BIDI;
    'GPP_L11_TESTCH1_D0':'(0,0,0,0,0,0,0,AD20,0,0,0,0,0,0)';$S;BIDI;
    'GPP_L12_TESTCH1_D1':'(0,0,0,0,0,0,0,Y15,0,0,0,0,0,0)';$S;BIDI;
    'GPP_L13_TESTCH1_D2':'(0,0,0,0,0,0,0,AD13,0,0,0,0,0,0)';$S;BIDI;
    'GPP_L14_TESTCH1_D3':'(0,0,0,0,0,0,0,AA13,0,0,0,0,0,0)';$S;BIDI;
    'GPP_L15_TESTCH1_D4':'(0,0,0,0,0,0,0,Y11,0,0,0,0,0,0)';$S;BIDI;
    'GPP_L16_TESTCH1_D5':'(0,0,0,0,0,0,0,Y7,0,0,0,0,0,0)';$S;BIDI;
    'GPP_L17_TESTCH1_D6':'(0,0,0,0,0,0,0,AA9,0,0,0,0,0,0)';$S;BIDI;
    'GPP_L18_TESTCH1_D7':'(0,0,0,0,0,0,0,AE7,0,0,0,0,0,0)';$S;BIDI;
    'GPP_L19_TESTCH1_CLK':'(0,0,0,0,0,0,0,AG11,0,0,0,0,0,0)';$S;BIDI;
    'GPP_L2_TESTCH0_D0':'(0,0,0,0,0,0,0,AE18,0,0,0,0,0,0)';$S;BIDI;
    'GPP_L3_TESTCH0_D1':'(0,0,0,0,0,0,0,AE15,0,0,0,0,0,0)';$S;BIDI;
    'GPP_L4_TESTCH0_D2':'(0,0,0,0,0,0,0,AE11,0,0,0,0,0,0)';$S;BIDI;
    'GPP_L5_TESTCH0_D3':'(0,0,0,0,0,0,0,Y18,0,0,0,0,0,0)';$S;BIDI;
    'GPP_L6_TESTCH0_D4':'(0,0,0,0,0,0,0,AA20,0,0,0,0,0,0)';$S;BIDI;
    'GPP_L7_TESTCH0_D5':'(0,0,0,0,0,0,0,AA17,0,0,0,0,0,0)';$S;BIDI;
    'GPP_L8_TESTCH0_D6':'(0,0,0,0,0,0,0,AD9,0,0,0,0,0,0)';$S;BIDI;
    'GPP_L9_TESTCH0_D7':'(0,0,0,0,0,0,0,AD17,0,0,0,0,0,0)';$S;BIDI;
    'HDA_BCLK':'(0,0,0,0,0,0,0,P18,0,0,0,0,0,0)';$S;BIDI;
    'HDA_RST_N':'(0,0,0,0,0,0,0,M18,0,0,0,0,0,0)';$S;BIDI;
    'HDA_SDI_0':'(0,0,0,0,0,0,0,K20,0,0,0,0,0,0)';$S;BIDI;
    'HDA_SDI_1':'(0,0,0,0,0,0,0,V18,0,0,0,0,0,0)';$S;BIDI;
    'HDA_SDO':'(0,0,0,0,0,0,0,U24,0,0,0,0,0,0)';$S;BIDI;
    'HDA_SYNC':'(0,0,0,0,0,0,0,H20,0,0,0,0,0,0)';$S;BIDI;
    'INTRUDER_N':'(0,0,0,0,0,0,0,AG18,0,0,0,0,0,0)';$S;BIDI;
    'ITP_PMODE':'(0,0,0,0,AR54,0,0,0,0,0,0,0,0,0)';$S;BIDI;
    'JTAGX':'(0,0,0,0,AF54,0,0,0,0,0,0,0,0,0)';$S;BIDI;
    'JTAG_TCK':'(0,0,0,0,AL56,0,0,0,0,0,0,0,0,0)';$S;BIDI;
    'JTAG_TDI':'(0,0,0,0,AN54,0,0,0,0,0,0,0,0,0)';$S;BIDI;
    'JTAG_TDO':'(0,0,0,0,AP56,0,0,0,0,0,0,0,0,0)';$S;BIDI;
    'JTAG_TMS':'(0,0,0,0,AH54,0,0,0,0,0,0,0,0,0)';$S;BIDI;
    'LAN_RBIAS_0':'(0,0,0,0,BB29,0,0,0,0,0,0,0,0,0)';$S;BIDI;
    'LAN_RBIAS_1':'(0,0,0,0,BD42,0,0,0,0,0,0,0,0,0)';$S;BIDI;
    'LAN_RX_P0N':'(0,0,0,0,BH31,0,0,0,0,0,0,0,0,0)';$S;BIDI;
    'LAN_RX_P0P':'(0,0,0,0,BF31,0,0,0,0,0,0,0,0,0)';$S;BIDI;
    'LAN_RX_P1N':'(0,0,0,0,BG29,0,0,0,0,0,0,0,0,0)';$S;BIDI;
    'LAN_RX_P1P':'(0,0,0,0,BJ29,0,0,0,0,0,0,0,0,0)';$S;BIDI;
    'LAN_RX_P2N':'(0,0,0,0,BJ37,0,0,0,0,0,0,0,0,0)';$S;BIDI;
    'LAN_RX_P2P':'(0,0,0,0,BG37,0,0,0,0,0,0,0,0,0)';$S;BIDI;
    'LAN_RX_P3N':'(0,0,0,0,BF35,0,0,0,0,0,0,0,0,0)';$S;BIDI;
    'LAN_RX_P3P':'(0,0,0,0,BH35,0,0,0,0,0,0,0,0,0)';$S;BIDI;
    'LAN_TX_P0N':'(0,0,0,0,BM27,0,0,0,0,0,0,0,0,0)';$S;BIDI;
    'LAN_TX_P0P':'(0,0,0,0,BR27,0,0,0,0,0,0,0,0,0)';$S;BIDI;
    'LAN_TX_P1N':'(0,0,0,0,BM24,0,0,0,0,0,0,0,0,0)';$S;BIDI;
    'LAN_TX_P1P':'(0,0,0,0,BR24,0,0,0,0,0,0,0,0,0)';$S;BIDI;
    'LAN_TX_P2N':'(0,0,0,0,BM35,0,0,0,0,0,0,0,0,0)';$S;BIDI;
    'LAN_TX_P2P':'(0,0,0,0,BR35,0,0,0,0,0,0,0,0,0)';$S;BIDI;
    'LAN_TX_P3N':'(0,0,0,0,BR31,0,0,0,0,0,0,0,0,0)';$S;BIDI;
    'LAN_TX_P3P':'(0,0,0,0,BM31,0,0,0,0,0,0,0,0,0)';$S;BIDI;
    'LAN_XTAL_IN':'(0,0,0,0,BV16,0,0,0,0,0,0,0,0,0)';$S;BIDI;
    'LAN_XTAL_OUT':'(0,0,0,0,BY16,0,0,0,0,0,0,0,0,0)';$S;BIDI;
    'PCH_PWROK':'(0,0,0,0,R17,0,0,0,0,0,0,0,0,0)';$S;BIDI;
    'PCIE10_SSATA4_RXN':'(0,0,AV63,0,0,0,0,0,0,0,0,0,0,0)';$S;BIDI;
    'PCIE10_SSATA4_RXP':'(0,0,AU65,0,0,0,0,0,0,0,0,0,0,0)';$S;BIDI;
    'PCIE10_SSATA4_TXN':'(0,0,AD70,0,0,0,0,0,0,0,0,0,0,0)';$S;BIDI;
    'PCIE10_SSATA4_TXP':'(0,0,AD72,0,0,0,0,0,0,0,0,0,0,0)';$S;BIDI;
    'PCIE11_SSATA5_GBE_RXN':'(0,0,AT66,0,0,0,0,0,0,0,0,0,0,0)';$S;BIDI;
    'PCIE11_SSATA5_GBE_RXP':'(0,0,AV66,0,0,0,0,0,0,0,0,0,0,0)';$S;BIDI;
    'PCIE11_SSATA5_GBE_TXN':'(0,0,AC69,0,0,0,0,0,0,0,0,0,0,0)';$S;BIDI;
    'PCIE11_SSATA5_GBE_TXP':'(0,0,AC71,0,0,0,0,0,0,0,0,0,0,0)';$S;BIDI;
    'PCIE12_UP0_SATA0_RXN':'(0,0,AR61,0,0,0,0,0,0,0,0,0,0,0)';$S;BIDI;
    'PCIE12_UP0_SATA0_RXP':'(0,0,AT63,0,0,0,0,0,0,0,0,0,0,0)';$S;BIDI;
    'PCIE12_UP0_SATA0_TXN':'(0,0,W69,0,0,0,0,0,0,0,0,0,0,0)';$S;BIDI;
    'PCIE12_UP0_SATA0_TXP':'(0,0,W71,0,0,0,0,0,0,0,0,0,0,0)';$S;BIDI;
    'PCIE13_UP1_SATA1_RXN':'(0,0,AL66,0,0,0,0,0,0,0,0,0,0,0)';$S;BIDI;
    'PCIE13_UP1_SATA1_RXP':'(0,0,AN65,0,0,0,0,0,0,0,0,0,0,0)';$S;BIDI;
    'PCIE13_UP1_SATA1_TXN':'(0,0,V70,0,0,0,0,0,0,0,0,0,0,0)';$S;BIDI;
    'PCIE13_UP1_SATA1_TXP':'(0,0,V72,0,0,0,0,0,0,0,0,0,0,0)';$S;BIDI;
    'PCIE14_UP2_SATA2_RXN':'(0,0,AK65,0,0,0,0,0,0,0,0,0,0,0)';$S;BIDI;
    'PCIE14_UP2_SATA2_RXP':'(0,0,AJ63,0,0,0,0,0,0,0,0,0,0,0)';$S;BIDI;
    'PCIE14_UP2_SATA2_TXN':'(0,0,T69,0,0,0,0,0,0,0,0,0,0,0)';$S;BIDI;
    'PCIE14_UP2_SATA2_TXP':'(0,0,T71,0,0,0,0,0,0,0,0,0,0,0)';$S;BIDI;
    'PCIE15_UP3_SATA3_RXN':'(0,0,AP63,0,0,0,0,0,0,0,0,0,0,0)';$S;BIDI;
    'PCIE15_UP3_SATA3_RXP':'(0,0,AL63,0,0,0,0,0,0,0,0,0,0,0)';$S;BIDI;
    'PCIE15_UP3_SATA3_TXN':'(0,0,R70,0,0,0,0,0,0,0,0,0,0,0)';$S;BIDI;
    'PCIE15_UP3_SATA3_TXP':'(0,0,R72,0,0,0,0,0,0,0,0,0,0,0)';$S;BIDI;
    'PCIE16_UP4_SATA4_RXN':'(0,0,AF65,0,0,0,0,0,0,0,0,0,0,0)';$S;BIDI;
    'PCIE16_UP4_SATA4_RXP':'(0,0,AH65,0,0,0,0,0,0,0,0,0,0,0)';$S;BIDI;
    'PCIE16_UP4_SATA4_TXN':'(0,0,P69,0,0,0,0,0,0,0,0,0,0,0)';$S;BIDI;
    'PCIE16_UP4_SATA4_TXP':'(0,0,P71,0,0,0,0,0,0,0,0,0,0,0)';$S;BIDI;
    'PCIE17_UP5_SATA5_RXN':'(0,0,AH61,0,0,0,0,0,0,0,0,0,0,0)';$S;BIDI;
    'PCIE17_UP5_SATA5_RXP':'(0,0,AG63,0,0,0,0,0,0,0,0,0,0,0)';$S;BIDI;
    'PCIE17_UP5_SATA5_TXN':'(0,0,N70,0,0,0,0,0,0,0,0,0,0,0)';$S;BIDI;
    'PCIE17_UP5_SATA5_TXP':'(0,0,N72,0,0,0,0,0,0,0,0,0,0,0)';$S;BIDI;
    'PCIE18_UP6_SATA6_RXN':'(0,0,AP59,0,0,0,0,0,0,0,0,0,0,0)';$S;BIDI;
    'PCIE18_UP6_SATA6_RXP':'(0,0,AN61,0,0,0,0,0,0,0,0,0,0,0)';$S;BIDI;
    'PCIE18_UP6_SATA6_TXN':'(0,0,M69,0,0,0,0,0,0,0,0,0,0,0)';$S;BIDI;
    'PCIE18_UP6_SATA6_TXP':'(0,0,M71,0,0,0,0,0,0,0,0,0,0,0)';$S;BIDI;
    'PCIE19_UP7_SATA7_RXN':'(0,0,AA61,0,0,0,0,0,0,0,0,0,0,0)';$S;BIDI;
    'PCIE19_UP7_SATA7_RXP':'(0,0,AD61,0,0,0,0,0,0,0,0,0,0,0)';$S;BIDI;
    'PCIE19_UP7_SATA7_TXN':'(0,0,L70,0,0,0,0,0,0,0,0,0,0,0)';$S;BIDI;
    'PCIE19_UP7_SATA7_TXP':'(0,0,L72,0,0,0,0,0,0,0,0,0,0,0)';$S;BIDI;
    'PCIE4_GBE_RXN':'(0,0,AN70,0,0,0,0,0,0,0,0,0,0,0)';$S;BIDI;
    'PCIE4_GBE_RXP':'(0,0,AN72,0,0,0,0,0,0,0,0,0,0,0)';$S;BIDI;
    'PCIE4_GBE_TXN':'(0,0,BG66,0,0,0,0,0,0,0,0,0,0,0)';$S;BIDI;
    'PCIE4_GBE_TXP':'(0,0,BJ66,0,0,0,0,0,0,0,0,0,0,0)';$S;BIDI;
    'PCIE5_GBE_RXN':'(0,0,AM69,0,0,0,0,0,0,0,0,0,0,0)';$S;BIDI;
    'PCIE5_GBE_RXP':'(0,0,AM71,0,0,0,0,0,0,0,0,0,0,0)';$S;BIDI;
    'PCIE5_GBE_TXN':'(0,0,BH65,0,0,0,0,0,0,0,0,0,0,0)';$S;BIDI;
    'PCIE5_GBE_TXP':'(0,0,BJ63,0,0,0,0,0,0,0,0,0,0,0)';$S;BIDI;
    'PCIE6_SSATA0_RXN':'(0,0,BB63,0,0,0,0,0,0,0,0,0,0,0)';$S;BIDI;
    'PCIE6_SSATA0_RXP':'(0,0,BD61,0,0,0,0,0,0,0,0,0,0,0)';$S;BIDI;
    'PCIE6_SSATA0_TXN':'(0,0,AJ70,0,0,0,0,0,0,0,0,0,0,0)';$S;BIDI;
    'PCIE6_SSATA0_TXP':'(0,0,AJ72,0,0,0,0,0,0,0,0,0,0,0)';$S;BIDI;
    'PCIE7_SSATA1_RXN':'(0,0,AY59,0,0,0,0,0,0,0,0,0,0,0)';$S;BIDI;
    'PCIE7_SSATA1_RXP':'(0,0,BA61,0,0,0,0,0,0,0,0,0,0,0)';$S;BIDI;
    'PCIE7_SSATA1_TXN':'(0,0,AH69,0,0,0,0,0,0,0,0,0,0,0)';$S;BIDI;
    'PCIE7_SSATA1_TXP':'(0,0,AH71,0,0,0,0,0,0,0,0,0,0,0)';$S;BIDI;
    'PCIE8_SSATA2_GBE_RXN':'(0,0,BA65,0,0,0,0,0,0,0,0,0,0,0)';$S;BIDI;
    'PCIE8_SSATA2_GBE_RXP':'(0,0,BD65,0,0,0,0,0,0,0,0,0,0,0)';$S;BIDI;
    'PCIE8_SSATA2_GBE_TXN':'(0,0,AF70,0,0,0,0,0,0,0,0,0,0,0)';$S;BIDI;
    'PCIE8_SSATA2_GBE_TXP':'(0,0,AF72,0,0,0,0,0,0,0,0,0,0,0)';$S;BIDI;
    'PCIE9_SSATA3_RXN':'(0,0,AW65,0,0,0,0,0,0,0,0,0,0,0)';$S;BIDI;
    'PCIE9_SSATA3_RXP':'(0,0,AY66,0,0,0,0,0,0,0,0,0,0,0)';$S;BIDI;
    'PCIE9_SSATA3_TXN':'(0,0,AE69,0,0,0,0,0,0,0,0,0,0,0)';$S;BIDI;
    'PCIE9_SSATA3_TXP':'(0,0,AE71,0,0,0,0,0,0,0,0,0,0,0)';$S;BIDI;
    'PCIEUP_0_RXN':'(0,0,0,C48,0,0,0,0,0,0,0,0,0,0)';$S;BIDI;
    'PCIEUP_0_RXP':'(0,0,0,A48,0,0,0,0,0,0,0,0,0,0)';$S;BIDI;
    'PCIEUP_0_TXN':'(0,0,0,J52,0,0,0,0,0,0,0,0,0,0)';$S;BIDI;
    'PCIEUP_0_TXP':'(0,0,0,G52,0,0,0,0,0,0,0,0,0,0)';$S;BIDI;
    'PCIEUP_10_RXN':'(0,0,0,C59,0,0,0,0,0,0,0,0,0,0)';$S;BIDI;
    'PCIEUP_10_RXP':'(0,0,0,A59,0,0,0,0,0,0,0,0,0,0)';$S;BIDI;
    'PCIEUP_10_TXN':'(0,0,0,N65,0,0,0,0,0,0,0,0,0,0)';$S;BIDI;
    'PCIEUP_10_TXP':'(0,0,0,P66,0,0,0,0,0,0,0,0,0,0)';$S;BIDI;
    'PCIEUP_11_RXN':'(0,0,0,D60,0,0,0,0,0,0,0,0,0,0)';$S;BIDI;
    'PCIEUP_11_RXP':'(0,0,0,B60,0,0,0,0,0,0,0,0,0,0)';$S;BIDI;
    'PCIEUP_11_TXN':'(0,0,0,T59,0,0,0,0,0,0,0,0,0,0)';$S;BIDI;
    'PCIEUP_11_TXP':'(0,0,0,V59,0,0,0,0,0,0,0,0,0,0)';$S;BIDI;
    'PCIEUP_12_RXN':'(0,0,0,C61,0,0,0,0,0,0,0,0,0,0)';$S;BIDI;
    'PCIEUP_12_RXP':'(0,0,0,A61,0,0,0,0,0,0,0,0,0,0)';$S;BIDI;
    'PCIEUP_12_TXN':'(0,0,0,R65,0,0,0,0,0,0,0,0,0,0)';$S;BIDI;
    'PCIEUP_12_TXP':'(0,0,0,U65,0,0,0,0,0,0,0,0,0,0)';$S;BIDI;
    'PCIEUP_13_RXN':'(0,0,0,D62,0,0,0,0,0,0,0,0,0,0)';$S;BIDI;
    'PCIEUP_13_RXP':'(0,0,0,B62,0,0,0,0,0,0,0,0,0,0)';$S;BIDI;
    'PCIEUP_13_TXN':'(0,0,0,T63,0,0,0,0,0,0,0,0,0,0)';$S;BIDI;
    'PCIEUP_13_TXP':'(0,0,0,U61,0,0,0,0,0,0,0,0,0,0)';$S;BIDI;
    'PCIEUP_14_RXN':'(0,0,0,C63,0,0,0,0,0,0,0,0,0,0)';$S;BIDI;
    'PCIEUP_14_RXP':'(0,0,0,A63,0,0,0,0,0,0,0,0,0,0)';$S;BIDI;
    'PCIEUP_14_TXN':'(0,0,0,W65,0,0,0,0,0,0,0,0,0,0)';$S;BIDI;
    'PCIEUP_14_TXP':'(0,0,0,V63,0,0,0,0,0,0,0,0,0,0)';$S;BIDI;
    'PCIEUP_15_RXN':'(0,0,0,D64,0,0,0,0,0,0,0,0,0,0)';$S;BIDI;
    'PCIEUP_15_RXP':'(0,0,0,B64,0,0,0,0,0,0,0,0,0,0)';$S;BIDI;
    'PCIEUP_15_TXN':'(0,0,0,Y66,0,0,0,0,0,0,0,0,0,0)';$S;BIDI;
    'PCIEUP_15_TXP':'(0,0,0,AA65,0,0,0,0,0,0,0,0,0,0)';$S;BIDI;
    'PCIEUP_1_RXN':'(0,0,0,D49,0,0,0,0,0,0,0,0,0,0)';$S;BIDI;
    'PCIEUP_1_RXP':'(0,0,0,B49,0,0,0,0,0,0,0,0,0,0)';$S;BIDI;
    'PCIEUP_1_TXN':'(0,0,0,P56,0,0,0,0,0,0,0,0,0,0)';$S;BIDI;
    'PCIEUP_1_TXP':'(0,0,0,M56,0,0,0,0,0,0,0,0,0,0)';$S;BIDI;
    'PCIEUP_2_RXN':'(0,0,0,C50,0,0,0,0,0,0,0,0,0,0)';$S;BIDI;
    'PCIEUP_2_RXP':'(0,0,0,A50,0,0,0,0,0,0,0,0,0,0)';$S;BIDI;
    'PCIEUP_2_TXN':'(0,0,0,H54,0,0,0,0,0,0,0,0,0,0)';$S;BIDI;
    'PCIEUP_2_TXP':'(0,0,0,G56,0,0,0,0,0,0,0,0,0,0)';$S;BIDI;
    'PCIEUP_3_RXN':'(0,0,0,D51,0,0,0,0,0,0,0,0,0,0)';$S;BIDI;
    'PCIEUP_3_RXP':'(0,0,0,B51,0,0,0,0,0,0,0,0,0,0)';$S;BIDI;
    'PCIEUP_3_TXN':'(0,0,0,J56,0,0,0,0,0,0,0,0,0,0)';$S;BIDI;
    'PCIEUP_3_TXP':'(0,0,0,K58,0,0,0,0,0,0,0,0,0,0)';$S;BIDI;
    'PCIEUP_4_RXN':'(0,0,0,C52,0,0,0,0,0,0,0,0,0,0)';$S;BIDI;
    'PCIEUP_4_RXP':'(0,0,0,A52,0,0,0,0,0,0,0,0,0,0)';$S;BIDI;
    'PCIEUP_4_TXN':'(0,0,0,N58,0,0,0,0,0,0,0,0,0,0)';$S;BIDI;
    'PCIEUP_4_TXP':'(0,0,0,M59,0,0,0,0,0,0,0,0,0,0)';$S;BIDI;
    'PCIEUP_5_RXN':'(0,0,0,D53,0,0,0,0,0,0,0,0,0,0)';$S;BIDI;
    'PCIEUP_5_RXP':'(0,0,0,B53,0,0,0,0,0,0,0,0,0,0)';$S;BIDI;
    'PCIEUP_5_TXN':'(0,0,0,N61,0,0,0,0,0,0,0,0,0,0)';$S;BIDI;
    'PCIEUP_5_TXP':'(0,0,0,K61,0,0,0,0,0,0,0,0,0,0)';$S;BIDI;
    'PCIEUP_6_RXN':'(0,0,0,C54,0,0,0,0,0,0,0,0,0,0)';$S;BIDI;
    'PCIEUP_6_RXP':'(0,0,0,A54,0,0,0,0,0,0,0,0,0,0)';$S;BIDI;
    'PCIEUP_6_TXN':'(0,0,0,H61,0,0,0,0,0,0,0,0,0,0)';$S;BIDI;
    'PCIEUP_6_TXP':'(0,0,0,J63,0,0,0,0,0,0,0,0,0,0)';$S;BIDI;
    'PCIEUP_7_RXN':'(0,0,0,D55,0,0,0,0,0,0,0,0,0,0)';$S;BIDI;
    'PCIEUP_7_RXP':'(0,0,0,B55,0,0,0,0,0,0,0,0,0,0)';$S;BIDI;
    'PCIEUP_7_TXN':'(0,0,0,P59,0,0,0,0,0,0,0,0,0,0)';$S;BIDI;
    'PCIEUP_7_TXP':'(0,0,0,R61,0,0,0,0,0,0,0,0,0,0)';$S;BIDI;
    'PCIEUP_8_RXN':'(0,0,0,C57,0,0,0,0,0,0,0,0,0,0)';$S;BIDI;
    'PCIEUP_8_RXP':'(0,0,0,A57,0,0,0,0,0,0,0,0,0,0)';$S;BIDI;
    'PCIEUP_8_TXN':'(0,0,0,K65,0,0,0,0,0,0,0,0,0,0)';$S;BIDI;
    'PCIEUP_8_TXP':'(0,0,0,M63,0,0,0,0,0,0,0,0,0,0)';$S;BIDI;
    'PCIEUP_9_RXN':'(0,0,0,D58,0,0,0,0,0,0,0,0,0,0)';$S;BIDI;
    'PCIEUP_9_RXP':'(0,0,0,B58,0,0,0,0,0,0,0,0,0,0)';$S;BIDI;
    'PCIEUP_9_TXN':'(0,0,0,J66,0,0,0,0,0,0,0,0,0,0)';$S;BIDI;
    'PCIEUP_9_TXP':'(0,0,0,M66,0,0,0,0,0,0,0,0,0,0)';$S;BIDI;
    'PCIEUP_RCOMPN':'(0,0,AF58,0,0,0,0,0,0,0,0,0,0,0)';$S;BIDI;
    'PCIEUP_RCOMPP':'(0,0,AH58,0,0,0,0,0,0,0,0,0,0,0)';$S;BIDI;
    'PCIE_RCOMPN':'(0,0,BD58,0,0,0,0,0,0,0,0,0,0,0)';$S;BIDI;
    'PCIE_RCOMPP':'(0,0,BB56,0,0,0,0,0,0,0,0,0,0,0)';$S;BIDI;
    'PECI':'(0,0,0,0,U9,0,0,0,0,0,0,0,0,0)';$S;BIDI;
    'PLTRST_CPU_N':'(0,0,0,0,U17,0,0,0,0,0,0,0,0,0)';$S;BIDI;
    'PM_SYNC':'(0,0,0,0,U13,0,0,0,0,0,0,0,0,0)';$S;BIDI;
    'PM_SYNC2':'(0,0,0,0,V7,0,0,0,0,0,0,0,0,0)';$S;BIDI;
    'PRDY_N':'(0,0,0,0,AD54,0,0,0,0,0,0,0,0,0)';$S;BIDI;
    'PREQ_N':'(0,0,0,0,U54,0,0,0,0,0,0,0,0,0)';$S;BIDI;
    'PROC_PWRGD':'(0,0,0,0,R9,0,0,0,0,0,0,0,0,0)';$S;BIDI;
    'RSMRST_N':'(0,0,0,0,P15,0,0,0,0,0,0,0,0,0)';$S;BIDI;
    'RSVD'<68>:'(0,0,0,0,0,0,0,V22,0,0,0,0,0,0)';BIDI;
    'RSVD'<67>:'(0,0,0,0,0,0,0,R20,0,0,0,0,0,0)';BIDI;
    'RSVD'<66>:'(0,0,0,0,0,0,0,U20,0,0,0,0,0,0)';BIDI;
    'RSVD'<65>:'(A26,0,0,0,0,0,0,0,0,0,0,0,0,0)';
    'RSVD'<64>:'(C26,0,0,0,0,0,0,0,0,0,0,0,0,0)';
    'RSVD'<59>:'(0,0,0,0,0,0,0,0,AT27,0,0,0,0,0)';
    'RSVD'<58>:'(0,0,0,0,0,0,0,0,AP27,0,0,0,0,0)';
    'RSVD'<55>:'(0,BN68,0,0,0,0,0,0,0,0,0,0,0,0)';
    'RSVD'<54>:'(0,0,0,0,R24,0,0,0,0,0,0,0,0,0)';
    'RSVD'<53>:'(0,0,0,0,P26,0,0,0,0,0,0,0,0,0)';
    'RSVD'<52>:'(0,0,AA71,0,0,0,0,0,0,0,0,0,0,0)';
    'RSVD'<51>:'(0,0,AA69,0,0,0,0,0,0,0,0,0,0,0)';
    'RSVD'<50>:'(0,0,H69,0,0,0,0,0,0,0,0,0,0,0)';
    'RSVD'<49>:'(0,0,G67,0,0,0,0,0,0,0,0,0,0,0)';
    'RSVD'<48>:'(0,0,AP71,0,0,0,0,0,0,0,0,0,0,0)';
    'RSVD'<47>:'(0,0,AP69,0,0,0,0,0,0,0,0,0,0,0)';
    'RSVD'<46>:'(0,0,0,0,0,0,0,BW3,0,0,0,0,0,0)';
    'RSVD'<45>:'(0,0,0,0,P22,0,0,0,0,0,0,0,0,0)';
    'RSVD'<44>:'(0,0,0,0,BN33,0,0,0,0,0,0,0,0,0)';
    'RSVD'<43>:'(0,0,0,0,BL33,0,0,0,0,0,0,0,0,0)';
    'RSVD'<42>:'(0,0,0,0,BG40,0,0,0,0,0,0,0,0,0)';
    'RSVD'<41>:'(0,0,0,0,BJ40,0,0,0,0,0,0,0,0,0)';
    'RSVD'<40>:'(0,0,0,0,BN26,0,0,0,0,0,0,0,0,0)';
    'RSVD'<39>:'(0,0,0,0,BL26,0,0,0,0,0,0,0,0,0)';
    'RSVD'<38>:'(0,0,0,0,BL29,0,0,0,0,0,0,0,0,0)';
    'RSVD'<37>:'(0,0,0,0,BN29,0,0,0,0,0,0,0,0,0)';
    'RSVD'<36>:'(0,0,0,0,AK54,0,0,0,0,0,0,0,0,0)';
    'RSVD'<35>:'(0,0,0,0,W54,0,0,0,0,0,0,0,0,0)';
    'RSVD'<34>:'(0,0,0,0,Y56,0,0,0,0,0,0,0,0,0)';
    'RSVD'<33>:'(0,0,0,0,V56,0,0,0,0,0,0,0,0,0)';
    'RSVD'<32>:'(0,0,0,0,AA54,0,0,0,0,0,0,0,0,0)';
    'RSVD'<31>:'(0,0,0,0,0,0,0,0,P29,0,0,0,0,0)';
    'RSVD'<30>:'(0,0,0,0,0,0,0,0,R31,0,0,0,0,0)';
    'RSVD'<29>:'(0,0,0,0,0,0,0,0,P33,0,0,0,0,0)';
    'RSVD'<28>:'(0,0,0,0,0,0,0,0,R35,0,0,0,0,0)';
    'RSVD'<27>:'(0,0,0,0,0,0,0,BG26,0,0,0,0,0,0)';
    'RSVD'<26>:'(0,0,0,0,0,0,0,BH24,0,0,0,0,0,0)';
    'RSVD'<25>:'(0,0,0,0,0,0,0,P48,0,0,0,0,0,0)';
    'RSVD'<24>:'(0,0,0,0,0,0,0,P44,0,0,0,0,0,0)';
    'RSVD'<23>:'(0,0,0,0,0,0,0,P40,0,0,0,0,0,0)';
    'RSVD'<22>:'(0,0,0,0,0,0,0,AT71,0,0,0,0,0,0)';
    'RSVD'<21>:'(0,0,0,0,0,0,0,A11,0,0,0,0,0,0)';
    'RSVD'<20>:'(0,0,0,0,0,0,0,D10,0,0,0,0,0,0)';
    'RSVD'<19>:'(0,0,0,0,0,0,0,C9,0,0,0,0,0,0)';
    'RSVD'<18>:'(0,0,0,0,0,0,0,C11,0,0,0,0,0,0)';
    'RSVD'<17>:'(0,0,0,0,0,0,0,B10,0,0,0,0,0,0)';
    'RSVD'<16>:'(0,0,0,0,0,0,0,C5,0,0,0,0,0,0)';
    'RSVD'<15>:'(0,0,0,0,0,0,0,C6,0,0,0,0,0,0)';
    'RSVD'<14>:'(0,0,0,0,0,0,0,E18,0,0,0,0,0,0)';
    'RSVD'<13>:'(0,0,0,0,0,0,0,C67,0,0,0,0,0,0)';
    'RSVD'<12>:'(0,0,0,0,0,0,0,C68,0,0,0,0,0,0)';
    'RSVD'<11>:'(0,0,0,0,0,0,0,C18,0,0,0,0,0,0)';
    'RSVD'<10>:'(0,0,0,0,0,0,0,D8,0,0,0,0,0,0)';
    'RSVD'<9>:'(0,0,0,0,0,0,0,F66,0,0,0,0,0,0)';
    'RSVD'<8>:'(0,0,0,0,0,0,0,F69,0,0,0,0,0,0)';
    'RSVD'<7>:'(0,0,0,0,0,0,0,F8,0,0,0,0,0,0)';
    'RSVD'<6>:'(0,0,0,0,0,0,0,AT69,0,0,0,0,0,0)';
    'RSVD'<5>:'(0,0,0,0,0,0,0,AG15,0,0,0,0,0,0)';
    'RSVD'<4>:'(0,0,0,0,0,0,0,P37,0,0,0,0,0,0)';
    'RSVD'<3>:'(0,0,0,0,0,0,0,V11,0,0,0,0,0,0)';
    'RSVD'<2>:'(0,0,0,0,0,0,0,AA58,0,0,0,0,0,0)';
    'RSVD'<1>:'(0,0,0,0,0,0,0,AC56,0,0,0,0,0,0)';
    'RSVD'<0>:'(0,0,0,0,0,0,0,AF61,0,0,0,0,0,0)';
    'RTCRST_N':'(0,0,0,0,0,0,0,P11,0,0,0,0,0,0)';$S;BIDI;
    'RTCX1':'(K17,0,0,0,0,0,0,0,0,0,0,0,0,0)';$S;BIDI;
    'RTCX2':'(H17,0,0,0,0,0,0,0,0,0,0,0,0,0)';$S;BIDI;
    'SLP_GBE_N':'(0,0,0,0,M15,0,0,0,0,0,0,0,0,0)';$S;BIDI;
    'SLP_SUS_N':'(0,0,0,0,P7,0,0,0,0,0,0,0,0,0)';$S;BIDI;
    'SPI0_CLK':'(0,0,0,0,0,0,0,K2,0,0,0,0,0,0)';$S;BIDI;
    'SPI0_FLASH_CS0_N':'(0,0,0,0,0,0,0,J3,0,0,0,0,0,0)';$S;BIDI;
    'SPI0_FLASH_CS1_N':'(0,0,0,0,0,0,0,G7,0,0,0,0,0,0)';$S;BIDI;
    'SPI0_IO2':'(0,0,0,0,0,0,0,F5,0,0,0,0,0,0)';$S;BIDI;
    'SPI0_IO3':'(0,0,0,0,0,0,0,L1,0,0,0,0,0,0)';$S;BIDI;
    'SPI0_MISO_IO1':'(0,0,0,0,0,0,0,L3,0,0,0,0,0,0)';$S;BIDI;
    'SPI0_MOSI_IO0':'(0,0,0,0,0,0,0,H4,0,0,0,0,0,0)';$S;BIDI;
    'SPI0_TPM_CS_N':'(0,0,0,0,0,0,0,K4,0,0,0,0,0,0)';$S;BIDI;
    'SRTCRST_N':'(0,0,0,0,0,0,0,G18,0,0,0,0,0,0)';$S;BIDI;
    'SYS_PWROK':'(0,0,0,0,BY19,0,0,0,0,0,0,0,0,0)';$S;BIDI;
    'SYS_RESET_N':'(0,0,0,0,BV19,0,0,0,0,0,0,0,0,0)';$S;BIDI;
    'THRMTRIP_N':'(0,0,0,0,V15,0,0,0,0,0,0,0,0,0)';$S;BIDI;
    'TRIGGER_IN':'(0,0,0,0,M7,0,0,0,0,0,0,0,0,0)';$S;BIDI;
    'TRIGGER_OUT':'(0,0,0,0,R13,0,0,0,0,0,0,0,0,0)';$S;BIDI;
    'USB2N_1':'(0,BY60,0,0,0,0,0,0,0,0,0,0,0,0)';$S;BIDI;
    'USB2N_10':'(0,BW65,0,0,0,0,0,0,0,0,0,0,0,0)';$S;BIDI;
    'USB2N_11':'(0,CA54,0,0,0,0,0,0,0,0,0,0,0,0)';$S;BIDI;
    'USB2N_12':'(0,BW67,0,0,0,0,0,0,0,0,0,0,0,0)';$S;BIDI;
    'USB2N_13':'(0,BY53,0,0,0,0,0,0,0,0,0,0,0,0)';$S;BIDI;
    'USB2N_14':'(0,BW68,0,0,0,0,0,0,0,0,0,0,0,0)';$S;BIDI;
    'USB2N_2':'(0,CA61,0,0,0,0,0,0,0,0,0,0,0,0)';$S;BIDI;
    'USB2N_3':'(0,CA59,0,0,0,0,0,0,0,0,0,0,0,0)';$S;BIDI;
    'USB2N_4':'(0,BY62,0,0,0,0,0,0,0,0,0,0,0,0)';$S;BIDI;
    'USB2N_5':'(0,BY58,0,0,0,0,0,0,0,0,0,0,0,0)';$S;BIDI;
    'USB2N_6':'(0,CA63,0,0,0,0,0,0,0,0,0,0,0,0)';$S;BIDI;
    'USB2N_7':'(0,CA57,0,0,0,0,0,0,0,0,0,0,0,0)';$S;BIDI;
    'USB2N_8':'(0,BY64,0,0,0,0,0,0,0,0,0,0,0,0)';$S;BIDI;
    'USB2N_9':'(0,BY55,0,0,0,0,0,0,0,0,0,0,0,0)';$S;BIDI;
    'USB2P_1':'(0,BV60,0,0,0,0,0,0,0,0,0,0,0,0)';$S;BIDI;
    'USB2P_10':'(0,BU65,0,0,0,0,0,0,0,0,0,0,0,0)';$S;BIDI;
    'USB2P_11':'(0,BW54,0,0,0,0,0,0,0,0,0,0,0,0)';$S;BIDI;
    'USB2P_12':'(0,BV66,0,0,0,0,0,0,0,0,0,0,0,0)';$S;BIDI;
    'USB2P_13':'(0,BV53,0,0,0,0,0,0,0,0,0,0,0,0)';$S;BIDI;
    'USB2P_14':'(0,BU67,0,0,0,0,0,0,0,0,0,0,0,0)';$S;BIDI;
    'USB2P_2':'(0,BW61,0,0,0,0,0,0,0,0,0,0,0,0)';$S;BIDI;
    'USB2P_3':'(0,BW59,0,0,0,0,0,0,0,0,0,0,0,0)';$S;BIDI;
    'USB2P_4':'(0,BV62,0,0,0,0,0,0,0,0,0,0,0,0)';$S;BIDI;
    'USB2P_5':'(0,BV58,0,0,0,0,0,0,0,0,0,0,0,0)';$S;BIDI;
    'USB2P_6':'(0,BW63,0,0,0,0,0,0,0,0,0,0,0,0)';$S;BIDI;
    'USB2P_7':'(0,BW57,0,0,0,0,0,0,0,0,0,0,0,0)';$S;BIDI;
    'USB2P_8':'(0,BV64,0,0,0,0,0,0,0,0,0,0,0,0)';$S;BIDI;
    'USB2P_9':'(0,BV55,0,0,0,0,0,0,0,0,0,0,0,0)';$S;BIDI;
    'USB2_COMP':'(0,BN70,0,0,0,0,0,0,0,0,0,0,0,0)';$S;BIDI;
    'USB2_VBUS':'(0,BR67,0,0,0,0,0,0,0,0,0,0,0,0)';$S;BIDI;
    'USB3_10_PCIE3_GBE_RXN':'(0,0,AV72,0,0,0,0,0,0,0,0,0,0,0)';$S;BIDI;
    'USB3_10_PCIE3_GBE_RXP':'(0,0,AV70,0,0,0,0,0,0,0,0,0,0,0)';$S;BIDI;
    'USB3_10_PCIE3_GBE_TXN':'(0,0,BH61,0,0,0,0,0,0,0,0,0,0,0)';$S;BIDI;
    'USB3_10_PCIE3_GBE_TXP':'(0,0,BK61,0,0,0,0,0,0,0,0,0,0,0)';$S;BIDI;
    'USB3_1_RXN':'(0,BK71,0,0,0,0,0,0,0,0,0,0,0,0)';$S;BIDI;
    'USB3_1_RXP':'(0,BK69,0,0,0,0,0,0,0,0,0,0,0,0)';$S;BIDI;
    'USB3_1_TXN':'(0,BL52,0,0,0,0,0,0,0,0,0,0,0,0)';$S;BIDI;
    'USB3_1_TXP':'(0,BK54,0,0,0,0,0,0,0,0,0,0,0,0)';$S;BIDI;
    'USB3_2_RXN':'(0,BJ72,0,0,0,0,0,0,0,0,0,0,0,0)';$S;BIDI;
    'USB3_2_RXP':'(0,BJ70,0,0,0,0,0,0,0,0,0,0,0,0)';$S;BIDI;
    'USB3_2_TXN':'(0,BL56,0,0,0,0,0,0,0,0,0,0,0,0)';$S;BIDI;
    'USB3_2_TXP':'(0,BJ56,0,0,0,0,0,0,0,0,0,0,0,0)';$S;BIDI;
    'USB3_3_RXN':'(0,BH71,0,0,0,0,0,0,0,0,0,0,0,0)';$S;BIDI;
    'USB3_3_RXP':'(0,BH69,0,0,0,0,0,0,0,0,0,0,0,0)';$S;BIDI;
    'USB3_3_TXN':'(0,BM54,0,0,0,0,0,0,0,0,0,0,0,0)';$S;BIDI;
    'USB3_3_TXP':'(0,BN56,0,0,0,0,0,0,0,0,0,0,0,0)';$S;BIDI;
    'USB3_4_RXN':'(0,BF72,0,0,0,0,0,0,0,0,0,0,0,0)';$S;BIDI;
    'USB3_4_RXP':'(0,BF70,0,0,0,0,0,0,0,0,0,0,0,0)';$S;BIDI;
    'USB3_4_TXN':'(0,BH58,0,0,0,0,0,0,0,0,0,0,0,0)';$S;BIDI;
    'USB3_4_TXP':'(0,BG56,0,0,0,0,0,0,0,0,0,0,0,0)';$S;BIDI;
    'USB3_5_RXN':'(0,BE71,0,0,0,0,0,0,0,0,0,0,0,0)';$S;BIDI;
    'USB3_5_RXP':'(0,BE69,0,0,0,0,0,0,0,0,0,0,0,0)';$S;BIDI;
    'USB3_5_TXN':'(0,BK58,0,0,0,0,0,0,0,0,0,0,0,0)';$S;BIDI;
    'USB3_5_TXP':'(0,BJ59,0,0,0,0,0,0,0,0,0,0,0,0)';$S;BIDI;
    'USB3_6_RXN':'(0,BD72,0,0,0,0,0,0,0,0,0,0,0,0)';$S;BIDI;
    'USB3_6_RXP':'(0,BD70,0,0,0,0,0,0,0,0,0,0,0,0)';$S;BIDI;
    'USB3_6_TXN':'(0,BL59,0,0,0,0,0,0,0,0,0,0,0,0)';$S;BIDI;
    'USB3_6_TXP':'(0,BM61,0,0,0,0,0,0,0,0,0,0,0,0)';$S;BIDI;
    'USB3_7_PCIE0_RXN':'(0,0,BA71,0,0,0,0,0,0,0,0,0,0,0)';$S;BIDI;
    'USB3_7_PCIE0_RXP':'(0,0,BA69,0,0,0,0,0,0,0,0,0,0,0)';$S;BIDI;
    'USB3_7_PCIE0_TXN':'(0,0,BR61,0,0,0,0,0,0,0,0,0,0,0)';$S;BIDI;
    'USB3_7_PCIE0_TXP':'(0,0,BN63,0,0,0,0,0,0,0,0,0,0,0)';$S;BIDI;
    'USB3_8_PCIE1_RXN':'(0,0,AY72,0,0,0,0,0,0,0,0,0,0,0)';$S;BIDI;
    'USB3_8_PCIE1_RXP':'(0,0,AY70,0,0,0,0,0,0,0,0,0,0,0)';$S;BIDI;
    'USB3_8_PCIE1_TXN':'(0,0,BM65,0,0,0,0,0,0,0,0,0,0,0)';$S;BIDI;
    'USB3_8_PCIE1_TXP':'(0,0,BR65,0,0,0,0,0,0,0,0,0,0,0)';$S;BIDI;
    'USB3_9_PCIE2_RXN':'(0,0,AW71,0,0,0,0,0,0,0,0,0,0,0)';$S;BIDI;
    'USB3_9_PCIE2_RXP':'(0,0,AW69,0,0,0,0,0,0,0,0,0,0,0)';$S;BIDI;
    'USB3_9_PCIE2_TXN':'(0,0,BK65,0,0,0,0,0,0,0,0,0,0,0)';$S;BIDI;
    'USB3_9_PCIE2_TXP':'(0,0,BL66,0,0,0,0,0,0,0,0,0,0,0)';$S;BIDI;
    'VCCA_CLKFILT_1P05'<4>:'(0,0,0,0,0,0,0,0,AE46,0,0,0,0,0)';
    'VCCA_CLKFILT_1P05'<3>:'(0,0,0,0,0,0,0,0,AJ48,0,0,0,0,0)';
    'VCCA_CLKFILT_1P05'<2>:'(0,0,0,0,0,0,0,0,AJ46,0,0,0,0,0)';
    'VCCA_CLKFILT_1P05'<1>:'(0,0,0,0,0,0,0,0,AG45,0,0,0,0,0)';
    'VCCA_CLKFILT_1P05'<0>:'(0,0,0,0,0,0,0,0,W50,0,0,0,0,0)';
    'VCCA_CLKUNF_1P05'<1>:'(0,0,0,0,0,0,0,0,U50,0,0,0,0,0)';
    'VCCA_CLKUNF_1P05'<0>:'(0,0,0,0,0,0,0,0,AH50,0,0,0,0,0)';
    'VCCA_CLKXTAL_1P05':'(0,0,0,0,0,0,0,0,AD50,0,0,0,0,0)';$S;
    'VCCA_PLL0_1P05':'(0,0,0,0,0,0,0,0,AG48,0,0,0,0,0)';$S;
    'VCCA_PLL1_1P05':'(0,0,0,0,0,0,0,0,AE45,0,0,0,0,0)';$S;
    'VCCMPHY_1P05'<13>:'(0,0,0,0,0,0,0,0,0,AE27,0,0,0,0)';
    'VCCMPHY_1P05'<12>:'(0,0,0,0,0,0,0,0,AK43,0,0,0,0,0)';
    'VCCMPHY_1P05'<11>:'(0,0,0,0,0,0,0,0,AK45,0,0,0,0,0)';
    'VCCMPHY_1P05'<10>:'(0,0,0,0,0,0,0,0,AM43,0,0,0,0,0)';
    'VCCMPHY_1P05'<9>:'(0,0,0,0,0,0,0,0,AM45,0,0,0,0,0)';
    'VCCMPHY_1P05'<8>:'(0,0,0,0,0,0,0,0,AP43,0,0,0,0,0)';
    'VCCMPHY_1P05'<7>:'(0,0,0,0,0,0,0,0,AP45,0,0,0,0,0)';
    'VCCMPHY_1P05'<6>:'(0,0,0,0,0,0,0,0,AT43,0,0,0,0,0)';
    'VCCMPHY_1P05'<5>:'(0,0,0,0,0,0,0,0,AT45,0,0,0,0,0)';
    'VCCMPHY_1P05'<4>:'(0,0,0,0,0,0,0,0,AU43,0,0,0,0,0)';
    'VCCMPHY_1P05'<3>:'(0,0,0,0,0,0,0,0,AU45,0,0,0,0,0)';
    'VCCMPHY_1P05'<2>:'(0,0,0,0,0,0,0,0,AJ43,0,0,0,0,0)';
    'VCCMPHY_1P05'<1>:'(0,0,0,0,0,0,0,0,AW43,0,0,0,0,0)';
    'VCCMPHY_1P05'<0>:'(0,0,0,0,0,0,0,0,AW45,0,0,0,0,0)';
    'VCCP10GBEPLL_1P05'<3>:'(0,0,0,0,0,0,0,0,BA39,0,0,0,0,0)';
    'VCCP10GBEPLL_1P05'<2>:'(0,0,0,0,0,0,0,0,BA41,0,0,0,0,0)';
    'VCCP10GBEPLL_1P05'<1>:'(0,0,0,0,0,0,0,0,BB40,0,0,0,0,0)';
    'VCCP10GBEPLL_1P05'<0>:'(0,0,0,0,0,0,0,0,BD38,0,0,0,0,0)';
    'VCCP10GBE_HV_1P8'<1>:'(0,0,0,0,0,0,0,0,BA27,0,0,0,0,0)';
    'VCCP10GBE_HV_1P8'<0>:'(0,0,0,0,0,0,0,0,BA29,0,0,0,0,0)';
    'VCCP10GBE_LV_1P05'<6>:'(0,0,0,0,0,0,0,0,BA30,0,0,0,0,0)';
    'VCCP10GBE_LV_1P05'<5>:'(0,0,0,0,0,0,0,0,BA32,0,0,0,0,0)';
    'VCCP10GBE_LV_1P05'<4>:'(0,0,0,0,0,0,0,0,BA34,0,0,0,0,0)';
    'VCCP10GBE_LV_1P05'<3>:'(0,0,0,0,0,0,0,0,BA36,0,0,0,0,0)';
    'VCCP10GBE_LV_1P05'<2>:'(0,0,0,0,0,0,0,0,BA37,0,0,0,0,0)';
    'VCCP10GBE_LV_1P05'<1>:'(0,0,0,0,0,0,0,0,BB33,0,0,0,0,0)';
    'VCCP10GBE_LV_1P05'<0>:'(0,0,0,0,0,0,0,0,BB37,0,0,0,0,0)';
    'VCCPDSW_3P3':'(0,0,0,0,0,0,0,0,AH24,0,0,0,0,0)';$S;
    'VCCPGPPA':'(0,0,0,0,0,0,0,0,AW24,0,0,0,0,0)';$S;
    'VCCPGPPB':'(0,0,0,0,0,0,0,0,BE26,0,0,0,0,0)';$S;
    'VCCPGPPC':'(0,0,0,0,0,0,0,0,BE40,0,0,0,0,0)';$S;
    'VCCPGPPD':'(0,0,0,0,0,0,0,0,BA43,0,0,0,0,0)';$S;
    'VCCPGPPE':'(0,0,0,0,0,0,0,0,BE44,0,0,0,0,0)';$S;
    'VCCPGPPF':'(0,0,0,0,0,0,0,0,AU27,0,0,0,0,0)';$S;
    'VCCPGPPG':'(0,0,0,0,0,0,0,0,BA26,0,0,0,0,0)';$S;
    'VCCPGPPH':'(0,0,0,0,0,0,0,0,BA24,0,0,0,0,0)';$S;
    'VCCPGPPJ':'(0,0,0,0,0,0,0,0,BB26,0,0,0,0,0)';$S;
    'VCCPGPPK':'(0,0,0,0,0,0,0,0,AU24,0,0,0,0,0)';$S;
    'VCCPGPP_1P8'<6>:'(0,0,0,0,0,0,0,0,AK24,0,0,0,0,0)';
    'VCCPGPP_1P8'<5>:'(0,0,0,0,0,0,0,0,AW27,0,0,0,0,0)';
    'VCCPGPP_1P8'<4>:'(0,0,0,0,0,0,0,0,AP29,0,0,0,0,0)';
    'VCCPGPP_1P8'<3>:'(0,0,0,0,0,0,0,0,AM29,0,0,0,0,0)';
    'VCCPGPP_1P8'<2>:'(0,0,0,0,0,0,0,0,AT29,0,0,0,0,0)';
    'VCCPGPP_1P8'<1>:'(0,0,0,0,0,0,0,0,AW29,0,0,0,0,0)';
    'VCCPGPP_1P8'<0>:'(0,0,0,0,0,0,0,0,AU29,0,0,0,0,0)';
    'VCCPHDA_1P8':'(0,0,0,0,0,0,0,0,AG27,0,0,0,0,0)';$S;
    'VCCPRIM_1P05'<19>:'(0,0,0,0,0,0,0,0,Y26,0,0,0,0,0)';
    'VCCPRIM_1P05'<18>:'(0,0,0,0,0,0,0,0,AA24,0,0,0,0,0)';
    'VCCPRIM_1P05'<17>:'(0,0,0,0,0,0,0,0,AK27,0,0,0,0,0)';
    'VCCPRIM_1P05'<16>:'(0,0,0,0,0,0,0,0,R42,0,0,0,0,0)';
    'VCCPRIM_1P05'<15>:'(0,0,0,0,0,0,0,0,R46,0,0,0,0,0)';
    'VCCPRIM_1P05'<14>:'(0,0,0,0,0,0,0,0,T44,0,0,0,0,0)';
    'VCCPRIM_1P05'<13>:'(0,0,0,0,0,0,0,0,U46,0,0,0,0,0)';
    'VCCPRIM_1P05'<12>:'(0,0,0,0,0,0,0,0,V44,0,0,0,0,0)';
    'VCCPRIM_1P05'<11>:'(0,0,0,0,0,0,0,0,Y45,0,0,0,0,0)';
    'VCCPRIM_1P05'<10>:'(0,0,0,0,0,0,0,0,Y46,0,0,0,0,0)';
    'VCCPRIM_1P05'<9>:'(0,0,0,0,0,0,0,0,AA45,0,0,0,0,0)';
    'VCCPRIM_1P05'<8>:'(0,0,0,0,0,0,0,0,AA46,0,0,0,0,0)';
    'VCCPRIM_1P05'<7>:'(0,0,0,0,0,0,0,0,AC26,0,0,0,0,0)';
    'VCCPRIM_1P05'<6>:'(0,0,0,0,0,0,0,0,AJ29,0,0,0,0,0)';
    'VCCPRIM_1P05'<5>:'(0,0,0,0,0,0,0,0,AM27,0,0,0,0,0)';
    'VCCPRIM_1P05'<4>:'(0,0,0,0,0,0,0,0,AT39,0,0,0,0,0)';
    'VCCPRIM_1P05'<3>:'(0,0,0,0,0,0,0,0,AU37,0,0,0,0,0)';
    'VCCPRIM_1P05'<2>:'(0,0,0,0,0,0,0,0,AU39,0,0,0,0,0)';
    'VCCPRIM_1P05'<1>:'(0,0,0,0,0,0,0,0,BE48,0,0,0,0,0)';
    'VCCPRIM_1P05'<0>:'(0,0,0,0,0,0,0,0,BF46,0,0,0,0,0)';
    'VCCPRIM_AVID'<62>:'(0,0,0,0,0,0,0,0,0,AK32,0,0,0,0)';
    'VCCPRIM_AVID'<61>:'(0,0,0,0,0,0,0,0,0,U31,0,0,0,0)';
    'VCCPRIM_AVID'<60>:'(0,0,0,0,0,0,0,0,0,U35,0,0,0,0)';
    'VCCPRIM_AVID'<59>:'(0,0,0,0,0,0,0,0,0,U38,0,0,0,0)';
    'VCCPRIM_AVID'<58>:'(0,0,0,0,0,0,0,0,0,V29,0,0,0,0)';
    'VCCPRIM_AVID'<57>:'(0,0,0,0,0,0,0,0,0,V33,0,0,0,0)';
    'VCCPRIM_AVID'<56>:'(0,0,0,0,0,0,0,0,0,V40,0,0,0,0)';
    'VCCPRIM_AVID'<55>:'(0,0,0,0,0,0,0,0,0,Y29,0,0,0,0)';
    'VCCPRIM_AVID'<54>:'(0,0,0,0,0,0,0,0,0,Y30,0,0,0,0)';
    'VCCPRIM_AVID'<53>:'(0,0,0,0,0,0,0,0,0,Y32,0,0,0,0)';
    'VCCPRIM_AVID'<52>:'(0,0,0,0,0,0,0,0,0,Y34,0,0,0,0)';
    'VCCPRIM_AVID'<51>:'(0,0,0,0,0,0,0,0,0,Y36,0,0,0,0)';
    'VCCPRIM_AVID'<50>:'(0,0,0,0,0,0,0,0,0,Y37,0,0,0,0)';
    'VCCPRIM_AVID'<49>:'(0,0,0,0,0,0,0,0,0,Y39,0,0,0,0)';
    'VCCPRIM_AVID'<48>:'(0,0,0,0,0,0,0,0,0,Y41,0,0,0,0)';
    'VCCPRIM_AVID'<47>:'(0,0,0,0,0,0,0,0,0,AA29,0,0,0,0)';
    'VCCPRIM_AVID'<46>:'(0,0,0,0,0,0,0,0,0,AA30,0,0,0,0)';
    'VCCPRIM_AVID'<45>:'(0,0,0,0,0,0,0,0,0,AA32,0,0,0,0)';
    'VCCPRIM_AVID'<44>:'(0,0,0,0,0,0,0,0,0,AA34,0,0,0,0)';
    'VCCPRIM_AVID'<43>:'(0,0,0,0,0,0,0,0,0,AA36,0,0,0,0)';
    'VCCPRIM_AVID'<42>:'(0,0,0,0,0,0,0,0,0,AA37,0,0,0,0)';
    'VCCPRIM_AVID'<41>:'(0,0,0,0,0,0,0,0,0,AA39,0,0,0,0)';
    'VCCPRIM_AVID'<40>:'(0,0,0,0,0,0,0,0,0,AA41,0,0,0,0)';
    'VCCPRIM_AVID'<39>:'(0,0,0,0,0,0,0,0,0,AC29,0,0,0,0)';
    'VCCPRIM_AVID'<38>:'(0,0,0,0,0,0,0,0,0,AC30,0,0,0,0)';
    'VCCPRIM_AVID'<37>:'(0,0,0,0,0,0,0,0,0,AC32,0,0,0,0)';
    'VCCPRIM_AVID'<36>:'(0,0,0,0,0,0,0,0,0,AC34,0,0,0,0)';
    'VCCPRIM_AVID'<35>:'(0,0,0,0,0,0,0,0,0,AC36,0,0,0,0)';
    'VCCPRIM_AVID'<34>:'(0,0,0,0,0,0,0,0,0,AC37,0,0,0,0)';
    'VCCPRIM_AVID'<33>:'(0,0,0,0,0,0,0,0,0,AC39,0,0,0,0)';
    'VCCPRIM_AVID'<32>:'(0,0,0,0,0,0,0,0,0,AC41,0,0,0,0)';
    'VCCPRIM_AVID'<31>:'(0,0,0,0,0,0,0,0,0,U27,0,0,0,0)';
    'VCCPRIM_AVID'<30>:'(0,0,0,0,0,0,0,0,0,AE30,0,0,0,0)';
    'VCCPRIM_AVID'<29>:'(0,0,0,0,0,0,0,0,0,AE32,0,0,0,0)';
    'VCCPRIM_AVID'<28>:'(0,0,0,0,0,0,0,0,0,AE34,0,0,0,0)';
    'VCCPRIM_AVID'<27>:'(0,0,0,0,0,0,0,0,0,AE36,0,0,0,0)';
    'VCCPRIM_AVID'<26>:'(0,0,0,0,0,0,0,0,0,AE37,0,0,0,0)';
    'VCCPRIM_AVID'<25>:'(0,0,0,0,0,0,0,0,0,AE39,0,0,0,0)';
    'VCCPRIM_AVID'<24>:'(0,0,0,0,0,0,0,0,0,AE41,0,0,0,0)';
    'VCCPRIM_AVID'<23>:'(0,0,0,0,0,0,0,0,0,AG32,0,0,0,0)';
    'VCCPRIM_AVID'<22>:'(0,0,0,0,0,0,0,0,0,AG34,0,0,0,0)';
    'VCCPRIM_AVID'<21>:'(0,0,0,0,0,0,0,0,0,AG36,0,0,0,0)';
    'VCCPRIM_AVID'<20>:'(0,0,0,0,0,0,0,0,0,AG37,0,0,0,0)';
    'VCCPRIM_AVID'<19>:'(0,0,0,0,0,0,0,0,0,AG39,0,0,0,0)';
    'VCCPRIM_AVID'<18>:'(0,0,0,0,0,0,0,0,0,AK34,0,0,0,0)';
    'VCCPRIM_AVID'<17>:'(0,0,0,0,0,0,0,0,0,AK37,0,0,0,0)';
    'VCCPRIM_AVID'<16>:'(0,0,0,0,0,0,0,0,0,AK39,0,0,0,0)';
    'VCCPRIM_AVID'<15>:'(0,0,0,0,0,0,0,0,0,AM32,0,0,0,0)';
    'VCCPRIM_AVID'<14>:'(0,0,0,0,0,0,0,0,0,AM34,0,0,0,0)';
    'VCCPRIM_AVID'<13>:'(0,0,0,0,0,0,0,0,0,AM36,0,0,0,0)';
    'VCCPRIM_AVID'<12>:'(0,0,0,0,0,0,0,0,0,AM37,0,0,0,0)';
    'VCCPRIM_AVID'<11>:'(0,0,0,0,0,0,0,0,0,AM39,0,0,0,0)';
    'VCCPRIM_AVID'<10>:'(0,0,0,0,0,0,0,0,0,AP32,0,0,0,0)';
    'VCCPRIM_AVID'<9>:'(0,0,0,0,0,0,0,0,0,AP34,0,0,0,0)';
    'VCCPRIM_AVID'<8>:'(0,0,0,0,0,0,0,0,0,AP36,0,0,0,0)';
    'VCCPRIM_AVID'<7>:'(0,0,0,0,0,0,0,0,0,AP37,0,0,0,0)';
    'VCCPRIM_AVID'<6>:'(0,0,0,0,0,0,0,0,0,AP39,0,0,0,0)';
    'VCCPRIM_AVID'<5>:'(0,0,0,0,0,0,0,0,0,AT32,0,0,0,0)';
    'VCCPRIM_AVID'<4>:'(0,0,0,0,0,0,0,0,0,AT34,0,0,0,0)';
    'VCCPRIM_AVID'<3>:'(0,0,0,0,0,0,0,0,0,AT36,0,0,0,0)';
    'VCCPRIM_AVID'<2>:'(0,0,0,0,0,0,0,0,0,AU32,0,0,0,0)';
    'VCCPRIM_AVID'<1>:'(0,0,0,0,0,0,0,0,0,AU34,0,0,0,0)';
    'VCCPRIM_AVID'<0>:'(0,0,0,0,0,0,0,0,0,AU36,0,0,0,0)';
    'VCCPRIM_AVID_QAT_SENSE':'(0,0,0,0,0,0,0,0,0,V37,0,0,0,0)';$S;
    'VCCPRIM_AVID_SENSE':'(0,0,0,0,0,0,0,0,0,AK36,0,0,0,0)';$S;BIDI;
    'VCCPRTC':'(0,0,0,0,0,0,0,0,AJ27,0,0,0,0,0)';$S;
    'VCCPRTCPRIM_3P3':'(0,0,0,0,0,0,0,0,AG29,0,0,0,0,0)';$S;
    'VCCPSPI':'(0,0,0,0,0,0,0,0,AR24,0,0,0,0,0)';$S;
    'VCCPSPI_1P8':'(0,0,0,0,0,0,0,0,AK29,0,0,0,0,0)';$S;
    'VCCPUSBDSW_3P3':'(0,0,0,0,0,0,0,0,BA48,0,0,0,0,0)';$S;
    'VCCP_1P8'<1>:'(0,0,0,0,0,0,0,0,AE26,0,0,0,0,0)';
    'VCCP_1P8'<0>:'(0,0,0,0,0,0,0,0,BD46,0,0,0,0,0)';
    'VCCP_3P3'<5>:'(0,0,0,0,0,0,0,0,AN24,0,0,0,0,0)';
    'VCCP_3P3'<2>:'(0,0,0,0,0,0,0,0,AD24,0,0,0,0,0)';
    'VCCP_3P3'<1>:'(0,0,0,0,0,0,0,0,BA45,0,0,0,0,0)';
    'VCCP_3P3'<0>:'(0,0,0,0,0,0,0,0,BA46,0,0,0,0,0)';
    'VCCP_HSIOPLLUNF_1P05':'(0,0,0,0,0,0,0,0,AT48,0,0,0,0,0)';$S;
    'VCCP_HSIOPLL_1P05'<3>:'(0,0,0,0,0,0,0,0,AP48,0,0,0,0,0)';
    'VCCP_HSIOPLL_1P05'<2>:'(0,0,0,0,0,0,0,0,AU48,0,0,0,0,0)';
    'VCCP_HSIOPLL_1P05'<0>:'(0,0,0,0,0,0,0,0,AW48,0,0,0,0,0)';
    'VCCP_UPPLLUNF_1P05':'(0,0,0,0,0,0,0,0,AM48,0,0,0,0,0)';$S;
    'VCCP_UPPLL_1P05'<2>:'(0,0,0,0,0,0,0,0,AK50,0,0,0,0,0)';
    'VCCP_UPPLL_1P05'<0>:'(0,0,0,0,0,0,0,0,AN50,0,0,0,0,0)';
    'VCCRTCEXT':'(0,0,0,0,0,0,0,0,AG22,0,0,0,0,0)';$S;
    'VSS'<494>:'(0,0,0,0,0,0,0,0,0,0,BP69,0,0,0)';
    'VSS'<493>:'(0,0,0,0,0,0,0,0,0,0,BT69,0,0,0)';
    'VSS'<492>:'(0,0,0,0,0,0,0,0,0,0,BU70,0,0,0)';
    'VSS'<491>:'(0,0,0,0,0,0,0,0,0,0,BR70,0,0,0)';
    'VSS'<490>:'(0,0,0,0,0,0,0,0,0,0,F70,0,0,0)';
    'VSS'<489>:'(0,0,0,0,0,0,0,0,0,0,E70,0,0,0)';
    'VSS'<488>:'(0,0,0,0,0,0,0,0,0,0,BU3,0,0,0)';
    'VSS'<487>:'(0,0,0,0,0,0,0,0,0,0,BR3,0,0,0)';
    'VSS'<486>:'(0,0,0,0,0,0,0,0,0,0,F3,0,0,0)';
    'VSS'<485>:'(0,0,0,0,0,0,0,0,0,0,E3,0,0,0)';
    'VSS'<484>:'(0,0,0,0,0,0,0,0,0,0,A5,0,0,0)';
    'VSS'<483>:'(0,0,0,0,0,0,0,0,0,0,A7,0,0,0)';
    'VSS'<482>:'(0,0,0,0,0,0,0,0,0,0,A9,0,0,0)';
    'VSS'<481>:'(0,0,0,0,0,0,0,0,0,0,A65,0,0,0)';
    'VSS'<480>:'(0,0,0,0,0,0,0,0,0,0,A66,0,0,0)';
    'VSS'<479>:'(0,0,0,0,0,0,0,0,0,0,A68,0,0,0)';
    'VSS'<478>:'(0,0,0,0,0,0,0,0,0,0,J1,0,0,0)';
    'VSS'<477>:'(0,0,0,0,0,0,0,0,0,0,J72,0,0,0)';
    'VSS'<476>:'(0,0,0,0,0,0,0,0,0,0,BN1,0,0,0)';
    'VSS'<475>:'(0,0,0,0,0,0,0,0,0,0,BN72,0,0,0)';
    'VSS'<474>:'(0,0,0,0,0,0,0,0,0,0,CA68,0,0,0)';
    'VSS'<473>:'(0,0,0,0,0,0,0,0,0,0,CA66,0,0,0)';
    'VSS'<472>:'(0,0,0,0,0,0,0,0,0,0,CA65,0,0,0)';
    'VSS'<471>:'(0,0,0,0,0,0,0,0,0,0,CA9,0,0,0)';
    'VSS'<470>:'(0,0,0,0,0,0,0,0,0,0,CA7,0,0,0)';
    'VSS'<469>:'(0,0,0,0,0,0,0,0,0,0,CA5,0,0,0)';
    'VSS'<468>:'(0,0,0,0,0,0,0,0,0,0,A70,0,0,0)';
    'VSS'<467>:'(0,0,0,0,0,0,0,0,0,0,CA3,0,0,0)';
    'VSS'<466>:'(0,0,0,0,0,0,0,0,0,0,BW1,0,0,0)';
    'VSS'<465>:'(0,0,0,0,0,0,0,0,0,0,BU1,0,0,0)';
    'VSS'<464>:'(0,0,0,0,0,0,0,0,0,0,BR1,0,0,0)';
    'VSS'<463>:'(0,0,0,0,0,0,0,0,0,0,C3,0,0,0)';
    'VSS'<462>:'(0,0,0,0,0,0,0,0,0,0,C72,0,0,0)';
    'VSS'<461>:'(0,0,0,0,0,0,0,0,0,0,E1,0,0,0)';
    'VSS'<460>:'(0,0,0,0,0,0,0,0,0,0,E72,0,0,0)';
    'VSS'<459>:'(0,0,0,0,0,0,0,0,0,0,G1,0,0,0)';
    'VSS'<458>:'(0,0,0,0,0,0,0,0,0,0,G72,0,0,0)';
    'VSS'<457>:'(0,0,0,0,0,0,0,0,0,0,BR72,0,0,0)';
    'VSS'<456>:'(0,0,0,0,0,0,0,0,0,0,BU72,0,0,0)';
    'VSS'<455>:'(0,0,0,0,0,0,0,0,0,0,BW70,0,0,0)';
    'VSS'<454>:'(0,0,0,0,0,0,0,0,0,0,BW72,0,0,0)';
    'VSS'<453>:'(0,0,0,0,0,0,0,0,0,0,CA70,0,0,0)';
    'VSS'<452>:'(0,0,0,0,0,0,0,0,0,0,BB48,0,0,0)';
    'VSS'<451>:'(0,0,0,0,0,0,0,0,0,0,AT37,0,0,0)';
    'VSS'<450>:'(0,0,0,0,0,0,0,0,0,0,Y72,0,0,0)';
    'VSS'<449>:'(0,0,0,0,0,0,0,0,0,0,Y70,0,0,0)';
    'VSS'<448>:'(0,0,0,0,0,0,0,0,0,0,A18,0,0,0)';
    'VSS'<447>:'(0,0,0,0,0,0,0,0,0,0,A22,0,0,0)';
    'VSS'<446>:'(0,0,0,0,0,0,0,0,0,0,A30,0,0,0)';
    'VSS'<445>:'(0,0,0,0,0,0,0,0,0,0,A34,0,0,0)';
    'VSS'<444>:'(0,0,0,0,0,0,0,0,0,0,A37,0,0,0)';
    'VSS'<443>:'(0,0,0,0,0,0,0,0,0,0,A41,0,0,0)';
    'VSS'<442>:'(0,0,0,0,0,0,0,0,0,0,B12,0,0,0)';
    'VSS'<441>:'(0,0,0,0,0,0,0,0,0,0,B19,0,0,0)';
    'VSS'<440>:'(0,0,0,0,0,0,0,0,0,0,B25,0,0,0)';
    'VSS'<439>:'(0,0,0,0,0,0,0,0,0,0,B27,0,0,0)';
    'VSS'<438>:'(0,0,0,0,0,0,0,0,0,0,B47,0,0,0)';
    'VSS'<437>:'(0,0,0,0,0,0,0,0,0,0,C22,0,0,0)';
    'VSS'<436>:'(0,0,0,0,0,0,0,0,0,0,C30,0,0,0)';
    'VSS'<435>:'(0,0,0,0,0,0,0,0,0,0,C34,0,0,0)';
    'VSS'<434>:'(0,0,0,0,0,0,0,0,0,0,C37,0,0,0)';
    'VSS'<433>:'(0,0,0,0,0,0,0,0,0,0,C41,0,0,0)';
    'VSS'<432>:'(0,0,0,0,0,0,0,0,0,0,C65,0,0,0)';
    'VSS'<431>:'(0,0,0,0,0,0,0,0,0,0,D12,0,0,0)';
    'VSS'<430>:'(0,0,0,0,0,0,0,0,0,0,D16,0,0,0)';
    'VSS'<429>:'(0,0,0,0,0,0,0,0,0,0,D19,0,0,0)';
    'VSS'<428>:'(0,0,0,0,0,0,0,0,0,0,D25,0,0,0)';
    'VSS'<427>:'(0,0,0,0,0,0,0,0,0,0,D27,0,0,0)';
    'VSS'<426>:'(0,0,0,0,0,0,0,0,0,0,E59,0,0,0)';
    'VSS'<425>:'(0,0,0,0,0,0,0,0,0,0,E65,0,0,0)';
    'VSS'<424>:'(0,0,0,0,0,0,0,0,0,0,D47,0,0,0)';
    'VSS'<423>:'(0,0,0,0,0,0,0,0,0,0,E11,0,0,0)';
    'VSS'<422>:'(0,0,0,0,0,0,0,0,0,0,E13,0,0,0)';
    'VSS'<421>:'(0,0,0,0,0,0,0,0,0,0,E15,0,0,0)';
    'VSS'<420>:'(0,0,0,0,0,0,0,0,0,0,E20,0,0,0)';
    'VSS'<419>:'(0,0,0,0,0,0,0,0,0,0,E22,0,0,0)';
    'VSS'<418>:'(0,0,0,0,0,0,0,0,0,0,E24,0,0,0)';
    'VSS'<417>:'(0,0,0,0,0,0,0,0,0,0,E26,0,0,0)';
    'VSS'<416>:'(0,0,0,0,0,0,0,0,0,0,E28,0,0,0)';
    'VSS'<415>:'(0,0,0,0,0,0,0,0,0,0,E30,0,0,0)';
    'VSS'<414>:'(0,0,0,0,0,0,0,0,0,0,E32,0,0,0)';
    'VSS'<413>:'(0,0,0,0,0,0,0,0,0,0,E34,0,0,0)';
    'VSS'<412>:'(0,0,0,0,0,0,0,0,0,0,E37,0,0,0)';
    'VSS'<411>:'(0,0,0,0,0,0,0,0,0,0,E39,0,0,0)';
    'VSS'<410>:'(0,0,0,0,0,0,0,0,0,0,E41,0,0,0)';
    'VSS'<409>:'(0,0,0,0,0,0,0,0,0,0,E43,0,0,0)';
    'VSS'<408>:'(0,0,0,0,0,0,0,0,0,0,E45,0,0,0)';
    'VSS'<407>:'(0,0,0,0,0,0,0,0,0,0,E48,0,0,0)';
    'VSS'<406>:'(0,0,0,0,0,0,0,0,0,0,E50,0,0,0)';
    'VSS'<405>:'(0,0,0,0,0,0,0,0,0,0,E52,0,0,0)';
    'VSS'<404>:'(0,0,0,0,0,0,0,0,0,0,E54,0,0,0)';
    'VSS'<403>:'(0,0,0,0,0,0,0,0,0,0,E57,0,0,0)';
    'VSS'<402>:'(0,0,0,0,0,0,0,0,0,0,E6,0,0,0)';
    'VSS'<401>:'(0,0,0,0,0,0,0,0,0,0,E61,0,0,0)';
    'VSS'<400>:'(0,0,0,0,0,0,0,0,0,0,E63,0,0,0)';
    'VSS'<399>:'(0,0,0,0,0,0,0,0,0,0,G59,0,0,0)';
    'VSS'<398>:'(0,0,0,0,0,0,0,0,0,0,E9,0,0,0)';
    'VSS'<397>:'(0,0,0,0,0,0,0,0,0,0,G22,0,0,0)';
    'VSS'<396>:'(0,0,0,0,0,0,0,0,0,0,G29,0,0,0)';
    'VSS'<395>:'(0,0,0,0,0,0,0,0,0,0,G37,0,0,0)';
    'VSS'<394>:'(0,0,0,0,0,0,0,0,0,0,G48,0,0,0)';
    'VSS'<393>:'(0,0,0,0,0,0,0,0,0,0,G6,0,0,0)';
    'VSS'<392>:'(0,0,0,0,0,0,0,0,0,0,G63,0,0,0)';
    'VSS'<391>:'(0,0,0,0,0,0,0,0,0,0,G66,0,0,0)';
    'VSS'<390>:'(0,0,0,0,0,0,0,0,0,0,H58,0,0,0)';
    'VSS'<389>:'(0,0,0,0,0,0,0,0,0,0,J29,0,0,0)';
    'VSS'<388>:'(0,0,0,0,0,0,0,0,0,0,J5,0,0,0)';
    'VSS'<387>:'(0,0,0,0,0,0,0,0,0,0,J7,0,0,0)';
    'VSS'<386>:'(0,0,0,0,0,0,0,0,0,0,H65,0,0,0)';
    'VSS'<385>:'(0,0,0,0,0,0,0,0,0,0,J11,0,0,0)';
    'VSS'<384>:'(0,0,0,0,0,0,0,0,0,0,J15,0,0,0)';
    'VSS'<383>:'(0,0,0,0,0,0,0,0,0,0,J22,0,0,0)';
    'VSS'<382>:'(0,0,0,0,0,0,0,0,0,0,J37,0,0,0)';
    'VSS'<381>:'(0,0,0,0,0,0,0,0,0,0,J44,0,0,0)';
    'VSS'<380>:'(0,0,0,0,0,0,0,0,0,0,J59,0,0,0)';
    'VSS'<379>:'(0,0,0,0,0,0,0,0,0,0,J68,0,0,0)';
    'VSS'<378>:'(0,0,0,0,0,0,0,0,0,0,J70,0,0,0)';
    'VSS'<377>:'(0,0,0,0,0,0,0,0,0,0,K54,0,0,0)';
    'VSS'<376>:'(0,0,0,0,0,0,0,0,0,0,K69,0,0,0)';
    'VSS'<375>:'(0,0,0,0,0,0,0,0,0,0,K71,0,0,0)';
    'VSS'<374>:'(0,0,0,0,0,0,0,0,0,0,L5,0,0,0)';
    'VSS'<373>:'(0,0,0,0,0,0,0,0,0,0,L68,0,0,0)';
    'VSS'<372>:'(0,0,0,0,0,0,0,0,0,0,M2,0,0,0)';
    'VSS'<371>:'(0,0,0,0,0,0,0,0,0,0,M22,0,0,0)';
    'VSS'<370>:'(0,0,0,0,0,0,0,0,0,0,M26,0,0,0)';
    'VSS'<369>:'(0,0,0,0,0,0,0,0,0,0,M29,0,0,0)';
    'VSS'<368>:'(0,0,0,0,0,0,0,0,0,0,M33,0,0,0)';
    'VSS'<367>:'(0,0,0,0,0,0,0,0,0,0,M37,0,0,0)';
    'VSS'<366>:'(0,0,0,0,0,0,0,0,0,0,M4,0,0,0)';
    'VSS'<365>:'(0,0,0,0,0,0,0,0,0,0,M40,0,0,0)';
    'VSS'<364>:'(0,0,0,0,0,0,0,0,0,0,N42,0,0,0)';
    'VSS'<363>:'(0,0,0,0,0,0,0,0,0,0,N50,0,0,0)';
    'VSS'<362>:'(0,0,0,0,0,0,0,0,0,0,M44,0,0,0)';
    'VSS'<361>:'(0,0,0,0,0,0,0,0,0,0,M48,0,0,0)';
    'VSS'<360>:'(0,0,0,0,0,0,0,0,0,0,N13,0,0,0)';
    'VSS'<359>:'(0,0,0,0,0,0,0,0,0,0,N17,0,0,0)';
    'VSS'<358>:'(0,0,0,0,0,0,0,0,0,0,N20,0,0,0)';
    'VSS'<357>:'(0,0,0,0,0,0,0,0,0,0,N24,0,0,0)';
    'VSS'<356>:'(0,0,0,0,0,0,0,0,0,0,N27,0,0,0)';
    'VSS'<355>:'(0,0,0,0,0,0,0,0,0,0,N31,0,0,0)';
    'VSS'<354>:'(0,0,0,0,0,0,0,0,0,0,0,N35,0,0)';
    'VSS'<353>:'(0,0,0,0,0,0,0,0,0,0,0,N38,0,0)';
    'VSS'<352>:'(0,0,0,0,0,0,0,0,0,0,0,N46,0,0)';
    'VSS'<351>:'(0,0,0,0,0,0,0,0,0,0,0,N5,0,0)';
    'VSS'<350>:'(0,0,0,0,0,0,0,0,0,0,0,R38,0,0)';
    'VSS'<349>:'(0,0,0,0,0,0,0,0,0,0,0,N68,0,0)';
    'VSS'<348>:'(0,0,0,0,0,0,0,0,0,0,0,N9,0,0)';
    'VSS'<347>:'(0,0,0,0,0,0,0,0,0,0,0,AE43,0,0)';
    'VSS'<346>:'(0,0,0,0,0,0,0,0,0,0,0,P63,0,0)';
    'VSS'<345>:'(0,0,0,0,0,0,0,0,0,0,0,R27,0,0)';
    'VSS'<344>:'(0,0,0,0,0,0,0,0,0,0,0,U42,0,0)';
    'VSS'<343>:'(0,0,0,0,0,0,0,0,0,0,0,R5,0,0)';
    'VSS'<342>:'(0,0,0,0,0,0,0,0,0,0,0,R50,0,0)';
    'VSS'<341>:'(0,0,0,0,0,0,0,0,0,0,0,R54,0,0)';
    'VSS'<340>:'(0,0,0,0,0,0,0,0,0,0,0,T56,0,0)';
    'VSS'<339>:'(0,0,0,0,0,0,0,0,0,0,0,R58,0,0)';
    'VSS'<338>:'(0,0,0,0,0,0,0,0,0,0,0,R68,0,0)';
    'VSS'<337>:'(0,0,0,0,0,0,0,0,0,0,0,T11,0,0)';
    'VSS'<336>:'(0,0,0,0,0,0,0,0,0,0,0,T15,0,0)';
    'VSS'<335>:'(0,0,0,0,0,0,0,0,0,0,0,T18,0,0)';
    'VSS'<334>:'(0,0,0,0,0,0,0,0,0,0,0,T22,0,0)';
    'VSS'<333>:'(0,0,0,0,0,0,0,0,0,0,0,T26,0,0)';
    'VSS'<332>:'(0,0,0,0,0,0,0,0,0,0,0,T29,0,0)';
    'VSS'<331>:'(0,0,0,0,0,0,0,0,0,0,0,T33,0,0)';
    'VSS'<330>:'(0,0,0,0,0,0,0,0,0,0,0,T37,0,0)';
    'VSS'<329>:'(0,0,0,0,0,0,0,0,0,0,0,T40,0,0)';
    'VSS'<328>:'(0,0,0,0,0,0,0,0,0,0,0,AJ45,0,0)';
    'VSS'<327>:'(0,0,0,0,0,0,0,0,0,0,0,T48,0,0)';
    'VSS'<326>:'(0,0,0,0,0,0,0,0,0,0,0,T52,0,0)';
    'VSS'<325>:'(0,0,0,0,0,0,0,0,0,0,0,T66,0,0)';
    'VSS'<324>:'(0,0,0,0,0,0,0,0,0,0,0,T7,0,0)';
    'VSS'<323>:'(0,0,0,0,0,0,0,0,0,0,0,AF50,0,0)';
    'VSS'<322>:'(0,0,0,0,0,0,0,0,0,0,0,AG46,0,0)';
    'VSS'<321>:'(0,0,0,0,0,0,0,0,0,0,0,U58,0,0)';
    'VSS'<320>:'(0,0,0,0,0,0,0,0,0,0,0,V26,0,0)';
    'VSS'<319>:'(0,0,0,0,0,0,0,0,0,0,0,V48,0,0)';
    'VSS'<318>:'(0,0,0,0,0,0,0,0,0,0,0,V5,0,0)';
    'VSS'<317>:'(0,0,0,0,0,0,0,0,0,0,0,V52,0,0)';
    'VSS'<316>:'(0,0,0,0,0,0,0,0,0,0,0,W58,0,0)';
    'VSS'<315>:'(0,0,0,0,0,0,0,0,0,0,0,V66,0,0)';
    'VSS'<314>:'(0,0,0,0,0,0,0,0,0,0,0,V68,0,0)';
    'VSS'<313>:'(0,0,0,0,0,0,0,0,0,0,0,W13,0,0)';
    'VSS'<312>:'(0,0,0,0,0,0,0,0,0,0,0,W17,0,0)';
    'VSS'<311>:'(0,0,0,0,0,0,0,0,0,0,0,W20,0,0)';
    'VSS'<310>:'(0,0,0,0,0,0,0,0,0,0,0,W24,0,0)';
    'VSS'<309>:'(0,0,0,0,0,0,0,0,0,0,0,AA50,0,0)';
    'VSS'<308>:'(0,0,0,0,0,0,0,0,0,0,0,Y43,0,0)';
    'VSS'<307>:'(0,0,0,0,0,0,0,0,0,0,0,W61,0,0)';
    'VSS'<306>:'(0,0,0,0,0,0,0,0,0,0,0,W9,0,0)';
    'VSS'<305>:'(0,0,0,0,0,0,0,0,0,0,0,Y22,0,0)';
    'VSS'<304>:'(0,0,0,0,0,0,0,0,0,0,0,Y27,0,0)';
    'VSS'<303>:'(0,0,0,0,0,0,0,0,0,0,0,Y48,0,0)';
    'VSS'<302>:'(0,0,0,0,0,0,0,0,0,0,0,Y5,0,0)';
    'VSS'<301>:'(0,0,0,0,0,0,0,0,0,0,0,Y52,0,0)';
    'VSS'<300>:'(0,0,0,0,0,0,0,0,0,0,0,Y59,0,0)';
    'VSS'<299>:'(0,0,0,0,0,0,0,0,0,0,0,Y63,0,0)';
    'VSS'<298>:'(0,0,0,0,0,0,0,0,0,0,0,Y68,0,0)';
    'VSS'<297>:'(0,0,0,0,0,0,0,0,0,0,0,AA26,0,0)';
    'VSS'<296>:'(0,0,0,0,0,0,0,0,0,0,0,AA27,0,0)';
    'VSS'<295>:'(0,0,0,0,0,0,0,0,0,0,0,AA43,0,0)';
    'VSS'<294>:'(0,0,0,0,0,0,0,0,0,0,0,AA48,0,0)';
    'VSS'<293>:'(0,0,0,0,0,0,0,0,0,0,0,AB5,0,0)';
    'VSS'<292>:'(0,0,0,0,0,0,0,0,0,0,0,AB68,0,0)';
    'VSS'<291>:'(0,0,0,0,0,0,0,0,0,0,0,AB70,0,0)';
    'VSS'<290>:'(0,0,0,0,0,0,0,0,0,0,0,AB72,0,0)';
    'VSS'<289>:'(0,0,0,0,0,0,0,0,0,0,0,AC11,0,0)';
    'VSS'<288>:'(0,0,0,0,0,0,0,0,0,0,0,AC15,0,0)';
    'VSS'<287>:'(0,0,0,0,0,0,0,0,0,0,0,AC18,0,0)';
    'VSS'<286>:'(0,0,0,0,0,0,0,0,0,0,0,AC22,0,0)';
    'VSS'<285>:'(0,0,0,0,0,0,0,0,0,0,0,AC45,0,0)';
    'VSS'<284>:'(0,0,0,0,0,0,0,0,0,0,0,AD58,0,0)';
    'VSS'<283>:'(0,0,0,0,0,0,0,0,0,0,0,AC27,0,0)';
    'VSS'<282>:'(0,0,0,0,0,0,0,0,0,0,0,AC43,0,0)';
    'VSS'<281>:'(0,0,0,0,0,0,0,0,0,0,0,AC46,0,0)';
    'VSS'<280>:'(0,0,0,0,0,0,0,0,0,0,0,AC48,0,0)';
    'VSS'<279>:'(0,0,0,0,0,0,0,0,0,0,0,AC52,0,0)';
    'VSS'<278>:'(0,0,0,0,0,0,0,0,0,0,0,AC59,0,0)';
    'VSS'<277>:'(0,0,0,0,0,0,0,0,0,0,0,AC63,0,0)';
    'VSS'<276>:'(0,0,0,0,0,0,0,0,0,0,0,AC66,0,0)';
    'VSS'<275>:'(0,0,0,0,0,0,0,0,0,0,0,AC7,0,0)';
    'VSS'<274>:'(0,0,0,0,0,0,0,0,0,0,0,AD5,0,0)';
    'VSS'<273>:'(0,0,0,0,0,0,0,0,0,0,0,AD65,0,0)';
    'VSS'<272>:'(0,0,0,0,0,0,0,0,0,0,0,AD68,0,0)';
    'VSS'<271>:'(0,0,0,0,0,0,0,0,0,0,0,AE29,0,0)';
    'VSS'<270>:'(0,0,0,0,0,0,0,0,0,0,0,J18,0,0)';
    'VSS'<269>:'(0,0,0,0,0,0,0,0,0,0,0,AE48,0,0)';
    'VSS'<268>:'(0,0,0,0,0,0,0,0,0,0,0,AE52,0,0)';
    'VSS'<267>:'(0,0,0,0,0,0,0,0,0,0,0,AE56,0,0)';
    'VSS'<266>:'(0,0,0,0,0,0,0,0,0,0,0,AE59,0,0)';
    'VSS'<265>:'(0,0,0,0,0,0,0,0,0,0,0,AE63,0,0)';
    'VSS'<264>:'(0,0,0,0,0,0,0,0,0,0,0,AE66,0,0)';
    'VSS'<263>:'(0,0,0,0,0,0,0,0,0,0,0,AF1,0,0)';
    'VSS'<262>:'(0,0,0,0,0,0,0,0,0,0,0,AF13,0,0)';
    'VSS'<261>:'(0,0,0,0,0,0,0,0,0,0,0,AF5,0,0)';
    'VSS'<260>:'(0,0,0,0,0,0,0,0,0,0,0,AF9,0,0)';
    'VSS'<259>:'(0,0,0,0,0,0,0,0,0,0,0,AF17,0,0)';
    'VSS'<258>:'(0,0,0,0,0,0,0,0,0,0,0,AF24,0,0)';
    'VSS'<257>:'(0,0,0,0,0,0,0,0,0,0,0,AF3,0,0)';
    'VSS'<256>:'(0,0,0,0,0,0,0,0,0,0,0,AF68,0,0)';
    'VSS'<255>:'(0,0,0,0,0,0,0,0,0,0,0,AG26,0,0)';
    'VSS'<254>:'(0,0,0,0,0,0,0,0,0,0,0,AG30,0,0)';
    'VSS'<253>:'(0,0,0,0,0,0,0,0,0,0,0,AG41,0,0)';
    'VSS'<252>:'(0,0,0,0,0,0,0,0,0,0,0,AG43,0,0)';
    'VSS'<251>:'(0,0,0,0,0,0,0,0,0,0,0,AG52,0,0)';
    'VSS'<250>:'(0,0,0,0,0,0,0,0,0,0,0,AG56,0,0)';
    'VSS'<249>:'(0,0,0,0,0,0,0,0,0,0,0,AG59,0,0)';
    'VSS'<248>:'(0,0,0,0,0,0,0,0,0,0,0,AG66,0,0)';
    'VSS'<247>:'(0,0,0,0,0,0,0,0,0,0,0,AH20,0,0)';
    'VSS'<246>:'(0,0,0,0,0,0,0,0,0,0,0,AJ11,0,0)';
    'VSS'<245>:'(0,0,0,0,0,0,0,0,0,0,0,AJ32,0,0)';
    'VSS'<244>:'(0,0,0,0,0,0,0,0,0,0,0,AJ56,0,0)';
    'VSS'<243>:'(0,0,0,0,0,0,0,0,0,0,0,AK30,0,0)';
    'VSS'<242>:'(0,0,0,0,0,0,0,0,0,0,0,AJ15,0,0)';
    'VSS'<241>:'(0,0,0,0,0,0,0,0,0,0,0,AJ18,0,0)';
    'VSS'<240>:'(0,0,0,0,0,0,0,0,0,0,0,AJ22,0,0)';
    'VSS'<239>:'(0,0,0,0,0,0,0,0,0,0,0,AJ26,0,0)';
    'VSS'<238>:'(0,0,0,0,0,0,0,0,0,0,0,AJ30,0,0)';
    'VSS'<237>:'(0,0,0,0,0,0,0,0,0,0,0,AJ34,0,0)';
    'VSS'<236>:'(0,0,0,0,0,0,0,0,0,0,0,AJ36,0,0)';
    'VSS'<235>:'(0,0,0,0,0,0,0,0,0,0,0,AJ37,0,0)';
    'VSS'<234>:'(0,0,0,0,0,0,0,0,0,0,0,AJ39,0,0)';
    'VSS'<233>:'(0,0,0,0,0,0,0,0,0,0,0,AJ41,0,0)';
    'VSS'<232>:'(0,0,0,0,0,0,0,0,0,0,0,AJ5,0,0)';
    'VSS'<231>:'(0,0,0,0,0,0,0,0,0,0,0,AJ52,0,0)';
    'VSS'<230>:'(0,0,0,0,0,0,0,0,0,0,0,AJ59,0,0)';
    'VSS'<229>:'(0,0,0,0,0,0,0,0,0,0,0,AJ66,0,0)';
    'VSS'<228>:'(0,0,0,0,0,0,0,0,0,0,0,AJ68,0,0)';
    'VSS'<227>:'(0,0,0,0,0,0,0,0,0,0,0,AJ7,0,0)';
    'VSS'<226>:'(0,0,0,0,0,0,0,0,0,0,0,AK26,0,0)';
    'VSS'<225>:'(0,0,0,0,0,0,0,0,0,0,0,AK41,0,0)';
    'VSS'<224>:'(0,0,0,0,0,0,0,0,0,0,0,AK46,0,0)';
    'VSS'<223>:'(0,0,0,0,0,0,0,0,0,0,0,AK48,0,0)';
    'VSS'<222>:'(0,0,0,0,0,0,0,0,0,0,0,AK58,0,0)';
    'VSS'<221>:'(0,0,0,0,0,0,0,0,0,0,0,AK61,0,0)';
    'VSS'<220>:'(0,0,0,0,0,0,0,0,0,0,0,AK69,0,0)';
    'VSS'<219>:'(0,0,0,0,0,0,0,0,0,0,0,AK71,0,0)';
    'VSS'<218>:'(0,0,0,0,0,0,0,0,0,0,0,AL22,0,0)';
    'VSS'<217>:'(0,0,0,0,0,0,0,0,0,0,0,AL5,0,0)';
    'VSS'<216>:'(0,0,0,0,0,0,0,0,0,0,0,AL52,0,0)';
    'VSS'<215>:'(0,0,0,0,0,0,0,0,0,0,0,AL59,0,0)';
    'VSS'<214>:'(0,0,0,0,0,0,0,0,0,0,0,0,AL68,0)';
    'VSS'<213>:'(0,0,0,0,0,0,0,0,0,0,0,0,AL70,0)';
    'VSS'<212>:'(0,0,0,0,0,0,0,0,0,0,0,0,AL72,0)';
    'VSS'<211>:'(0,0,0,0,0,0,0,0,0,0,0,0,AM26,0)';
    'VSS'<210>:'(0,0,0,0,0,0,0,0,0,0,0,0,AM30,0)';
    'VSS'<209>:'(0,0,0,0,0,0,0,0,0,0,0,0,AM41,0)';
    'VSS'<208>:'(0,0,0,0,0,0,0,0,0,0,0,0,AM46,0)';
    'VSS'<207>:'(0,0,0,0,0,0,0,0,0,0,0,0,AN13,0)';
    'VSS'<206>:'(0,0,0,0,0,0,0,0,0,0,0,0,AN17,0)';
    'VSS'<205>:'(0,0,0,0,0,0,0,0,0,0,0,0,AN68,0)';
    'VSS'<204>:'(0,0,0,0,0,0,0,0,0,0,0,0,AP22,0)';
    'VSS'<203>:'(0,0,0,0,0,0,0,0,0,0,0,0,AN20,0)';
    'VSS'<202>:'(0,0,0,0,0,0,0,0,0,0,0,0,AN5,0)';
    'VSS'<201>:'(0,0,0,0,0,0,0,0,0,0,0,0,AN58,0)';
    'VSS'<200>:'(0,0,0,0,0,0,0,0,0,0,0,0,AN9,0)';
    'VSS'<199>:'(0,0,0,0,0,0,0,0,0,0,0,0,AP2,0)';
    'VSS'<198>:'(0,0,0,0,0,0,0,0,0,0,0,0,AP26,0)';
    'VSS'<197>:'(0,0,0,0,0,0,0,0,0,0,0,0,AP30,0)';
    'VSS'<196>:'(0,0,0,0,0,0,0,0,0,0,0,0,AP4,0)';
    'VSS'<195>:'(0,0,0,0,0,0,0,0,0,0,0,0,AP41,0)';
    'VSS'<194>:'(0,0,0,0,0,0,0,0,0,0,0,0,AP46,0)';
    'VSS'<193>:'(0,0,0,0,0,0,0,0,0,0,0,0,AP52,0)';
    'VSS'<192>:'(0,0,0,0,0,0,0,0,0,0,0,0,AP66,0)';
    'VSS'<191>:'(0,0,0,0,0,0,0,0,0,0,0,0,AR5,0)';
    'VSS'<190>:'(0,0,0,0,0,0,0,0,0,0,0,0,AR50,0)';
    'VSS'<189>:'(0,0,0,0,0,0,0,0,0,0,0,0,AR58,0)';
    'VSS'<188>:'(0,0,0,0,0,0,0,0,0,0,0,0,AR65,0)';
    'VSS'<187>:'(0,0,0,0,0,0,0,0,0,0,0,0,AR68,0)';
    'VSS'<186>:'(0,0,0,0,0,0,0,0,0,0,0,0,AR70,0)';
    'VSS'<185>:'(0,0,0,0,0,0,0,0,0,0,0,0,AR72,0)';
    'VSS'<184>:'(0,0,0,0,0,0,0,0,0,0,0,0,AT7,0)';
    'VSS'<183>:'(0,0,0,0,0,0,0,0,0,0,0,0,AT11,0)';
    'VSS'<182>:'(0,0,0,0,0,0,0,0,0,0,0,0,AT15,0)';
    'VSS'<181>:'(0,0,0,0,0,0,0,0,0,0,0,0,AT18,0)';
    'VSS'<180>:'(0,0,0,0,0,0,0,0,0,0,0,0,AT22,0)';
    'VSS'<179>:'(0,0,0,0,0,0,0,0,0,0,0,0,AT26,0)';
    'VSS'<178>:'(0,0,0,0,0,0,0,0,0,0,0,0,AT30,0)';
    'VSS'<177>:'(0,0,0,0,0,0,0,0,0,0,0,0,AT41,0)';
    'VSS'<176>:'(0,0,0,0,0,0,0,0,0,0,0,0,AT46,0)';
    'VSS'<175>:'(0,0,0,0,0,0,0,0,0,0,0,0,AT59,0)';
    'VSS'<174>:'(0,0,0,0,0,0,0,0,0,0,0,0,AU26,0)';
    'VSS'<173>:'(0,0,0,0,0,0,0,0,0,0,0,0,AU30,0)';
    'VSS'<172>:'(0,0,0,0,0,0,0,0,0,0,0,0,AE22,0)';
    'VSS'<171>:'(0,0,0,0,0,0,0,0,0,0,0,0,AU41,0)';
    'VSS'<170>:'(0,0,0,0,0,0,0,0,0,0,0,0,AU46,0)';
    'VSS'<169>:'(0,0,0,0,0,0,0,0,0,0,0,0,AU50,0)';
    'VSS'<168>:'(0,0,0,0,0,0,0,0,0,0,0,0,AU54,0)';
    'VSS'<167>:'(0,0,0,0,0,0,0,0,0,0,0,0,AU61,0)';
    'VSS'<166>:'(0,0,0,0,0,0,0,0,0,0,0,0,AV5,0)';
    'VSS'<165>:'(0,0,0,0,0,0,0,0,0,0,0,0,AV22,0)';
    'VSS'<164>:'(0,0,0,0,0,0,0,0,0,0,0,0,AV59,0)';
    'VSS'<163>:'(0,0,0,0,0,0,0,0,0,0,0,0,AV68,0)';
    'VSS'<162>:'(0,0,0,0,0,0,0,0,0,0,0,0,AW9,0)';
    'VSS'<161>:'(0,0,0,0,0,0,0,0,0,0,0,0,AW13,0)';
    'VSS'<160>:'(0,0,0,0,0,0,0,0,0,0,0,0,AW17,0)';
    'VSS'<159>:'(0,0,0,0,0,0,0,0,0,0,0,0,AW26,0)';
    'VSS'<158>:'(0,0,0,0,0,0,0,0,0,0,0,0,AW30,0)';
    'VSS'<157>:'(0,0,0,0,0,0,0,0,0,0,0,0,AW32,0)';
    'VSS'<156>:'(0,0,0,0,0,0,0,0,0,0,0,0,AW34,0)';
    'VSS'<155>:'(0,0,0,0,0,0,0,0,0,0,0,0,AW36,0)';
    'VSS'<154>:'(0,0,0,0,0,0,0,0,0,0,0,0,AW37,0)';
    'VSS'<153>:'(0,0,0,0,0,0,0,0,0,0,0,0,AW39,0)';
    'VSS'<152>:'(0,0,0,0,0,0,0,0,0,0,0,0,AW41,0)';
    'VSS'<151>:'(0,0,0,0,0,0,0,0,0,0,0,0,AW46,0)';
    'VSS'<150>:'(0,0,0,0,0,0,0,0,0,0,0,0,AW50,0)';
    'VSS'<149>:'(0,0,0,0,0,0,0,0,0,0,0,0,AW58,0)';
    'VSS'<148>:'(0,0,0,0,0,0,0,0,0,0,0,0,AW61,0)';
    'VSS'<147>:'(0,0,0,0,0,0,0,0,0,0,0,0,AY5,0)';
    'VSS'<146>:'(0,0,0,0,0,0,0,0,0,0,0,0,AY22,0)';
    'VSS'<145>:'(0,0,0,0,0,0,0,0,0,0,0,0,AY56,0)';
    'VSS'<144>:'(0,0,0,0,0,0,0,0,0,0,0,0,AY63,0)';
    'VSS'<143>:'(0,0,0,0,0,0,0,0,0,0,0,0,AY68,0)';
    'VSS'<142>:'(0,0,0,0,0,0,0,0,0,0,0,0,BA50,0)';
    'VSS'<141>:'(0,0,0,0,0,0,0,0,0,0,0,0,BA54,0)';
    'VSS'<140>:'(0,0,0,0,0,0,0,0,0,0,0,0,BA58,0)';
    'VSS'<139>:'(0,0,0,0,0,0,0,0,0,0,0,0,BB5,0)';
    'VSS'<138>:'(0,0,0,0,0,0,0,0,0,0,0,0,BB7,0)';
    'VSS'<137>:'(0,0,0,0,0,0,0,0,0,0,0,0,BB11,0)';
    'VSS'<136>:'(0,0,0,0,0,0,0,0,0,0,0,0,BB15,0)';
    'VSS'<135>:'(0,0,0,0,0,0,0,0,0,0,0,0,BB18,0)';
    'VSS'<134>:'(0,0,0,0,0,0,0,0,0,0,0,0,BB22,0)';
    'VSS'<133>:'(0,0,0,0,0,0,0,0,0,0,0,0,BB44,0)';
    'VSS'<132>:'(0,0,0,0,0,0,0,0,0,0,0,0,BB59,0)';
    'VSS'<131>:'(0,0,0,0,0,0,0,0,0,0,0,0,BB66,0)';
    'VSS'<130>:'(0,0,0,0,0,0,0,0,0,0,0,0,BB68,0)';
    'VSS'<129>:'(0,0,0,0,0,0,0,0,0,0,0,0,BB70,0)';
    'VSS'<128>:'(0,0,0,0,0,0,0,0,0,0,0,0,BB72,0)';
    'VSS'<127>:'(0,0,0,0,0,0,0,0,0,0,0,0,BC69,0)';
    'VSS'<126>:'(0,0,0,0,0,0,0,0,0,0,0,0,BC71,0)';
    'VSS'<125>:'(0,0,0,0,0,0,0,0,0,0,0,0,BD24,0)';
    'VSS'<124>:'(0,0,0,0,0,0,0,0,0,0,0,0,BD27,0)';
    'VSS'<123>:'(0,0,0,0,0,0,0,0,0,0,0,0,BD31,0)';
    'VSS'<122>:'(0,0,0,0,0,0,0,0,0,0,0,0,BD35,0)';
    'VSS'<121>:'(0,0,0,0,0,0,0,0,0,0,0,0,BD5,0)';
    'VSS'<120>:'(0,0,0,0,0,0,0,0,0,0,0,0,BD50,0)';
    'VSS'<119>:'(0,0,0,0,0,0,0,0,0,0,0,0,BD54,0)';
    'VSS'<118>:'(0,0,0,0,0,0,0,0,0,0,0,0,BD68,0)';
    'VSS'<117>:'(0,0,0,0,0,0,0,0,0,0,0,0,BE29,0)';
    'VSS'<116>:'(0,0,0,0,0,0,0,0,0,0,0,0,BE33,0)';
    'VSS'<115>:'(0,0,0,0,0,0,0,0,0,0,0,0,BE37,0)';
    'VSS'<114>:'(0,0,0,0,0,0,0,0,0,0,0,0,BE56,0)';
    'VSS'<113>:'(0,0,0,0,0,0,0,0,0,0,0,0,BE59,0)';
    'VSS'<112>:'(0,0,0,0,0,0,0,0,0,0,0,0,BE63,0)';
    'VSS'<111>:'(0,0,0,0,0,0,0,0,0,0,0,0,BE66,0)';
    'VSS'<110>:'(0,0,0,0,0,0,0,0,0,0,0,0,BF13,0)';
    'VSS'<109>:'(0,0,0,0,0,0,0,0,0,0,0,0,BF17,0)';
    'VSS'<108>:'(0,0,0,0,0,0,0,0,0,0,0,0,BF54,0)';
    'VSS'<107>:'(0,0,0,0,0,0,0,0,0,0,0,0,BG44,0)';
    'VSS'<106>:'(0,0,0,0,0,0,0,0,0,0,0,0,BF20,0)';
    'VSS'<105>:'(0,0,0,0,0,0,0,0,0,0,0,0,BF24,0)';
    'VSS'<104>:'(0,0,0,0,0,0,0,0,0,0,0,0,BF27,0)';
    'VSS'<103>:'(0,0,0,0,0,0,0,0,0,0,0,0,BF38,0)';
    'VSS'<102>:'(0,0,0,0,0,0,0,0,0,0,0,0,BF42,0)';
    'VSS'<101>:'(0,0,0,0,0,0,0,0,0,0,0,0,BF5,0)';
    'VSS'<100>:'(0,0,0,0,0,0,0,0,0,0,0,0,BF50,0)';
    'VSS'<99>:'(0,0,0,0,0,0,0,0,0,0,0,0,BF58,0)';
    'VSS'<98>:'(0,0,0,0,0,0,0,0,0,0,0,0,BF61,0)';
    'VSS'<97>:'(0,0,0,0,0,0,0,0,0,0,0,0,BF65,0)';
    'VSS'<96>:'(0,0,0,0,0,0,0,0,0,0,0,0,BF68,0)';
    'VSS'<95>:'(0,0,0,0,0,0,0,0,0,0,0,0,BF9,0)';
    'VSS'<94>:'(0,0,0,0,0,0,0,0,0,0,0,0,BG33,0)';
    'VSS'<93>:'(0,0,0,0,0,0,0,0,0,0,0,0,BG48,0)';
    'VSS'<92>:'(0,0,0,0,0,0,0,0,0,0,0,0,BG59,0)';
    'VSS'<91>:'(0,0,0,0,0,0,0,0,0,0,0,0,BG63,0)';
    'VSS'<90>:'(0,0,0,0,0,0,0,0,0,0,0,0,BH27,0)';
    'VSS'<89>:'(0,0,0,0,0,0,0,0,0,0,0,0,BH38,0)';
    'VSS'<88>:'(0,0,0,0,0,0,0,0,0,0,0,0,BH42,0)';
    'VSS'<87>:'(0,0,0,0,0,0,0,0,0,0,0,0,BH46,0)';
    'VSS'<86>:'(0,0,0,0,0,0,0,0,0,0,0,0,BH54,0)';
    'VSS'<85>:'(0,0,0,0,0,0,0,0,0,0,0,0,BJ1,0)';
    'VSS'<84>:'(0,0,0,0,0,0,0,0,0,0,0,0,BJ11,0)';
    'VSS'<83>:'(0,0,0,0,0,0,0,0,0,0,0,0,BJ5,0)';
    'VSS'<82>:'(0,0,0,0,0,0,0,0,0,0,0,0,BJ7,0)';
    'VSS'<81>:'(0,0,0,0,0,0,0,0,0,0,0,0,BJ15,0)';
    'VSS'<80>:'(0,0,0,0,0,0,0,0,0,0,0,0,BJ18,0)';
    'VSS'<79>:'(0,0,0,0,0,0,0,0,0,0,0,0,BJ26,0)';
    'VSS'<78>:'(0,0,0,0,0,0,0,0,0,0,0,0,BJ3,0)';
    'VSS'<77>:'(0,0,0,0,0,0,0,0,0,0,0,0,BJ33,0)';
    'VSS'<76>:'(0,0,0,0,0,0,0,0,0,0,0,0,BJ52,0)';
    'VSS'<75>:'(0,0,0,0,0,0,0,0,0,0,0,0,BJ68,0)';
    'VSS'<74>:'(0,0,0,0,0,0,0,0,0,0,0,0,0,BK24)';
    'VSS'<73>:'(0,0,0,0,0,0,0,0,0,0,0,0,0,BK27)';
    'VSS'<72>:'(0,0,0,0,0,0,0,0,0,0,0,0,0,BK31)';
    'VSS'<71>:'(0,0,0,0,0,0,0,0,0,0,0,0,0,BK35)';
    'VSS'<70>:'(0,0,0,0,0,0,0,0,0,0,0,0,0,BK38)';
    'VSS'<69>:'(0,0,0,0,0,0,0,0,0,0,0,0,0,BK42)';
    'VSS'<68>:'(0,0,0,0,0,0,0,0,0,0,0,0,0,BK50)';
    'VSS'<67>:'(0,0,0,0,0,0,0,0,0,0,0,0,0,BL22)';
    'VSS'<66>:'(0,0,0,0,0,0,0,0,0,0,0,0,0,BL40)';
    'VSS'<65>:'(0,0,0,0,0,0,0,0,0,0,0,0,0,BL68)';
    'VSS'<64>:'(0,0,0,0,0,0,0,0,0,0,0,0,0,BL37)';
    'VSS'<63>:'(0,0,0,0,0,0,0,0,0,0,0,0,0,BL5)';
    'VSS'<62>:'(0,0,0,0,0,0,0,0,0,0,0,0,0,BL63)';
    'VSS'<61>:'(0,0,0,0,0,0,0,0,0,0,0,0,0,BL70)';
    'VSS'<60>:'(0,0,0,0,0,0,0,0,0,0,0,0,0,BL72)';
    'VSS'<59>:'(0,0,0,0,0,0,0,0,0,0,0,0,0,BM13)';
    'VSS'<58>:'(0,0,0,0,0,0,0,0,0,0,0,0,0,BM17)';
    'VSS'<57>:'(0,0,0,0,0,0,0,0,0,0,0,0,0,BN37)';
    'VSS'<56>:'(0,0,0,0,0,0,0,0,0,0,0,0,0,BM46)';
    'VSS'<55>:'(0,0,0,0,0,0,0,0,0,0,0,0,0,BM50)';
    'VSS'<54>:'(0,0,0,0,0,0,0,0,0,0,0,0,0,BM58)';
    'VSS'<53>:'(0,0,0,0,0,0,0,0,0,0,0,0,0,BM69)';
    'VSS'<52>:'(0,0,0,0,0,0,0,0,0,0,0,0,0,BM71)';
    'VSS'<51>:'(0,0,0,0,0,0,0,0,0,0,0,0,0,BM9)';
    'VSS'<50>:'(0,0,0,0,0,0,0,0,0,0,0,0,0,BN22)';
    'VSS'<49>:'(0,0,0,0,0,0,0,0,0,0,0,0,0,BN59)';
    'VSS'<48>:'(0,0,0,0,0,0,0,0,0,0,0,0,0,BN5)';
    'VSS'<47>:'(0,0,0,0,0,0,0,0,0,0,0,0,0,BN52)';
    'VSS'<46>:'(0,0,0,0,0,0,0,0,0,0,0,0,0,BN66)';
    'VSS'<45>:'(0,0,0,0,0,0,0,0,0,0,0,0,0,BR20)';
    'VSS'<44>:'(0,0,0,0,0,0,0,0,0,0,0,0,0,BR50)';
    'VSS'<43>:'(0,0,0,0,0,0,0,0,0,0,0,0,0,BT8)';
    'VSS'<42>:'(0,0,0,0,0,0,0,0,0,0,0,0,0,BR54)';
    'VSS'<41>:'(0,0,0,0,0,0,0,0,0,0,0,0,0,BR58)';
    'VSS'<40>:'(0,0,0,0,0,0,0,0,0,0,0,0,0,BR6)';
    'VSS'<39>:'(0,0,0,0,0,0,0,0,0,0,0,0,0,BT66)';
    'VSS'<38>:'(0,0,0,0,0,0,0,0,0,0,0,0,0,BU13)';
    'VSS'<37>:'(0,0,0,0,0,0,0,0,0,0,0,0,0,BU11)';
    'VSS'<36>:'(0,0,0,0,0,0,0,0,0,0,0,0,0,BV49)';
    'VSS'<35>:'(0,0,0,0,0,0,0,0,0,0,0,0,0,BU15)';
    'VSS'<34>:'(0,0,0,0,0,0,0,0,0,0,0,0,0,BU18)';
    'VSS'<33>:'(0,0,0,0,0,0,0,0,0,0,0,0,0,BU20)';
    'VSS'<32>:'(0,0,0,0,0,0,0,0,0,0,0,0,0,BU22)';
    'VSS'<31>:'(0,0,0,0,0,0,0,0,0,0,0,0,0,BU24)';
    'VSS'<30>:'(0,0,0,0,0,0,0,0,0,0,0,0,0,BU26)';
    'VSS'<29>:'(0,0,0,0,0,0,0,0,0,0,0,0,0,BU28)';
    'VSS'<28>:'(0,0,0,0,0,0,0,0,0,0,0,0,0,BU30)';
    'VSS'<27>:'(0,0,0,0,0,0,0,0,0,0,0,0,0,BU32)';
    'VSS'<26>:'(0,0,0,0,0,0,0,0,0,0,0,0,0,BU34)';
    'VSS'<25>:'(0,0,0,0,0,0,0,0,0,0,0,0,0,BU37)';
    'VSS'<24>:'(0,0,0,0,0,0,0,0,0,0,0,0,0,BU39)';
    'VSS'<23>:'(0,0,0,0,0,0,0,0,0,0,0,0,0,BU41)';
    'VSS'<22>:'(0,0,0,0,0,0,0,0,0,0,0,0,0,BU43)';
    'VSS'<21>:'(0,0,0,0,0,0,0,0,0,0,0,0,0,BU45)';
    'VSS'<20>:'(0,0,0,0,0,0,0,0,0,0,0,0,0,BU48)';
    'VSS'<19>:'(0,0,0,0,0,0,0,0,0,0,0,0,0,BU50)';
    'VSS'<18>:'(0,0,0,0,0,0,0,0,0,0,0,0,0,BU52)';
    'VSS'<17>:'(0,0,0,0,0,0,0,0,0,0,0,0,0,BU54)';
    'VSS'<16>:'(0,0,0,0,0,0,0,0,0,0,0,0,0,BU57)';
    'VSS'<15>:'(0,0,0,0,0,0,0,0,0,0,0,0,0,BU59)';
    'VSS'<14>:'(0,0,0,0,0,0,0,0,0,0,0,0,0,BU61)';
    'VSS'<13>:'(0,0,0,0,0,0,0,0,0,0,0,0,0,BU63)';
    'VSS'<12>:'(0,0,0,0,0,0,0,0,0,0,0,0,0,BU9)';
    'VSS'<11>:'(0,0,0,0,0,0,0,0,0,0,0,0,0,BV40)';
    'VSS'<10>:'(0,0,0,0,0,0,0,0,0,0,0,0,0,BW15)';
    'VSS'<9>:'(0,0,0,0,0,0,0,0,0,0,0,0,0,BW18)';
    'VSS'<8>:'(0,0,0,0,0,0,0,0,0,0,0,0,0,BW26)';
    'VSS'<7>:'(0,0,0,0,0,0,0,0,0,0,0,0,0,BW52)';
    'VSS'<6>:'(0,0,0,0,0,0,0,0,0,0,0,0,0,BY40)';
    'VSS'<5>:'(0,0,0,0,0,0,0,0,0,0,0,0,0,BY49)';
    'VSS'<4>:'(0,0,0,0,0,0,0,0,0,0,0,0,0,CA15)';
    'VSS'<3>:'(0,0,0,0,0,0,0,0,0,0,0,0,0,CA18)';
    'VSS'<2>:'(0,0,0,0,0,0,0,0,0,0,0,0,0,CA26)';
    'VSS'<1>:'(0,0,0,0,0,0,0,0,0,0,0,0,0,CA50)';
    'VSS'<0>:'(0,0,0,0,0,0,0,0,0,0,0,0,0,CA52)';
    'WAKE_N':'(0,0,0,0,K9,0,0,0,0,0,0,0,0,0)';$S;BIDI;
    'XCLK_BIASREF':'(G44,0,0,0,0,0,0,0,0,0,0,0,0,0)';$S;BIDI;
    'XTAL_IN':'(B35,0,0,0,0,0,0,0,0,0,0,0,0,0)';$S;BIDI;
    'XTAL_OUT':'(D35,0,0,0,0,0,0,0,0,0,0,0,0,0)';$S;BIDI;
end_primitive;
primitive 'LCMXO2_A_256BGA-IC,H63395-001';body 'LCMXO2_A';
    'PB3A':'(P4,0,0)';$S;BIDI;
    'PB3B':'(T4,0,0)';$S;BIDI;
    'PB3C':'(T2,0,0)';$S;BIDI;
    'PB3D':'(R3,0,0)';$S;BIDI;
    'PB5A_CSSPIN':'(R5,0,0)';$S;BIDI;
    'PB5B':'(P5,0,0)';$S;BIDI;
    'PB6A':'(T5,0,0)';$S;BIDI;
    'PB6B':'(R6,0,0)';$S;BIDI;
    'PB6C':'(T3,0,0)';$S;BIDI;
    'PB6D':'(R4,0,0)';$S;BIDI;
    'PB8A_MCLK_CCLK':'(P6,0,0)';$S;BIDI;
    'PB8B_SO_SPISO':'(T6,0,0)';$S;BIDI;
    'PB8C':'(N6,0,0)';$S;BIDI;
    'PB8D':'(L7,0,0)';$S;BIDI;
    'PB9A':'(R7,0,0)';$S;BIDI;
    'PB9B':'(P7,0,0)';$S;BIDI;
    'PB9C':'(M7,0,0)';$S;BIDI;
    'PB9D':'(N7,0,0)';$S;BIDI;
    'PB11A_PCLKT2_0':'(T7,0,0)';$S;BIDI;
    'PB11B_PCLKC2_0':'(R8,0,0)';$S;BIDI;
    'PB11C':'(M6,0,0)';$S;BIDI;
    'PB11D':'(L8,0,0)';$S;BIDI;
    'PB12A':'(P8,0,0)';$S;BIDI;
    'PB12B':'(T8,0,0)';$S;BIDI;
    'PB12C':'(N8,0,0)';$S;BIDI;
    'PB12D':'(L9,0,0)';$S;BIDI;
    'PB16A_PCLKT2_1':'(T9,0,0)';$S;BIDI;
    'PB16B_PCLKC2_1':'(P9,0,0)';$S;BIDI;
    'PB16C':'(M8,0,0)';$S;BIDI;
    'PB16D':'(N9,0,0)';$S;BIDI;
    'PB18A':'(R9,0,0)';$S;BIDI;
    'PB18B':'(T10,0,0)';$S;BIDI;
    'PB18C':'(M9,0,0)';$S;BIDI;
    'PB18D':'(L10,0,0)';$S;BIDI;
    'PB19A':'(P10,0,0)';$S;BIDI;
    'PB19B':'(R10,0,0)';$S;BIDI;
    'PB19C':'(N10,0,0)';$S;BIDI;
    'PB19D':'(M11,0,0)';$S;BIDI;
    'PB21A':'(T11,0,0)';$S;BIDI;
    'PB21B':'(P11,0,0)';$S;BIDI;
    'PB21C':'(M10,0,0)';$S;BIDI;
    'PB21D':'(N11,0,0)';$S;BIDI;
    'PB22A':'(R11,0,0)';$S;BIDI;
    'PB22B':'(T12,0,0)';$S;BIDI;
    'PB22C':'(R13,0,0)';$S;BIDI;
    'PB22D':'(T14,0,0)';$S;BIDI;
    'PB24A':'(P12,0,0)';$S;BIDI;
    'PB24B':'(T13,0,0)';$S;BIDI;
    'PB25A_SN':'(R12,0,0)';$S;BIDI;
    'PB25B_SI_SISPI':'(P13,0,0)';$S;BIDI;
    'PB25C':'(T15,0,0)';$S;BIDI;
    'PB25D':'(R14,0,0)';$S;BIDI;
    'PL1A_L_GPLLT_FB':'(D3,0,0)';$S;BIDI;
    'PL1B_L_GPLLC_FB':'(D1,0,0)';$S;BIDI;
    'PL1C':'(B1,0,0)';$S;BIDI;
    'PL1D':'(C2,0,0)';$S;BIDI;
    'PL2A_L_GPLLT_IN':'(E2,0,0)';$S;BIDI;
    'PL2B_L_GPLLC_IN':'(E3,0,0)';$S;BIDI;
    'PL2C':'(C1,0,0)';$S;BIDI;
    'PL2D':'(D2,0,0)';$S;BIDI;
    'PL3A_PCLKT5_0':'(E1,0,0)';$S;BIDI;
    'PL3B_PCLKC5_0':'(F2,0,0)';$S;BIDI;
    'PL3C':'(F4,0,0)';$S;BIDI;
    'PL3D':'(G6,0,0)';$S;BIDI;
    'PL4A':'(F3,0,0)';$S;BIDI;
    'PL4B':'(F1,0,0)';$S;BIDI;
    'PL4C':'(G5,0,0)';$S;BIDI;
    'PL4D':'(G4,0,0)';$S;BIDI;
    'PL5A':'(G2,0,0)';$S;BIDI;
    'PL5B':'(G3,0,0)';$S;BIDI;
    'PL5C':'(F5,0,0)';$S;BIDI;
    'PL5D':'(H6,0,0)';$S;BIDI;
    'PL6A':'(G1,0,0)';$S;BIDI;
    'PL6B':'(H2,0,0)';$S;BIDI;
    'PL6C':'(H4,0,0)';$S;BIDI;
    'PL6D':'(J6,0,0)';$S;BIDI;
    'PL7A':'(H3,0,0)';$S;BIDI;
    'PL7B':'(H1,0,0)';$S;BIDI;
    'PL7C_PCLKT4_0':'(J1,0,0)';$S;BIDI;
    'PL7D_PCLKC4_0':'(J3,0,0)';$S;BIDI;
    'PL9A':'(J2,0,0)';$S;BIDI;
    'PL9B':'(K1,0,0)';$S;BIDI;
    'PL9C':'(H5,0,0)';$S;BIDI;
    'PL9D':'(J4,0,0)';$S;BIDI;
    'PL10A':'(K3,0,0)';$S;BIDI;
    'PL10B':'(K2,0,0)';$S;BIDI;
    'PL10C':'(J5,0,0)';$S;BIDI;
    'PL10D':'(K6,0,0)';$S;BIDI;
    'PL11A':'(L1,0,0)';$S;BIDI;
    'PL11B':'(L3,0,0)';$S;BIDI;
    'PL11C':'(K4,0,0)';$S;BIDI;
    'PL11D':'(L5,0,0)';$S;BIDI;
    'PL12A_PCLKT3_0':'(L2,0,0)';$S;BIDI;
    'PL12B_PCLKC3_0':'(M1,0,0)';$S;BIDI;
    'PL12C':'(K5,0,0)';$S;BIDI;
    'PL12D':'(L4,0,0)';$S;BIDI;
    'PL13A':'(M3,0,0)';$S;BIDI;
    'PL13B':'(N1,0,0)';$S;BIDI;
    'PL13C':'(N2,0,0)';$S;BIDI;
    'PL13D':'(P1,0,0)';$S;BIDI;
    'PL14A':'(M2,0,0)';$S;BIDI;
    'PL14B':'(N3,0,0)';$S;BIDI;
    'PL14C':'(R1,0,0)';$S;BIDI;
    'PL14D':'(P2,0,0)';$S;BIDI;
    'PR1A':'(0,D14,0)';$S;BIDI;
    'PR1B':'(0,E15,0)';$S;BIDI;
    'PR1C':'(0,C15,0)';$S;BIDI;
    'PR1D':'(0,B16,0)';$S;BIDI;
    'PR2A':'(0,D16,0)';$S;BIDI;
    'PR2B':'(0,E14,0)';$S;BIDI;
    'PR2C':'(0,C16,0)';$S;BIDI;
    'PR2D':'(0,D15,0)';$S;BIDI;
    'PR3A':'(0,E16,0)';$S;BIDI;
    'PR3B':'(0,F15,0)';$S;BIDI;
    'PR3C':'(0,F13,0)';$S;BIDI;
    'PR3D':'(0,G12,0)';$S;BIDI;
    'PR4A':'(0,F14,0)';$S;BIDI;
    'PR4B':'(0,F16,0)';$S;BIDI;
    'PR4C':'(0,F12,0)';$S;BIDI;
    'PR4D':'(0,G13,0)';$S;BIDI;
    'PR5A':'(0,G15,0)';$S;BIDI;
    'PR5B':'(0,G14,0)';$S;BIDI;
    'PR5C':'(0,G11,0)';$S;BIDI;
    'PR5D':'(0,H12,0)';$S;BIDI;
    'PR6A':'(0,G16,0)';$S;BIDI;
    'PR6B':'(0,H15,0)';$S;BIDI;
    'PR6C':'(0,H13,0)';$S;BIDI;
    'PR6D':'(0,J12,0)';$S;BIDI;
    'PR7A_PCLKT1_0':'(0,H14,0)';$S;BIDI;
    'PR7B_PCLKC1_0':'(0,H16,0)';$S;BIDI;
    'PR7C':'(0,J16,0)';$S;BIDI;
    'PR7D':'(0,J14,0)';$S;BIDI;
    'PR9A':'(0,J15,0)';$S;BIDI;
    'PR9B':'(0,K16,0)';$S;BIDI;
    'PR9C':'(0,H11,0)';$S;BIDI;
    'PR9D':'(0,J13,0)';$S;BIDI;
    'PR10A':'(0,K14,0)';$S;BIDI;
    'PR10B':'(0,K15,0)';$S;BIDI;
    'PR10C':'(0,J11,0)';$S;BIDI;
    'PR10D':'(0,L12,0)';$S;BIDI;
    'PR11A':'(0,L16,0)';$S;BIDI;
    'PR11B':'(0,L14,0)';$S;BIDI;
    'PR11C':'(0,K13,0)';$S;BIDI;
    'PR11D':'(0,K12,0)';$S;BIDI;
    'PR12A':'(0,L15,0)';$S;BIDI;
    'PR12B':'(0,M16,0)';$S;BIDI;
    'PR12C':'(0,K11,0)';$S;BIDI;
    'PR12D':'(0,L13,0)';$S;BIDI;
    'PR13A':'(0,M14,0)';$S;BIDI;
    'PR13B':'(0,M15,0)';$S;BIDI;
    'PR13C':'(0,N15,0)';$S;BIDI;
    'PR13D':'(0,P16,0)';$S;BIDI;
    'PR14A':'(0,N16,0)';$S;BIDI;
    'PR14B':'(0,N14,0)';$S;BIDI;
    'PR14C':'(0,P15,0)';$S;BIDI;
    'PR14D':'(0,R16,0)';$S;BIDI;
    'PT9A':'(0,C4,0)';$S;BIDI;
    'PT9B':'(0,B5,0)';$S;BIDI;
    'PT9C':'(0,B3,0)';$S;BIDI;
    'PT10A':'(0,A4,0)';$S;BIDI;
    'PT10B':'(0,C5,0)';$S;BIDI;
    'PT11A':'(0,A5,0)';$S;BIDI;
    'PT11B':'(0,B6,0)';$S;BIDI;
    'PT11C':'(0,A3,0)';$S;BIDI;
    'PT11D':'(0,B4,0)';$S;BIDI;
    'PT12A':'(0,D6,0)';$S;BIDI;
    'PT12B':'(0,E7,0)';$S;BIDI;
    'PT12C_TDO':'(0,C6,0)';$S;BIDI;
    'PT12D_TDI':'(0,A6,0)';$S;BIDI;
    'PT13A':'(0,B7,0)';$S;BIDI;
    'PT13B':'(0,C7,0)';$S;BIDI;
    'PT13C':'(0,E6,0)';$S;BIDI;
    'PT13D':'(0,D7,0)';$S;BIDI;
    'PT16A':'(0,F7,0)';$S;BIDI;
    'PT16B':'(0,E8,0)';$S;BIDI;
    'PT16C_TCK':'(0,A7,0)';$S;BIDI;
    'PT16D_TMS':'(0,B8,0)';$S;BIDI;
    'PT17A_PCLKT0_1':'(0,C8,0)';$S;BIDI;
    'PT17B_PCLKC0_1':'(0,A8,0)';$S;BIDI;
    'PT17C':'(0,D8,0)';$S;BIDI;
    'PT17D':'(0,E9,0)';$S;BIDI;
    'PT18A':'(0,F8,0)';$S;BIDI;
    'PT18B':'(0,D9,0)';$S;BIDI;
    'PT18C_SCL_PCLKT0_0':'(0,A9,0)';$S;BIDI;
    'PT18D_SDA_PCLKC0_0':'(0,C9,0)';$S;BIDI;
    'PT19A':'(0,B9,0)';$S;BIDI;
    'PT19B':'(0,A10,0)';$S;BIDI;
    'PT19C':'(0,F9,0)';$S;BIDI;
    'PT19D':'(0,E11,0)';$S;BIDI;
    'PT20A':'(0,D10,0)';$S;BIDI;
    'PT20B':'(0,E10,0)';$S;BIDI;
    'PT20C_JTAGENB':'(0,C10,0)';$S;BIDI;
    'PT20D_PROGRAMN':'(0,B10,0)';$S;BIDI;
    'PT21A':'(0,A11,0)';$S;BIDI;
    'PT21B':'(0,C11,0)';$S;BIDI;
    'PT21C':'(0,F10,0)';$S;BIDI;
    'PT21D':'(0,D11,0)';$S;BIDI;
    'PT22A':'(0,B11,0)';$S;BIDI;
    'PT22B':'(0,A12,0)';$S;BIDI;
    'PT22C':'(0,B13,0)';$S;BIDI;
    'PT22D':'(0,A14,0)';$S;BIDI;
    'PT23A':'(0,C12,0)';$S;BIDI;
    'PT23B':'(0,B12,0)';$S;BIDI;
    'PT24A':'(0,B14,0)';$S;BIDI;
    'PT24B':'(0,A15,0)';$S;BIDI;
    'PT24C_INITN':'(0,A13,0)';$S;BIDI;
    'PT24D_DONE':'(0,C13,0)';$S;BIDI;
    'GND'<0>:'(0,0,B2)';
    'GND'<1>:'(0,0,B15)';
    'GND'<2>:'(0,0,C3)';
    'GND'<3>:'(0,0,C14)';
    'GND'<4>:'(0,0,D4)';
    'GND'<5>:'(0,0,D13)';
    'GND'<6>:'(0,0,E5)';
    'GND'<7>:'(0,0,E12)';
    'GND'<8>:'(0,0,F6)';
    'GND'<9>:'(0,0,F11)';
    'GND'<10>:'(0,0,H8)';
    'GND'<11>:'(0,0,H9)';
    'GND'<12>:'(0,0,J8)';
    'GND'<13>:'(0,0,J9)';
    'GND'<14>:'(0,0,L6)';
    'GND'<15>:'(0,0,L11)';
    'GND'<16>:'(0,0,M5)';
    'GND'<17>:'(0,0,M12)';
    'GND'<18>:'(0,0,N4)';
    'GND'<19>:'(0,0,N13)';
    'GND'<20>:'(0,0,P3)';
    'GND'<21>:'(0,0,P14)';
    'GND'<22>:'(0,0,R2)';
    'GND'<23>:'(0,0,R15)';
    'VCC'<0>:'(0,0,A1)';
    'VCC'<1>:'(0,0,A16)';
    'VCC'<2>:'(0,0,T1)';
    'VCC'<3>:'(0,0,T16)';
    'VCC'<4>:'(0,0,G7)';
    'VCC'<5>:'(0,0,G10)';
    'VCC'<6>:'(0,0,K7)';
    'VCC'<7>:'(0,0,K10)';
    'VCCIO0'<0>:'(0,0,G8)';
    'VCCIO0'<1>:'(0,0,D12)';
    'VCCIO0'<2>:'(0,0,G9)';
    'VCCIO1'<0>:'(0,0,E13)';
    'VCCIO1'<1>:'(0,0,H10)';
    'VCCIO1'<2>:'(0,0,J10)';
    'VCCIO1'<3>:'(0,0,M13)';
    'VCCIO2'<0>:'(0,0,K9)';
    'VCCIO2'<1>:'(0,0,N12)';
    'VCCIO2'<2>:'(0,0,K8)';
    'VCCIO2'<3>:'(0,0,N5)';
    'VCCIO4'<0>:'(0,0,J7)';
    'VCCIO4'<1>:'(0,0,H7)';
    'VCCIO5'<0>:'(0,0,E4)';$S;
    'VCCIO0'<3>:'(0,0,D5)';
    'NC'<0>:'(0,0,A2)';$S;
    'VCCIO3'<0>:'(0,0,M4)';$S;
end_primitive;
primitive 'LED_1NC-BLUE,IC,C96565-012';body 'LED';
    'C':'(1)';
    'A':'(2)';
end_primitive;
primitive 'LED_1NCLF-GREEN,IC,C96565-011';body 'LED';
    'C':'(1)';
    'A':'(2)';
end_primitive;
primitive 'LED_1NCLF-YELLOW,IC,C96565-003';body 'LED';
    'C':'(1)';
    'A':'(2)';
end_primitive;
primitive 'LED_A1-RED,IC,D14725-005';body 'LED';
    'C':'(2)';
    'A':'(1)';
end_primitive;
primitive 'LED_A1LF-GREEN,IC,C97278-010';body 'LED';
    'C':'(2)';
    'A':'(1)';
end_primitive;
primitive 'LED_A1LF-GREEN,IC,D14725-022';body 'LED';
    'C':'(2)';
    'A':'(1)';
end_primitive;
primitive 'LMV331IDCKRG4-GP_DISCRET-G-LMVA';body 'LMV331IDCKRG4-GP';
    '+IN':'(1)';IN;
    '-IN':'(3)';IN;
    'OUT':'(4)';OUT;
    'VCC':'(5)';
    'GND':'(2)';
end_primitive;
primitive 'LMV431AIMFX-GP_DISCRET-G5-LMV4A';body 'LMV431AIMFX-GP';
    'REF':'(1)';
    'CATHODE':'(2)';
    'ANODE':'(3)';
end_primitive;
primitive 'LOTES-CON4-S1-GP_CONN-G7-LOTESA';body 'LOTES-CON4-S1-GP';
    '1':'(1)';
    '2':'(2)';
    '3':'(3)';
    '4':'(4)';
    'NP1':'(NP1)';
end_primitive;
primitive 'M25PE16_SM-IC,H77797-001';body 'M25PE16';
    'S_N':'(1)';IN;
    'RESET_N':'(7)';IN;
    'C':'(6)';IN;
    'DQ0':'(5)';IN;
    'DQ1':'(2)';OUT;
    'VCC':'(8)';
    'VSS':'(4)';
    'W_N':'(3)';IN;
end_primitive;
primitive 'MAX4564EKA-GP_SCRET-GC1-MAX456A';body 'MAX4564EKA-GP';
    'NC':'(1)';
    'V+':'(2)';
    'IN':'(3)';IN;
    'NO':'(4)';
    'GND':'(5)';
    'V-':'(6)';
    'EN#':'(7)';
    'COM':'(8)';
end_primitive;
primitive 'MIC5166_DFN-IC,H55101-001';body 'MIC5166';
    'EN':'(7)';IN;
    'VIN':'(10)';
    'VREF':'(1)';OUT;
    'BIAS':'(2)';BIDI;
    'AGND':'(3)';
    'PG':'(5)';OUT;
    'VDDQ':'(4)';
    'SNS':'(6)';IN;
    'PGND':'(8)';
    'VTT':'(9)';OUT;
    'THPAD':'(11)';
end_primitive;
primitive 'MOSFETN_1D3S_SOT5-IC,G68777-001';body 'MOSFETN_1D3S';
    'S1':'(1)';
    'S2':'(2)';
    'S3':'(3)';
    'D':'(5)';
    'G':'(4)';IN;
end_primitive;
primitive 'MOSFET_N_LCC3-BSZ019N03LS,NFETA';body 'MOSFET_N';
    'GATE':'(4)';
    'SRC':'(1)';
    'DRN':'(5)';
end_primitive;
primitive 'MTG_KEYHOLE_TH-EMPTY,NA';body 'MTG_KEYHOLE';
    '1':'(1)';
end_primitive;
primitive 'NB3W1200L_LCC-IC,H13585-001';body 'NB3W1200L';
    'VDDA':'(1)';
    'GNDA':'(2)';
    'NC'<0>:'(3)';
    '100M_133M_N':'(4)';IN;
    'HBW_BYPASS_LOBW_N':'(5)';IN;
    'PWRGD_PWRDN_N':'(6)';IN;
    'GND'<0>:'(7)';
    'VDDR':'(8)';
    'CLK_INP':'(9)';IN;
    'CLK_INN':'(10)';IN;
    'SA_0':'(11)';IN;
    'SDA':'(12)';BIDI;
    'SCL':'(13)';BIDI;
    'SA_1':'(14)';IN;
    'NC'<2>:'(15)';
    'NC'<1>:'(16)';
    'DIF_0P':'(17)';OUT;
    'DIF_0N':'(18)';OUT;
    'OE_0_N':'(19)';IN;
    'OE_1_N':'(20)';IN;
    'DIF_1P':'(21)';OUT;
    'DIF_1N':'(22)';OUT;
    'GND'<1>:'(23)';
    'VDD'<0>:'(24)';
    'VDDIO'<0>:'(25)';
    'DIF_2P':'(26)';OUT;
    'DIF_2N':'(27)';OUT;
    'OE_2_N':'(28)';IN;
    'OE_3_N':'(29)';IN;
    'DIF_3P':'(30)';OUT;
    'DIF_3N':'(31)';OUT;
    'VDDIO'<1>:'(32)';
    'GND'<2>:'(33)';
    'DIF_4P':'(34)';OUT;
    'DIF_4N':'(35)';OUT;
    'OE_4_N':'(36)';IN;
    'OE_5_N':'(37)';IN;
    'DIF_5P':'(38)';OUT;
    'DIF_5N':'(39)';OUT;
    'VDD'<1>:'(40)';
    'GND'<3>:'(41)';
    'DIF_6P':'(42)';OUT;
    'DIF_6N':'(43)';OUT;
    'OE_6_N':'(44)';IN;
    'OE_7_N':'(45)';IN;
    'DIF_7P':'(46)';OUT;
    'DIF_7N':'(47)';OUT;
    'GND'<4>:'(48)';
    'VDDIO'<2>:'(49)';
    'DIF_8P':'(50)';OUT;
    'DIF_8N':'(51)';OUT;
    'OE_8_N':'(52)';IN;
    'OE_9_N':'(53)';IN;
    'DIF_9P':'(54)';OUT;
    'DIF_9N':'(55)';OUT;
    'VDDIO'<3>:'(56)';
    'VDD'<2>:'(57)';
    'GND'<5>:'(58)';
    'DIF_10P':'(59)';OUT;
    'DIF_10N':'(60)';OUT;
    'OE_10_N':'(61)';IN;
    'OE_11_N':'(62)';IN;
    'DIF_11P':'(63)';OUT;
    'DIF_11N':'(64)';OUT;
    'THPAD':'(65)';
end_primitive;
primitive 'NC7SB3157_SMLF-IC,C99406-001';body 'NC7SB3157';
    'S':'(6)';
    'B0':'(3)';
    'B1':'(1)';
    'A':'(4)';
    'VCC':'(5)';
    'GND':'(2)';
end_primitive;
primitive 'NCP3232L_SM-IC,H86355-001';body 'NCP3232L';
    'AGND':'(5)';
    'BST':'(36)';IN;
    'COMP':'(3)';OUT;
    'EN':'(40)';IN;
    'FB':'(2)';BIDI;
    'GND':'(41)';
    'ISET':'(4)';BIDI;
    'OTS':'(6)';IN;
    'PG':'(7)';BIDI;
    'PGND'<13>:'(37)';
    'PGND'<12>:'(28)';
    'PGND'<11>:'(27)';
    'PGND'<10>:'(26)';
    'PGND'<9>:'(25)';
    'PGND'<8>:'(24)';
    'PGND'<7>:'(23)';
    'PGND'<6>:'(22)';
    'PGND'<5>:'(21)';
    'PGND'<4>:'(20)';
    'PGND'<3>:'(19)';
    'PGND'<2>:'(18)';
    'PGND'<1>:'(17)';
    'PGND'<0>:'(16)';
    'SS':'(1)';BIDI;
    'VB':'(38)';OUT;
    'VCC':'(39)';
    'VIN'<7>:'(42)';IN;
    'VIN'<6>:'(14)';IN;
    'VIN'<5>:'(13)';IN;
    'VIN'<4>:'(12)';IN;
    'VIN'<3>:'(11)';IN;
    'VIN'<2>:'(10)';IN;
    'VIN'<1>:'(9)';IN;
    'VIN'<0>:'(8)';IN;
    'VSW':'(35)';BIDI;
    'VSWH'<7>:'(43)';BIDI;
    'VSWH'<6>:'(34)';BIDI;
    'VSWH'<5>:'(33)';BIDI;
    'VSWH'<4>:'(32)';BIDI;
    'VSWH'<3>:'(31)';BIDI;
    'VSWH'<2>:'(30)';BIDI;
    'VSWH'<1>:'(29)';BIDI;
    'VSWH'<0>:'(15)';BIDI;
end_primitive;
primitive 'NPN_DUAL_SSOPLF-MBT3904,EMPTY,A';body 'NPN_DUAL';
    'B'<0>:'(5,2)';$S;
    'C'<0>:'(3,6)';$S;
    'E'<0>:'(4,1)';$S;
end_primitive;
primitive 'NPN_DUAL_SSOPLF-MBT3904,XSTR,CA';body 'NPN_DUAL';
    'B'<0>:'(5,2)';$S;
    'C'<0>:'(3,6)';$S;
    'E'<0>:'(4,1)';$S;
end_primitive;
primitive 'NPN_SM-MMBT3904,IC,C52245-001';body 'NPN';
    'B':'(1)';
    'C':'(3)';
    'E':'(2)';
end_primitive;
primitive 'OSC_C_6P10-156.25MHZ,OSC,G6383A';body 'OSC_C';
    'ENABLE_DISABLE':'(1)';BIDI;
    'NC_GND':'(2)';
    'GND':'(3)';
    'OUT':'(4)';OUT;
    'OUT_N':'(5)';OUT;
    'VCC':'(6)';
end_primitive;
primitive 'OSC_C_SM4-24MHZ,OSC,D34520-021';body 'OSC_C';
    'ENABLE_CONTROL':'(1)';IN;
    'GND':'(2)';
    'OUT':'(3)';OUT;
    'VDD':'(4)';
end_primitive;
primitive 'PCA9554PWR-GP_DISCRET-G1-PCA95A';body 'PCA9554PWR-GP';
    'A0':'(1)';IN;
    'A1':'(2)';IN;
    'A2':'(3)';IN;
    'P0':'(4)';BIDI;
    'P1':'(5)';BIDI;
    'P2':'(6)';BIDI;
    'P3':'(7)';BIDI;
    'GND':'(8)';
    'P4':'(9)';BIDI;
    'P5':'(10)';BIDI;
    'P6':'(11)';BIDI;
    'P7':'(12)';BIDI;
    'INT#':'(13)';OUT;
    'SCL':'(14)';
    'SDA':'(15)';IN;
    'VCC':'(16)';
end_primitive;
primitive 'PCA9617_SSOP-IC,G81764-001-GNDA';body 'PCA9617';
    'EN':'(5)';IN;
    'SCLA':'(2)';IN;
    'SCLB':'(7)';OUT;
    'SDAA':'(3)';IN;
    'SDAB':'(6)';OUT;
    'VCCA':'(1)';
    'VCCB':'(8)';
end_primitive;
primitive 'PI3B3257A_TSSOPLF-IC,E16801-001';body 'PI3B3257A';
    'VCC':'(16)';
    'GND':'(8)';
    'EN':'(15)';IN;
    'S':'(1)';BIDI;
    'YA':'(4)';BIDI;
    'YB':'(7)';BIDI;
    'YC':'(9)';BIDI;
    'YD':'(12)';BIDI;
    'IA0':'(2)';BIDI;
    'IA1':'(3)';BIDI;
    'IB0':'(5)';BIDI;
    'IB1':'(6)';BIDI;
    'IC0':'(11)';BIDI;
    'IC1':'(10)';BIDI;
    'ID0':'(14)';BIDI;
    'ID1':'(13)';BIDI;
end_primitive;
primitive 'PI5A3157BC6E-GP_DISCRET-GC2-PIA';body 'PI5A3157BC6E-GP';
    'B1':'(1)';
    'GND':'(2)';
    'B0':'(3)';
    'A':'(4)';
    'VCC':'(5)';
    'S':'(6)';
end_primitive;
primitive 'PIN-CON3-27-GP_CONN-G7-PIN-CONA';body 'PIN-CON3-27-GP';
    '1':'(1)';
    '2':'(2)';
    '3':'(3)';
end_primitive;
primitive 'POLYSW-1D1A6V-2-GP-U_DISCRET-GA';body 'POLYSW-1D1A6V-2-GP-U';
    '1':'(1)';
    '2':'(2)';
end_primitive;
primitive 'POLYSW-D5A6V-2-GP-U_DISCRET-GAA';body 'POLYSW-D5A6V-2-GP-U';
    '1':'(1)';
    '2':'(2)';
end_primitive;
primitive 'PXE1110B_QFN-IC,H89187-001';body 'PXE1110B';
    'DNC'<0>:'(1)';
    'DNC'<1>:'(2)';
    'BPWM1':'(3)';OUT;
    'DNC'<2>:'(4)';
    'APWM1':'(5)';OUT;
    'SDA':'(6)';BIDI;
    'SCL':'(7)';BIDI;
    'RESET_N':'(8)';IN;
    'AVRRDY':'(9)';OUT;
    'AVREN':'(10)';IN;
    'VRHOT_N':'(11)';OUT;
    'PINALRT_N':'(12)';OUT;
    'MP0':'(13)';BIDI;
    'MP1':'(14)';BIDI;
    'VCLK':'(15)';IN;
    'VDIO':'(16)';BIDI;
    'VALRT_N':'(17)';OUT;
    'MP2':'(18)';OUT;
    'AVSEN':'(19)';IN;
    'AVREF':'(20)';IN;
    'AIREF1':'(21)';IN;
    'AISEN1':'(22)';IN;
    'GND'<1>:'(23)';
    'DNC'<3>:'(24)';
    'BIREF1':'(25)';IN;
    'BISEN1':'(26)';IN;
    'GND'<0>:'(27)';
    'DNC'<4>:'(28)';
    'BVSEN':'(29)';IN;
    'BVREF':'(30)';IN;
    'MP3':'(31)';BIDI;
    'MP4':'(32)';BIDI;
    'XADDR2':'(33)';IN;
    'BTSEN':'(34)';IN;
    'ATSEN':'(35)';IN;
    'XADDR1':'(36)';IN;
    'VINSEN':'(37)';IN;
    'IINSEN':'(38)';IN;
    'VDD':'(39)';
    'VD12':'(40)';
    'THPAD':'(41)';
end_primitive;
primitive 'PXE1610B_QFN-IC,H79206-001';body 'PXE1610B';
    'BPWM1':'(1)';OUT;
    'APWM6':'(2)';OUT;
    'APWM5':'(3)';OUT;
    'APWM4':'(4)';OUT;
    'APWM3':'(5)';OUT;
    'APWM2':'(6)';OUT;
    'APWM1':'(7)';OUT;
    'SDA':'(8)';BIDI;
    'SCL':'(9)';BIDI;
    'RESET_N':'(10)';IN;
    'AVRRDY':'(11)';OUT;
    'AVREN':'(12)';IN;
    'VRHOT_N':'(13)';OUT;
    'PINALRT_N':'(14)';OUT;
    'MP0':'(15)';BIDI;
    'MP1':'(16)';BIDI;
    'VCLK':'(17)';IN;
    'VDIO':'(18)';BIDI;
    'VALRT_N':'(19)';OUT;
    'MP2':'(20)';OUT;
    'AVSEN':'(21)';IN;
    'AVREF':'(22)';IN;
    'AIREF1':'(23)';IN;
    'AISEN1':'(24)';IN;
    'AIREF2':'(25)';IN;
    'AISEN2':'(26)';IN;
    'AIREF3':'(27)';IN;
    'AISEN3':'(28)';IN;
    'AIREF4':'(29)';IN;
    'AISEN4':'(30)';IN;
    'AIREF5':'(31)';IN;
    'AISEN5':'(32)';IN;
    'AIREF6':'(33)';IN;
    'AISEN6':'(34)';IN;
    'BVSEN':'(35)';IN;
    'BVREF':'(36)';IN;
    'BIREF1':'(37)';IN;
    'BISEN1':'(38)';IN;
    'MP3':'(39)';OUT;
    'MP4':'(40)';OUT;
    'XADDR2':'(41)';IN;
    'BTSEN':'(42)';IN;
    'ATSEN':'(43)';IN;
    'XADDR1':'(44)';IN;
    'VINSEN':'(45)';IN;
    'IINSEN':'(46)';IN;
    'VDD':'(47)';
    'VD12':'(48)';
    'THPAD':'(49)';
end_primitive;
primitive 'PXM1310B_QFN-IC,H89186-001';body 'PXM1310B';
    'BPWM1':'(1)';OUT;
    'DNC'<0>:'(2)';
    'APWM3':'(3)';OUT;
    'APWM2':'(4)';OUT;
    'APWM1':'(5)';OUT;
    'SDA':'(6)';BIDI;
    'SCL':'(7)';BIDI;
    'RESET_N':'(8)';IN;
    'AVRRDY':'(9)';OUT;
    'AVREN':'(10)';IN;
    'VRHOT_N':'(11)';OUT;
    'PINALRT_N':'(12)';OUT;
    'MP0':'(13)';BIDI;
    'MP1':'(14)';BIDI;
    'VCLK':'(15)';IN;
    'VDIO':'(16)';BIDI;
    'VALRT_N':'(17)';OUT;
    'MP2':'(18)';BIDI;
    'AVSEN':'(19)';IN;
    'AVREF':'(20)';IN;
    'AIREF1':'(21)';IN;
    'AISEN1':'(22)';IN;
    'AIREF2':'(23)';IN;
    'AISEN2':'(24)';IN;
    'AIREF3':'(25)';IN;
    'AISEN3':'(26)';IN;
    'GND':'(27)';
    'DNC'<1>:'(28)';
    'BVSEN':'(29)';IN;
    'BVREF':'(30)';IN;
    'BIREF1':'(31)';IN;
    'BISEN1':'(32)';IN;
    'XADDR2':'(33)';IN;
    'BTSEN':'(34)';IN;
    'ATSEN':'(35)';IN;
    'XADDR1':'(36)';IN;
    'VINSEN':'(37)';IN;
    'IINSEN':'(38)';IN;
    'VDD':'(39)';
    'VD12':'(40)';BIDI;
    'THPAD':'(41)';
end_primitive;
primitive 'RB551V30-GP_DISCRET-G-RB551V30A';body 'RB551V30-GP';
    'CATHODE':'(K)';
    'ANODE':'(A)';
end_primitive;
primitive 'RES_0402-0.0,5%,1/16W,CHIP,G21A';body 'RES';
    'A':'(1)';
    'B':'(2)';
end_primitive;
primitive 'RES_0402-0.0,5%,1/16W,EMPTY,G2A';body 'RES';
    'A':'(1)';
    'B':'(2)';
end_primitive;
primitive 'RES_0402-1.00K,1%,1/16W,CHIP,GA';body 'RES';
    'A':'(1)';
    'B':'(2)';
end_primitive;
primitive 'RES_0402-1.00K,1%,1/16W,EMPTY,A';body 'RES';
    'A':'(1)';
    'B':'(2)';
end_primitive;
primitive 'RES_0402-1.0K,0.1%,1/16W,CHIP,A';body 'RES';
    'A':'(1)';
    'B':'(2)';
end_primitive;
primitive 'RES_0402-1.0M,1%,1/16W,EMPTY,GA';body 'RES';
    'A':'(1)';
    'B':'(2)';
end_primitive;
primitive 'RES_0402-1.37K,1%,1/16W,CHIP,GA';body 'RES';
    'A':'(1)';
    'B':'(2)';
end_primitive;
primitive 'RES_0402-1.5K,1%,1/16W,CHIP,G2A';body 'RES';
    'A':'(1)';
    'B':'(2)';
end_primitive;
primitive 'RES_0402-1.8K,1%,1/16W,CHIP,G2A';body 'RES';
    'A':'(1)';
    'B':'(2)';
end_primitive;
primitive 'RES_0402-10.0,1%,1/16W,CHIP,G2A';body 'RES';
    'A':'(1)';
    'B':'(2)';
end_primitive;
primitive 'RES_0402-10.0,1%,1/16W,EMPTY,GA';body 'RES';
    'A':'(1)';
    'B':'(2)';
end_primitive;
primitive 'RES_0402-10.0K,1%,1/16W,CHIP,GA';body 'RES';
    'A':'(1)';
    'B':'(2)';
end_primitive;
primitive 'RES_0402-10.0K,1%,1/16W,EMPTY,A';body 'RES';
    'A':'(1)';
    'B':'(2)';
end_primitive;
primitive 'RES_0402-100.0,1%,1/16W,CHIP,GA';body 'RES';
    'A':'(1)';
    'B':'(2)';
end_primitive;
primitive 'RES_0402-100.0,1%,1/16W,EMPTY,A';body 'RES';
    'A':'(1)';
    'B':'(2)';
end_primitive;
primitive 'RES_0402-100.0K,1%,1/16W,CHIP,A';body 'RES';
    'A':'(1)';
    'B':'(2)';
end_primitive;
primitive 'RES_0402-100.0K,1%,1/16W,CHIP,B';body 'RES';
    'A':'(1)';
    'B':'(2)';
end_primitive;
primitive 'RES_0402-100.0K,1%,1/16W,EMPTYA';body 'RES';
    'A':'(1)';
    'B':'(2)';
end_primitive;
primitive 'RES_0402-105.0K,1%,1/16W,CHIP,A';body 'RES';
    'A':'(1)';
    'B':'(2)';
end_primitive;
primitive 'RES_0402-110,1%,1/16W,EMPTY,G2A';body 'RES';
    'A':'(1)';
    'B':'(2)';
end_primitive;
primitive 'RES_0402-113,1%,1/16W,CHIP,G21A';body 'RES';
    'A':'(1)';
    'B':'(2)';
end_primitive;
primitive 'RES_0402-11K,1%,1/16W,CHIP,G21A';body 'RES';
    'A':'(1)';
    'B':'(2)';
end_primitive;
primitive 'RES_0402-12.1K,1%,1/16W,CHIP,GA';body 'RES';
    'A':'(1)';
    'B':'(2)';
end_primitive;
primitive 'RES_0402-15.0K,1%,1/16W,CHIP,GA';body 'RES';
    'A':'(1)';
    'B':'(2)';
end_primitive;
primitive 'RES_0402-150.0,1%,1/16W,CHIP,GA';body 'RES';
    'A':'(1)';
    'B':'(2)';
end_primitive;
primitive 'RES_0402-150.0K,1%,1/16W,CHIP,A';body 'RES';
    'A':'(1)';
    'B':'(2)';
end_primitive;
primitive 'RES_0402-169,1.0%,1/16W,CHIP,GA';body 'RES';
    'A':'(1)';
    'B':'(2)';
end_primitive;
primitive 'RES_0402-16K,1.0%,1/16W,CHIP,GA';body 'RES';
    'A':'(1)';
    'B':'(2)';
end_primitive;
primitive 'RES_0402-2,1.0%,1/16W,CHIP,G21A';body 'RES';
    'A':'(1)';
    'B':'(2)';
end_primitive;
primitive 'RES_0402-2.0K,1%,1/16W,CHIP,G2A';body 'RES';
    'A':'(1)';
    'B':'(2)';
end_primitive;
primitive 'RES_0402-2.0K,1%,1/16W,EMPTY,GA';body 'RES';
    'A':'(1)';
    'B':'(2)';
end_primitive;
primitive 'RES_0402-2.2,5%,1/16W,EMPTY,G2A';body 'RES';
    'A':'(1)';
    'B':'(2)';
end_primitive;
primitive 'RES_0402-2.21K,1%,1/16W,CHIP,GA';body 'RES';
    'A':'(1)';
    'B':'(2)';
end_primitive;
primitive 'RES_0402-2.26K,1.0%,1/16W,CHIPA';body 'RES';
    'A':'(1)';
    'B':'(2)';
end_primitive;
primitive 'RES_0402-2.26K,1.0%,1/16W,EMPTA';body 'RES';
    'A':'(1)';
    'B':'(2)';
end_primitive;
primitive 'RES_0402-2.67K,1%,1/16W,CHIP,GA';body 'RES';
    'A':'(1)';
    'B':'(2)';
end_primitive;
primitive 'RES_0402-2.7K,1%,1/16W,CHIP,G2A';body 'RES';
    'A':'(1)';
    'B':'(2)';
end_primitive;
primitive 'RES_0402-2.7K,1%,1/16W,EMPTY,GA';body 'RES';
    'A':'(1)';
    'B':'(2)';
end_primitive;
primitive 'RES_0402-20.0,1%,1/16W,CHIP,G2A';body 'RES';
    'A':'(1)';
    'B':'(2)';
end_primitive;
primitive 'RES_0402-20.0,1%,1/16W,EMPTY,GA';body 'RES';
    'A':'(1)';
    'B':'(2)';
end_primitive;
primitive 'RES_0402-20.0K,1%,1/16W,CHIP,GA';body 'RES';
    'A':'(1)';
    'B':'(2)';
end_primitive;
primitive 'RES_0402-200.0,1%,1/16W,CHIP,GA';body 'RES';
    'A':'(1)';
    'B':'(2)';
end_primitive;
primitive 'RES_0402-200.0K,1%,1/16W,CHIP,A';body 'RES';
    'A':'(1)';
    'B':'(2)';
end_primitive;
primitive 'RES_0402-22.1,1.0%,1/16W,CHIP,A';body 'RES';
    'A':'(1)';
    'B':'(2)';
end_primitive;
primitive 'RES_0402-221,1.0%,1/16W,CHIP,GA';body 'RES';
    'A':'(1)';
    'B':'(2)';
end_primitive;
primitive 'RES_0402-23.2K,1%,1/16W,CHIP,GA';body 'RES';
    'A':'(1)';
    'B':'(2)';
end_primitive;
primitive 'RES_0402-24.9K,1%,1/16W,CHIP,GA';body 'RES';
    'A':'(1)';
    'B':'(2)';
end_primitive;
primitive 'RES_0402-240,1.0%,1/16W,CHIP,GA';body 'RES';
    'A':'(1)';
    'B':'(2)';
end_primitive;
primitive 'RES_0402-240,1.0%,1/16W,EMPTY,A';body 'RES';
    'A':'(1)';
    'B':'(2)';
end_primitive;
primitive 'RES_0402-249,0.1%,1/16W,CHIP,GA';body 'RES';
    'A':'(1)';
    'B':'(2)';
end_primitive;
primitive 'RES_0402-27.4,1%,1/16W,CHIP,G2A';body 'RES';
    'A':'(1)';
    'B':'(2)';
end_primitive;
primitive 'RES_0402-3.16K,1%,1/16W,CHIP,GA';body 'RES';
    'A':'(1)';
    'B':'(2)';
end_primitive;
primitive 'RES_0402-3.32K,1%,1/16W,CHIP,GA';body 'RES';
    'A':'(1)';
    'B':'(2)';
end_primitive;
primitive 'RES_0402-3.32K,1%,1/16W,EMPTY,A';body 'RES';
    'A':'(1)';
    'B':'(2)';
end_primitive;
primitive 'RES_0402-3.3K,5%,1/16W,CHIP,G2A';body 'RES';
    'A':'(1)';
    'B':'(2)';
end_primitive;
primitive 'RES_0402-3.48K,1.0%,1/16W,CHIPA';body 'RES';
    'A':'(1)';
    'B':'(2)';
end_primitive;
primitive 'RES_0402-3.74K,1%,1/16W,CHIP,GA';body 'RES';
    'A':'(1)';
    'B':'(2)';
end_primitive;
primitive 'RES_0402-301.0,1%,1/16W,CHIP,GA';body 'RES';
    'A':'(1)';
    'B':'(2)';
end_primitive;
primitive 'RES_0402-33.0K,5%,1/16W,CHIP,GA';body 'RES';
    'A':'(1)';
    'B':'(2)';
end_primitive;
primitive 'RES_0402-33.2,1%,1/16W,CHIP,G2A';body 'RES';
    'A':'(1)';
    'B':'(2)';
end_primitive;
primitive 'RES_0402-33.2,1%,1/16W,EMPTY,GA';body 'RES';
    'A':'(1)';
    'B':'(2)';
end_primitive;
primitive 'RES_0402-330,5%,1/16W,CHIP,G21A';body 'RES';
    'A':'(1)';
    'B':'(2)';
end_primitive;
primitive 'RES_0402-348,1%,1/16W,CHIP,G21A';body 'RES';
    'A':'(1)';
    'B':'(2)';
end_primitive;
primitive 'RES_0402-348,1%,1/16W,EMPTY,G2A';body 'RES';
    'A':'(1)';
    'B':'(2)';
end_primitive;
primitive 'RES_0402-4.02K,1%,1/16W,CHIP,GA';body 'RES';
    'A':'(1)';
    'B':'(2)';
end_primitive;
primitive 'RES_0402-4.75K,1%,1/16W,CHIP,GA';body 'RES';
    'A':'(1)';
    'B':'(2)';
end_primitive;
primitive 'RES_0402-4.75K,1%,1/16W,EMPTY,A';body 'RES';
    'A':'(1)';
    'B':'(2)';
end_primitive;
primitive 'RES_0402-4.99K,1%,1/16W,CHIP,GA';body 'RES';
    'A':'(1)';
    'B':'(2)';
end_primitive;
primitive 'RES_0402-40.2K,1%,1/16W,CHIP,GA';body 'RES';
    'A':'(1)';
    'B':'(2)';
end_primitive;
primitive 'RES_0402-42.2,1.0%,1/16W,EMPTYA';body 'RES';
    'A':'(1)';
    'B':'(2)';
end_primitive;
primitive 'RES_0402-470.0,5%,1/16W,CHIP,GA';body 'RES';
    'A':'(1)';
    'B':'(2)';
end_primitive;
primitive 'RES_0402-475.0,1%,1/16W,CHIP,GA';body 'RES';
    'A':'(1)';
    'B':'(2)';
end_primitive;
primitive 'RES_0402-49.9,1%,1/16W,CHIP,G2A';body 'RES';
    'A':'(1)';
    'B':'(2)';
end_primitive;
primitive 'RES_0402-49.9,1%,1/16W,EMPTY,GA';body 'RES';
    'A':'(1)';
    'B':'(2)';
end_primitive;
primitive 'RES_0402-49.9K,1%,1/16W,CHIP,GA';body 'RES';
    'A':'(1)';
    'B':'(2)';
end_primitive;
primitive 'RES_0402-5.11K,1%,1/16W,CHIP,GA';body 'RES';
    'A':'(1)';
    'B':'(2)';
end_primitive;
primitive 'RES_0402-5.36K,1.0%,1/16W,CHIPA';body 'RES';
    'A':'(1)';
    'B':'(2)';
end_primitive;
primitive 'RES_0402-51,5.0%,1/16W,CHIP,G2A';body 'RES';
    'A':'(1)';
    'B':'(2)';
end_primitive;
primitive 'RES_0402-51.1,1.0%,1/16W,CHIP,A';body 'RES';
    'A':'(1)';
    'B':'(2)';
end_primitive;
primitive 'RES_0402-6.19K,1%,1/16W,CHIP,GA';body 'RES';
    'A':'(1)';
    'B':'(2)';
end_primitive;
primitive 'RES_0402-6.34K,1%,1/16W,CHIP,GA';body 'RES';
    'A':'(1)';
    'B':'(2)';
end_primitive;
primitive 'RES_0402-63.4K,1.0%,1/16W,CHIPA';body 'RES';
    'A':'(1)';
    'B':'(2)';
end_primitive;
primitive 'RES_0402-64.9,1.0%,1/16W,CHIP,A';body 'RES';
    'A':'(1)';
    'B':'(2)';
end_primitive;
primitive 'RES_0402-665,1.0%,1/16W,CHIP,GA';body 'RES';
    'A':'(1)';
    'B':'(2)';
end_primitive;
primitive 'RES_0402-68.1K,1%,1/16W,EMPTY,A';body 'RES';
    'A':'(1)';
    'B':'(2)';
end_primitive;
primitive 'RES_0402-69.8K,1%,1/16W,CHIP,GA';body 'RES';
    'A':'(1)';
    'B':'(2)';
end_primitive;
primitive 'RES_0402-7.5K,1%,1/16W,CHIP,G2A';body 'RES';
    'A':'(1)';
    'B':'(2)';
end_primitive;
primitive 'RES_0402-7.87K,1.0%,1/16W,CHIPA';body 'RES';
    'A':'(1)';
    'B':'(2)';
end_primitive;
primitive 'RES_0402-75,1.0%,1/16W,CHIP,G2A';body 'RES';
    'A':'(1)';
    'B':'(2)';
end_primitive;
primitive 'RES_0402-75K,1%,1/16W,CHIP,G21A';body 'RES';
    'A':'(1)';
    'B':'(2)';
end_primitive;
primitive 'RES_0402-8.06K,1%,1/16W,CHIP,GA';body 'RES';
    'A':'(1)';
    'B':'(2)';
end_primitive;
primitive 'RES_0402-8.2K,1%,1/16W,CHIP,G2A';body 'RES';
    'A':'(1)';
    'B':'(2)';
end_primitive;
primitive 'RES_0402-8.2K,1%,1/16W,EMPTY,GA';body 'RES';
    'A':'(1)';
    'B':'(2)';
end_primitive;
primitive 'RES_0402-90.9,1%,1/16W,CHIP,G2A';body 'RES';
    'A':'(1)';
    'B':'(2)';
end_primitive;
primitive 'RES_0402-90.9K,1%,1/16W,CHIP,GA';body 'RES';
    'A':'(1)';
    'B':'(2)';
end_primitive;
primitive 'RES_0603-0,5.0%,1/10W,CHIP,G22A';body 'RES';
    'A':'(1)';
    'B':'(2)';
end_primitive;
primitive 'RES_0603-0,5.0%,1/10W,EMPTY,G2A';body 'RES';
    'A':'(1)';
    'B':'(2)';
end_primitive;
primitive 'RES_0603-10.0,1%,1/10W,CHIP,G2A';body 'RES';
    'A':'(1)';
    'B':'(2)';
end_primitive;
primitive 'RES_0603-100.0,1%,1/10W,CHIP,GA';body 'RES';
    'A':'(1)';
    'B':'(2)';
end_primitive;
primitive 'RES_0603-100.0K,1%,1/10W,CHIP,A';body 'RES';
    'A':'(1)';
    'B':'(2)';
end_primitive;
primitive 'RES_0603-10M,1.0%,1/10W,CHIP,GA';body 'RES';
    'A':'(1)';
    'B':'(2)';
end_primitive;
primitive 'RES_0603-120.0,1%,1/10W,CHIP,GA';body 'RES';
    'A':'(1)';
    'B':'(2)';
end_primitive;
primitive 'RES_0603-2.2,1.0%,1/10W,CHIP,GA';body 'RES';
    'A':'(1)';
    'B':'(2)';
end_primitive;
primitive 'RES_0603-200K,0.1%,1/10W,CHIP,A';body 'RES';
    'A':'(1)';
    'B':'(2)';
end_primitive;
primitive 'RES_0603-475.0,1%,1/10W,CHIP,GA';body 'RES';
    'A':'(1)';
    'B':'(2)';
end_primitive;
primitive 'RES_0805-0.0,5%,1/8W,CHIP,G221A';body 'RES';
    'A':'(1)';
    'B':'(2)';
end_primitive;
primitive 'RES_0805-0.0,5%,1/8W,EMPTY,G22A';body 'RES';
    'A':'(1)';
    'B':'(2)';
end_primitive;
primitive 'RES_1206-0.002,1%,1W,CHIP,G521A';body 'RES';
    'A':'(1)';
    'B':'(2)';
end_primitive;
primitive 'RES_PWR_6PAD-0.001,1%,3W,CHIP,A';body 'RES_PWR';
    '1':'(1)';
    '2':'(2)';
    '3':'(3)';
    '4':'(4)';
    '5':'(5)';
    '6':'(6)';
end_primitive;
primitive 'RT8240_QFN-IC,H66262-001';body 'RT8240';
    'BOOT':'(4)';IN;
    'CS':'(10)';IN;
    'EN':'(8)';IN;
    'G0':'(11)';IN;
    'GND'<1>:'(13)';
    'GND'<0>:'(12)';
    'LGATE':'(1)';OUT;
    'PGOOD':'(9)';IN;
    'PHASE':'(2)';IN;
    'RGND':'(7)';
    'UGATE':'(3)';OUT;
    'VCC':'(5)';
    'VOUT':'(6)';OUT;
end_primitive;
primitive 'RT9059_DFN-IC,H65765-001';body 'RT9059';
    'ADJ_NC':'(4)';OUT;
    'EN':'(6)';IN;
    'GND':'(11)';
    'PGOOD':'(5)';OUT;
    'VDD':'(10)';
    'VIN'<2>:'(9)';IN;
    'VIN'<1>:'(8)';IN;
    'VIN'<0>:'(7)';IN;
    'VOUT'<2>:'(3)';OUT;
    'VOUT'<1>:'(2)';OUT;
    'VOUT'<0>:'(1)';OUT;
end_primitive;
primitive 'SC1U10V2KX-4-GP_SMD-BCG6-SC1U1A';body 'SC1U10V2KX-4-GP';
    '1':'(1)';
    '2':'(2)';
end_primitive;
primitive 'SC1U16V3KX-2GP_SMD-BCG-SC1U16VA';body 'SC1U16V3KX-2GP';
    '1':'(1)';
    '2':'(2)';
end_primitive;
primitive 'SC22P50V2JN-4GP_SMD-BCG-SC22P5A';body 'SC22P50V2JN-4GP';
    '1':'(1)';
    '2':'(2)';
end_primitive;
primitive 'SC22U16V5MX-4-GP_SMD-BCG5-SC22A';body 'SC22U16V5MX-4-GP';
    '1':'(1)';
    '2':'(2)';
end_primitive;
primitive 'SC4D7U16V3KX-GP_SMD-BCG5-SC4D7A';body 'SC4D7U16V3KX-GP';
    '1':'(1)';
    '2':'(2)';
end_primitive;
primitive 'SCONN10_C12536004_SMLF-CONN,C1A';body 'SCONN10_C12536004';
    'IO1':'(1)';
    'IO2':'(2)';
    'IO3':'(3)';
    'IO4':'(4)';
    'IO5':'(5)';
    'IO6':'(6)';
    'IO7':'(7)';
    'IO8':'(8)';
    'IO9':'(9)';
    'IO10':'(10)';
end_primitive;
primitive 'SCONN11_H67026001_SM-CONN,H670A';body 'SCONN11_H67026001';
    'IO1':'(1)';BIDI;
    'IO2':'(2)';BIDI;
    'IO3':'(3)';BIDI;
    'IO4':'(4)';BIDI;
    'IO5':'(5)';BIDI;
    'IO6':'(6)';BIDI;
    'IO7':'(7)';BIDI;
    'IO8':'(8)';BIDI;
    'IO9':'(9)';BIDI;
    'IO10':'(10)';BIDI;
    'IO11':'(11)';BIDI;
    'MP1':'(MP1)';
    'MP2':'(MP2)';
end_primitive;
primitive 'SCONN120_A28699018_SM-SCONN,A2A';body 'SCONN120_A28699018';
    'IO1':'(1)';BIDI;
    'IO10':'(10)';BIDI;
    'IO100':'(100)';BIDI;
    'IO101':'(101)';BIDI;
    'IO102':'(102)';BIDI;
    'IO103':'(103)';BIDI;
    'IO104':'(104)';BIDI;
    'IO105':'(105)';BIDI;
    'IO106':'(106)';BIDI;
    'IO107':'(107)';BIDI;
    'IO108':'(108)';BIDI;
    'IO109':'(109)';BIDI;
    'IO11':'(11)';BIDI;
    'IO110':'(110)';BIDI;
    'IO111':'(111)';BIDI;
    'IO112':'(112)';BIDI;
    'IO113':'(113)';BIDI;
    'IO114':'(114)';BIDI;
    'IO115':'(115)';BIDI;
    'IO116':'(116)';BIDI;
    'IO117':'(117)';BIDI;
    'IO118':'(118)';BIDI;
    'IO119':'(119)';BIDI;
    'IO12':'(12)';BIDI;
    'IO120':'(120)';BIDI;
    'IO13':'(13)';BIDI;
    'IO14':'(14)';BIDI;
    'IO15':'(15)';BIDI;
    'IO16':'(16)';BIDI;
    'IO17':'(17)';BIDI;
    'IO18':'(18)';BIDI;
    'IO19':'(19)';BIDI;
    'IO2':'(2)';BIDI;
    'IO20':'(20)';BIDI;
    'IO21':'(21)';BIDI;
    'IO22':'(22)';BIDI;
    'IO23':'(23)';BIDI;
    'IO24':'(24)';BIDI;
    'IO25':'(25)';BIDI;
    'IO26':'(26)';BIDI;
    'IO27':'(27)';BIDI;
    'IO28':'(28)';BIDI;
    'IO29':'(29)';BIDI;
    'IO3':'(3)';BIDI;
    'IO30':'(30)';BIDI;
    'IO31':'(31)';BIDI;
    'IO32':'(32)';BIDI;
    'IO33':'(33)';BIDI;
    'IO34':'(34)';BIDI;
    'IO35':'(35)';BIDI;
    'IO36':'(36)';BIDI;
    'IO37':'(37)';BIDI;
    'IO38':'(38)';BIDI;
    'IO39':'(39)';BIDI;
    'IO4':'(4)';BIDI;
    'IO40':'(40)';BIDI;
    'IO41':'(41)';BIDI;
    'IO42':'(42)';BIDI;
    'IO43':'(43)';BIDI;
    'IO44':'(44)';BIDI;
    'IO45':'(45)';BIDI;
    'IO46':'(46)';BIDI;
    'IO47':'(47)';BIDI;
    'IO48':'(48)';BIDI;
    'IO49':'(49)';BIDI;
    'IO5':'(5)';BIDI;
    'IO50':'(50)';BIDI;
    'IO51':'(51)';BIDI;
    'IO52':'(52)';BIDI;
    'IO53':'(53)';BIDI;
    'IO54':'(54)';BIDI;
    'IO55':'(55)';BIDI;
    'IO56':'(56)';BIDI;
    'IO57':'(57)';BIDI;
    'IO58':'(58)';BIDI;
    'IO59':'(59)';BIDI;
    'IO6':'(6)';BIDI;
    'IO60':'(60)';BIDI;
    'IO61':'(61)';BIDI;
    'IO62':'(62)';BIDI;
    'IO63':'(63)';BIDI;
    'IO64':'(64)';BIDI;
    'IO65':'(65)';BIDI;
    'IO66':'(66)';BIDI;
    'IO67':'(67)';BIDI;
    'IO68':'(68)';BIDI;
    'IO69':'(69)';BIDI;
    'IO7':'(7)';BIDI;
    'IO70':'(70)';BIDI;
    'IO71':'(71)';BIDI;
    'IO72':'(72)';BIDI;
    'IO73':'(73)';BIDI;
    'IO74':'(74)';BIDI;
    'IO75':'(75)';BIDI;
    'IO76':'(76)';BIDI;
    'IO77':'(77)';BIDI;
    'IO78':'(78)';BIDI;
    'IO79':'(79)';BIDI;
    'IO8':'(8)';BIDI;
    'IO80':'(80)';BIDI;
    'IO81':'(81)';BIDI;
    'IO82':'(82)';BIDI;
    'IO83':'(83)';BIDI;
    'IO84':'(84)';BIDI;
    'IO85':'(85)';BIDI;
    'IO86':'(86)';BIDI;
    'IO87':'(87)';BIDI;
    'IO88':'(88)';BIDI;
    'IO89':'(89)';BIDI;
    'IO9':'(9)';BIDI;
    'IO90':'(90)';BIDI;
    'IO91':'(91)';BIDI;
    'IO92':'(92)';BIDI;
    'IO93':'(93)';BIDI;
    'IO94':'(94)';BIDI;
    'IO95':'(95)';BIDI;
    'IO96':'(96)';BIDI;
    'IO97':'(97)';BIDI;
    'IO98':'(98)';BIDI;
    'IO99':'(99)';BIDI;
end_primitive;
primitive 'SCONN120_H61426002_SM-CONN,H61A';body 'SCONN120_H61426002';
    'IOA1':'(A1)';BIDI;
    'IOA10':'(A10)';BIDI;
    'IOA11':'(A11)';BIDI;
    'IOA12':'(A12)';BIDI;
    'IOA13':'(A13)';BIDI;
    'IOA14':'(A14)';BIDI;
    'IOA15':'(A15)';BIDI;
    'IOA16':'(A16)';BIDI;
    'IOA17':'(A17)';BIDI;
    'IOA18':'(A18)';BIDI;
    'IOA19':'(A19)';BIDI;
    'IOA2':'(A2)';BIDI;
    'IOA20':'(A20)';BIDI;
    'IOA3':'(A3)';BIDI;
    'IOA4':'(A4)';BIDI;
    'IOA5':'(A5)';BIDI;
    'IOA6':'(A6)';BIDI;
    'IOA7':'(A7)';BIDI;
    'IOA8':'(A8)';BIDI;
    'IOA9':'(A9)';BIDI;
    'IOB1':'(B1)';BIDI;
    'IOB10':'(B10)';BIDI;
    'IOB11':'(B11)';BIDI;
    'IOB12':'(B12)';BIDI;
    'IOB13':'(B13)';BIDI;
    'IOB14':'(B14)';BIDI;
    'IOB15':'(B15)';BIDI;
    'IOB16':'(B16)';BIDI;
    'IOB17':'(B17)';BIDI;
    'IOB18':'(B18)';BIDI;
    'IOB19':'(B19)';BIDI;
    'IOB2':'(B2)';BIDI;
    'IOB20':'(B20)';BIDI;
    'IOB3':'(B3)';BIDI;
    'IOB4':'(B4)';BIDI;
    'IOB5':'(B5)';BIDI;
    'IOB6':'(B6)';BIDI;
    'IOB7':'(B7)';BIDI;
    'IOB8':'(B8)';BIDI;
    'IOB9':'(B9)';BIDI;
    'IOC1':'(C1)';BIDI;
    'IOC10':'(C10)';BIDI;
    'IOC11':'(C11)';BIDI;
    'IOC12':'(C12)';BIDI;
    'IOC13':'(C13)';BIDI;
    'IOC14':'(C14)';BIDI;
    'IOC15':'(C15)';BIDI;
    'IOC16':'(C16)';BIDI;
    'IOC17':'(C17)';BIDI;
    'IOC18':'(C18)';BIDI;
    'IOC19':'(C19)';BIDI;
    'IOC2':'(C2)';BIDI;
    'IOC20':'(C20)';BIDI;
    'IOC3':'(C3)';BIDI;
    'IOC4':'(C4)';BIDI;
    'IOC5':'(C5)';BIDI;
    'IOC6':'(C6)';BIDI;
    'IOC7':'(C7)';BIDI;
    'IOC8':'(C8)';BIDI;
    'IOC9':'(C9)';BIDI;
    'IOD1':'(D1)';BIDI;
    'IOD10':'(D10)';BIDI;
    'IOD11':'(D11)';BIDI;
    'IOD12':'(D12)';BIDI;
    'IOD13':'(D13)';BIDI;
    'IOD14':'(D14)';BIDI;
    'IOD15':'(D15)';BIDI;
    'IOD16':'(D16)';BIDI;
    'IOD17':'(D17)';BIDI;
    'IOD18':'(D18)';BIDI;
    'IOD19':'(D19)';BIDI;
    'IOD2':'(D2)';BIDI;
    'IOD20':'(D20)';BIDI;
    'IOD3':'(D3)';BIDI;
    'IOD4':'(D4)';BIDI;
    'IOD5':'(D5)';BIDI;
    'IOD6':'(D6)';BIDI;
    'IOD7':'(D7)';BIDI;
    'IOD8':'(D8)';BIDI;
    'IOD9':'(D9)';BIDI;
    'IOE1':'(E1)';BIDI;
    'IOE10':'(E10)';BIDI;
    'IOE11':'(E11)';BIDI;
    'IOE12':'(E12)';BIDI;
    'IOE13':'(E13)';BIDI;
    'IOE14':'(E14)';BIDI;
    'IOE15':'(E15)';BIDI;
    'IOE16':'(E16)';BIDI;
    'IOE17':'(E17)';BIDI;
    'IOE18':'(E18)';BIDI;
    'IOE19':'(E19)';BIDI;
    'IOE2':'(E2)';BIDI;
    'IOE20':'(E20)';BIDI;
    'IOE3':'(E3)';BIDI;
    'IOE4':'(E4)';BIDI;
    'IOE5':'(E5)';BIDI;
    'IOE6':'(E6)';BIDI;
    'IOE7':'(E7)';BIDI;
    'IOE8':'(E8)';BIDI;
    'IOE9':'(E9)';BIDI;
    'IOF1':'(F1)';BIDI;
    'IOF10':'(F10)';BIDI;
    'IOF11':'(F11)';BIDI;
    'IOF12':'(F12)';BIDI;
    'IOF13':'(F13)';BIDI;
    'IOF14':'(F14)';BIDI;
    'IOF15':'(F15)';BIDI;
    'IOF16':'(F16)';BIDI;
    'IOF17':'(F17)';BIDI;
    'IOF18':'(F18)';BIDI;
    'IOF19':'(F19)';BIDI;
    'IOF2':'(F2)';BIDI;
    'IOF20':'(F20)';BIDI;
    'IOF3':'(F3)';BIDI;
    'IOF4':'(F4)';BIDI;
    'IOF5':'(F5)';BIDI;
    'IOF6':'(F6)';BIDI;
    'IOF7':'(F7)';BIDI;
    'IOF8':'(F8)';BIDI;
    'IOF9':'(F9)';BIDI;
end_primitive;
primitive 'SCONN200_H68296001_SM-CONN,H68A';body 'SCONN200_H68296001';
    'IO1':'(1,0)';$S;BIDI;
    'IO2':'(2,0)';$S;BIDI;
    'IO3':'(3,0)';$S;BIDI;
    'IO4':'(4,0)';$S;BIDI;
    'IO5':'(5,0)';$S;BIDI;
    'IO6':'(6,0)';$S;BIDI;
    'IO7':'(7,0)';$S;BIDI;
    'IO8':'(8,0)';$S;BIDI;
    'IO9':'(9,0)';$S;BIDI;
    'IO10':'(10,0)';$S;BIDI;
    'IO11':'(11,0)';$S;BIDI;
    'IO12':'(12,0)';$S;BIDI;
    'IO13':'(13,0)';$S;BIDI;
    'IO14':'(14,0)';$S;BIDI;
    'IO15':'(15,0)';$S;BIDI;
    'IO16':'(16,0)';$S;BIDI;
    'IO17':'(17,0)';$S;BIDI;
    'IO18':'(18,0)';$S;BIDI;
    'IO19':'(19,0)';$S;BIDI;
    'IO20':'(20,0)';$S;BIDI;
    'IO21':'(21,0)';$S;BIDI;
    'IO22':'(22,0)';$S;BIDI;
    'IO23':'(23,0)';$S;BIDI;
    'IO24':'(24,0)';$S;BIDI;
    'IO25':'(25,0)';$S;BIDI;
    'IO26':'(26,0)';$S;BIDI;
    'IO27':'(27,0)';$S;BIDI;
    'IO28':'(28,0)';$S;BIDI;
    'IO29':'(29,0)';$S;BIDI;
    'IO30':'(30,0)';$S;BIDI;
    'IO31':'(31,0)';$S;BIDI;
    'IO32':'(32,0)';$S;BIDI;
    'IO33':'(33,0)';$S;BIDI;
    'IO34':'(34,0)';$S;BIDI;
    'IO35':'(35,0)';$S;BIDI;
    'IO36':'(36,0)';$S;BIDI;
    'IO37':'(37,0)';$S;BIDI;
    'IO38':'(38,0)';$S;BIDI;
    'IO39':'(39,0)';$S;BIDI;
    'IO40':'(40,0)';$S;BIDI;
    'IO41':'(41,0)';$S;BIDI;
    'IO42':'(42,0)';$S;BIDI;
    'IO43':'(43,0)';$S;BIDI;
    'IO44':'(44,0)';$S;BIDI;
    'IO45':'(45,0)';$S;BIDI;
    'IO46':'(46,0)';$S;BIDI;
    'IO47':'(47,0)';$S;BIDI;
    'IO48':'(48,0)';$S;BIDI;
    'IO49':'(49,0)';$S;BIDI;
    'IO50':'(50,0)';$S;BIDI;
    'IO51':'(51,0)';$S;BIDI;
    'IO52':'(52,0)';$S;BIDI;
    'IO53':'(53,0)';$S;BIDI;
    'IO54':'(54,0)';$S;BIDI;
    'IO55':'(55,0)';$S;BIDI;
    'IO56':'(56,0)';$S;BIDI;
    'IO57':'(57,0)';$S;BIDI;
    'IO58':'(58,0)';$S;BIDI;
    'IO59':'(59,0)';$S;BIDI;
    'IO60':'(60,0)';$S;BIDI;
    'IO61':'(61,0)';$S;BIDI;
    'IO62':'(62,0)';$S;BIDI;
    'IO63':'(63,0)';$S;BIDI;
    'IO64':'(64,0)';$S;BIDI;
    'IO65':'(65,0)';$S;BIDI;
    'IO66':'(66,0)';$S;BIDI;
    'IO67':'(67,0)';$S;BIDI;
    'IO68':'(68,0)';$S;BIDI;
    'IO69':'(69,0)';$S;BIDI;
    'IO70':'(70,0)';$S;BIDI;
    'IO71':'(71,0)';$S;BIDI;
    'IO72':'(72,0)';$S;BIDI;
    'IO73':'(73,0)';$S;BIDI;
    'IO74':'(74,0)';$S;BIDI;
    'IO75':'(75,0)';$S;BIDI;
    'IO76':'(76,0)';$S;BIDI;
    'IO77':'(77,0)';$S;BIDI;
    'IO78':'(78,0)';$S;BIDI;
    'IO79':'(79,0)';$S;BIDI;
    'IO80':'(80,0)';$S;BIDI;
    'IO81':'(81,0)';$S;BIDI;
    'IO82':'(82,0)';$S;BIDI;
    'IO83':'(83,0)';$S;BIDI;
    'IO84':'(84,0)';$S;BIDI;
    'IO85':'(85,0)';$S;BIDI;
    'IO86':'(86,0)';$S;BIDI;
    'IO87':'(87,0)';$S;BIDI;
    'IO88':'(88,0)';$S;BIDI;
    'IO89':'(89,0)';$S;BIDI;
    'IO90':'(90,0)';$S;BIDI;
    'IO91':'(91,0)';$S;BIDI;
    'IO92':'(92,0)';$S;BIDI;
    'IO93':'(93,0)';$S;BIDI;
    'IO94':'(94,0)';$S;BIDI;
    'IO95':'(95,0)';$S;BIDI;
    'IO96':'(96,0)';$S;BIDI;
    'IO97':'(97,0)';$S;BIDI;
    'IO98':'(98,0)';$S;BIDI;
    'IO99':'(99,0)';$S;BIDI;
    'IO100':'(100,0)';$S;BIDI;
    'IO101':'(0,101)';$S;BIDI;
    'IO102':'(0,102)';$S;BIDI;
    'IO103':'(0,103)';$S;BIDI;
    'IO104':'(0,104)';$S;BIDI;
    'IO105':'(0,105)';$S;BIDI;
    'IO106':'(0,106)';$S;BIDI;
    'IO107':'(0,107)';$S;BIDI;
    'IO108':'(0,108)';$S;BIDI;
    'IO109':'(0,109)';$S;BIDI;
    'IO110':'(0,110)';$S;BIDI;
    'IO111':'(0,111)';$S;BIDI;
    'IO112':'(0,112)';$S;BIDI;
    'IO113':'(0,113)';$S;BIDI;
    'IO114':'(0,114)';$S;BIDI;
    'IO115':'(0,115)';$S;BIDI;
    'IO116':'(0,116)';$S;BIDI;
    'IO117':'(0,117)';$S;BIDI;
    'IO118':'(0,118)';$S;BIDI;
    'IO119':'(0,119)';$S;BIDI;
    'IO120':'(0,120)';$S;BIDI;
    'IO121':'(0,121)';$S;BIDI;
    'IO122':'(0,122)';$S;BIDI;
    'IO123':'(0,123)';$S;BIDI;
    'IO124':'(0,124)';$S;BIDI;
    'IO125':'(0,125)';$S;BIDI;
    'IO126':'(0,126)';$S;BIDI;
    'IO127':'(0,127)';$S;BIDI;
    'IO128':'(0,128)';$S;BIDI;
    'IO129':'(0,129)';$S;BIDI;
    'IO130':'(0,130)';$S;BIDI;
    'IO131':'(0,131)';$S;BIDI;
    'IO132':'(0,132)';$S;BIDI;
    'IO133':'(0,133)';$S;BIDI;
    'IO134':'(0,134)';$S;BIDI;
    'IO135':'(0,135)';$S;BIDI;
    'IO136':'(0,136)';$S;BIDI;
    'IO137':'(0,137)';$S;BIDI;
    'IO138':'(0,138)';$S;BIDI;
    'IO139':'(0,139)';$S;BIDI;
    'IO140':'(0,140)';$S;BIDI;
    'IO141':'(0,141)';$S;BIDI;
    'IO142':'(0,142)';$S;BIDI;
    'IO143':'(0,143)';$S;BIDI;
    'IO144':'(0,144)';$S;BIDI;
    'IO145':'(0,145)';$S;BIDI;
    'IO146':'(0,146)';$S;BIDI;
    'IO147':'(0,147)';$S;BIDI;
    'IO148':'(0,148)';$S;BIDI;
    'IO149':'(0,149)';$S;BIDI;
    'IO150':'(0,150)';$S;BIDI;
    'IO151':'(0,151)';$S;BIDI;
    'IO152':'(0,152)';$S;BIDI;
    'IO153':'(0,153)';$S;BIDI;
    'IO154':'(0,154)';$S;BIDI;
    'IO155':'(0,155)';$S;BIDI;
    'IO156':'(0,156)';$S;BIDI;
    'IO157':'(0,157)';$S;BIDI;
    'IO158':'(0,158)';$S;BIDI;
    'IO159':'(0,159)';$S;BIDI;
    'IO160':'(0,160)';$S;BIDI;
    'IO161':'(0,161)';$S;BIDI;
    'IO162':'(0,162)';$S;BIDI;
    'IO163':'(0,163)';$S;BIDI;
    'IO164':'(0,164)';$S;BIDI;
    'IO165':'(0,165)';$S;BIDI;
    'IO166':'(0,166)';$S;BIDI;
    'IO167':'(0,167)';$S;BIDI;
    'IO168':'(0,168)';$S;BIDI;
    'IO169':'(0,169)';$S;BIDI;
    'IO170':'(0,170)';$S;BIDI;
    'IO171':'(0,171)';$S;BIDI;
    'IO172':'(0,172)';$S;BIDI;
    'IO173':'(0,173)';$S;BIDI;
    'IO174':'(0,174)';$S;BIDI;
    'IO175':'(0,175)';$S;BIDI;
    'IO176':'(0,176)';$S;BIDI;
    'IO177':'(0,177)';$S;BIDI;
    'IO178':'(0,178)';$S;BIDI;
    'IO179':'(0,179)';$S;BIDI;
    'IO180':'(0,180)';$S;BIDI;
    'IO181':'(0,181)';$S;BIDI;
    'IO182':'(0,182)';$S;BIDI;
    'IO183':'(0,183)';$S;BIDI;
    'IO184':'(0,184)';$S;BIDI;
    'IO185':'(0,185)';$S;BIDI;
    'IO186':'(0,186)';$S;BIDI;
    'IO187':'(0,187)';$S;BIDI;
    'IO188':'(0,188)';$S;BIDI;
    'IO189':'(0,189)';$S;BIDI;
    'IO190':'(0,190)';$S;BIDI;
    'IO191':'(0,191)';$S;BIDI;
    'IO192':'(0,192)';$S;BIDI;
    'IO193':'(0,193)';$S;BIDI;
    'IO194':'(0,194)';$S;BIDI;
    'IO195':'(0,195)';$S;BIDI;
    'IO196':'(0,196)';$S;BIDI;
    'IO197':'(0,197)';$S;BIDI;
    'IO198':'(0,198)';$S;BIDI;
    'IO199':'(0,199)';$S;BIDI;
    'IO200':'(0,200)';$S;BIDI;
    'MH1':'(MH1,0)';$S;
    'MH2':'(MH2,0)';$S;
end_primitive;
primitive 'SCONN24_H46321001_SM-SCONN,H46A';body 'SCONN24_H46321001';
    'IO1':'(1)';BIDI;
    'IO10':'(10)';BIDI;
    'IO11':'(11)';BIDI;
    'IO12':'(12)';BIDI;
    'IO13':'(13)';BIDI;
    'IO14':'(14)';BIDI;
    'IO15':'(15)';BIDI;
    'IO16':'(16)';BIDI;
    'IO17':'(17)';BIDI;
    'IO18':'(18)';BIDI;
    'IO19':'(19)';BIDI;
    'IO2':'(2)';BIDI;
    'IO20':'(20)';BIDI;
    'IO21':'(21)';BIDI;
    'IO22':'(22)';BIDI;
    'IO23':'(23)';BIDI;
    'IO24':'(24)';BIDI;
    'IO3':'(3)';BIDI;
    'IO4':'(4)';BIDI;
    'IO5':'(5)';BIDI;
    'IO6':'(6)';BIDI;
    'IO7':'(7)';BIDI;
    'IO8':'(8)';BIDI;
    'IO9':'(9)';BIDI;
    'MP1':'(MP1)';
    'MP2':'(MP2)';
end_primitive;
primitive 'SCONN288_H44441003_PIP-SCONN,HA';body 'SCONN288_H44441003';
    '12V'<1>:'(0,0,0,1)';
    '12V'<0>:'(0,0,0,145)';
    'A0':'(79,0,0,0)';$S;BIDI;
    'A1':'(72,0,0,0)';$S;BIDI;
    'A10':'(225,0,0,0)';$S;BIDI;
    'A11':'(210,0,0,0)';$S;BIDI;
    'A12':'(65,0,0,0)';$S;BIDI;
    'A13':'(232,0,0,0)';$S;BIDI;
    'A14_WE_N':'(228,0,0,0)';$S;BIDI;
    'A15_CAS_N':'(86,0,0,0)';$S;BIDI;
    'A16_RAS_N':'(82,0,0,0)';$S;BIDI;
    'A17':'(234,0,0,0)';$S;BIDI;
    'A2':'(216,0,0,0)';$S;BIDI;
    'A3':'(71,0,0,0)';$S;BIDI;
    'A4':'(214,0,0,0)';$S;BIDI;
    'A5':'(213,0,0,0)';$S;BIDI;
    'A6':'(69,0,0,0)';$S;BIDI;
    'A7':'(211,0,0,0)';$S;BIDI;
    'A8':'(68,0,0,0)';$S;BIDI;
    'A9':'(66,0,0,0)';$S;BIDI;
    'ACT_N':'(62,0,0,0)';$S;BIDI;
    'ALERT_N':'(208,0,0,0)';$S;BIDI;
    'BA'<1>:'(224,0,0,0)';BIDI;
    'BA'<0>:'(81,0,0,0)';BIDI;
    'BG'<1>:'(207,0,0,0)';BIDI;
    'BG'<0>:'(63,0,0,0)';BIDI;
    'C'<2>:'(235,0,0,0)';$S;BIDI;
    'CB'<7>:'(199,0,0,0)';BIDI;
    'CB'<6>:'(54,0,0,0)';BIDI;
    'CB'<5>:'(192,0,0,0)';BIDI;
    'CB'<4>:'(47,0,0,0)';BIDI;
    'CB'<3>:'(201,0,0,0)';BIDI;
    'CB'<2>:'(56,0,0,0)';BIDI;
    'CB'<1>:'(194,0,0,0)';BIDI;
    'CB'<0>:'(49,0,0,0)';BIDI;
    'CK0N':'(75,0,0,0)';$S;BIDI;
    'CK0P':'(74,0,0,0)';$S;BIDI;
    'CK1N':'(219,0,0,0)';$S;BIDI;
    'CK1P':'(218,0,0,0)';$S;BIDI;
    'CKE'<1>:'(203,0,0,0)';BIDI;
    'CKE'<0>:'(60,0,0,0)';BIDI;
    'DQ'<63>:'(280,0,0,0)';BIDI;
    'DQ'<62>:'(135,0,0,0)';BIDI;
    'DQ'<61>:'(273,0,0,0)';BIDI;
    'DQ'<60>:'(128,0,0,0)';BIDI;
    'DQ'<59>:'(282,0,0,0)';BIDI;
    'DQ'<58>:'(137,0,0,0)';BIDI;
    'DQ'<57>:'(275,0,0,0)';BIDI;
    'DQ'<56>:'(130,0,0,0)';BIDI;
    'DQ'<55>:'(269,0,0,0)';BIDI;
    'DQ'<54>:'(124,0,0,0)';BIDI;
    'DQ'<53>:'(262,0,0,0)';BIDI;
    'DQ'<52>:'(117,0,0,0)';BIDI;
    'DQ'<51>:'(271,0,0,0)';BIDI;
    'DQ'<50>:'(126,0,0,0)';BIDI;
    'DQ'<49>:'(264,0,0,0)';BIDI;
    'DQ'<48>:'(119,0,0,0)';BIDI;
    'DQ'<47>:'(258,0,0,0)';BIDI;
    'DQ'<46>:'(113,0,0,0)';BIDI;
    'DQ'<45>:'(251,0,0,0)';BIDI;
    'DQ'<44>:'(106,0,0,0)';BIDI;
    'DQ'<43>:'(260,0,0,0)';BIDI;
    'DQ'<42>:'(115,0,0,0)';BIDI;
    'DQ'<41>:'(253,0,0,0)';BIDI;
    'DQ'<40>:'(108,0,0,0)';BIDI;
    'DQ'<39>:'(247,0,0,0)';BIDI;
    'DQ'<38>:'(102,0,0,0)';BIDI;
    'DQ'<37>:'(240,0,0,0)';BIDI;
    'DQ'<36>:'(95,0,0,0)';BIDI;
    'DQ'<35>:'(249,0,0,0)';BIDI;
    'DQ'<34>:'(104,0,0,0)';BIDI;
    'DQ'<33>:'(242,0,0,0)';BIDI;
    'DQ'<32>:'(97,0,0,0)';BIDI;
    'DQ'<31>:'(188,0,0,0)';BIDI;
    'DQ'<30>:'(43,0,0,0)';BIDI;
    'DQ'<29>:'(181,0,0,0)';BIDI;
    'DQ'<28>:'(36,0,0,0)';BIDI;
    'DQ'<27>:'(190,0,0,0)';BIDI;
    'DQ'<26>:'(45,0,0,0)';BIDI;
    'DQ'<25>:'(183,0,0,0)';BIDI;
    'DQ'<24>:'(38,0,0,0)';BIDI;
    'DQ'<23>:'(177,0,0,0)';BIDI;
    'DQ'<22>:'(32,0,0,0)';BIDI;
    'DQ'<21>:'(170,0,0,0)';BIDI;
    'DQ'<20>:'(25,0,0,0)';BIDI;
    'DQ'<19>:'(179,0,0,0)';BIDI;
    'DQ'<18>:'(34,0,0,0)';BIDI;
    'DQ'<17>:'(172,0,0,0)';BIDI;
    'DQ'<16>:'(27,0,0,0)';BIDI;
    'DQ'<15>:'(166,0,0,0)';BIDI;
    'DQ'<14>:'(21,0,0,0)';BIDI;
    'DQ'<13>:'(159,0,0,0)';BIDI;
    'DQ'<12>:'(14,0,0,0)';BIDI;
    'DQ'<11>:'(168,0,0,0)';BIDI;
    'DQ'<10>:'(23,0,0,0)';BIDI;
    'DQ'<9>:'(161,0,0,0)';BIDI;
    'DQ'<8>:'(16,0,0,0)';BIDI;
    'DQ'<7>:'(155,0,0,0)';BIDI;
    'DQ'<6>:'(10,0,0,0)';BIDI;
    'DQ'<5>:'(148,0,0,0)';BIDI;
    'DQ'<4>:'(3,0,0,0)';BIDI;
    'DQ'<3>:'(157,0,0,0)';BIDI;
    'DQ'<2>:'(12,0,0,0)';BIDI;
    'DQ'<1>:'(150,0,0,0)';BIDI;
    'DQ'<0>:'(5,0,0,0)';BIDI;
    'DQS0N':'(0,152,0,0)';$S;BIDI;
    'DQS0P':'(0,153,0,0)';$S;BIDI;
    'DQS10N':'(0,19,0,0)';$S;BIDI;
    'DQS10P':'(0,18,0,0)';$S;BIDI;
    'DQS11N':'(0,30,0,0)';$S;BIDI;
    'DQS11P':'(0,29,0,0)';$S;BIDI;
    'DQS12N':'(0,41,0,0)';$S;BIDI;
    'DQS12P':'(0,40,0,0)';$S;BIDI;
    'DQS13N':'(0,100,0,0)';$S;BIDI;
    'DQS13P':'(0,99,0,0)';$S;BIDI;
    'DQS14N':'(0,111,0,0)';$S;BIDI;
    'DQS14P':'(0,110,0,0)';$S;BIDI;
    'DQS15N':'(0,122,0,0)';$S;BIDI;
    'DQS15P':'(0,121,0,0)';$S;BIDI;
    'DQS16N':'(0,133,0,0)';$S;BIDI;
    'DQS16P':'(0,132,0,0)';$S;BIDI;
    'DQS17N':'(0,52,0,0)';$S;BIDI;
    'DQS17P':'(0,51,0,0)';$S;BIDI;
    'DQS1N':'(0,163,0,0)';$S;BIDI;
    'DQS1P':'(0,164,0,0)';$S;BIDI;
    'DQS2N':'(0,174,0,0)';$S;BIDI;
    'DQS2P':'(0,175,0,0)';$S;BIDI;
    'DQS3N':'(0,185,0,0)';$S;BIDI;
    'DQS3P':'(0,186,0,0)';$S;BIDI;
    'DQS4N':'(0,244,0,0)';$S;BIDI;
    'DQS4P':'(0,245,0,0)';$S;BIDI;
    'DQS5N':'(0,255,0,0)';$S;BIDI;
    'DQS5P':'(0,256,0,0)';$S;BIDI;
    'DQS6N':'(0,266,0,0)';$S;BIDI;
    'DQS6P':'(0,267,0,0)';$S;BIDI;
    'DQS7N':'(0,277,0,0)';$S;BIDI;
    'DQS7P':'(0,278,0,0)';$S;BIDI;
    'DQS8N':'(0,196,0,0)';$S;BIDI;
    'DQS8P':'(0,197,0,0)';$S;BIDI;
    'DQS9N':'(0,8,0,0)';$S;BIDI;
    'DQS9P':'(0,7,0,0)';$S;BIDI;
    'EVENT_N':'(78,0,0,0)';$S;BIDI;
    'ODT'<1>:'(91,0,0,0)';BIDI;
    'ODT'<0>:'(87,0,0,0)';BIDI;
    'PAR':'(222,0,0,0)';$S;BIDI;
    'RESET_N':'(58,0,0,0)';$S;BIDI;
    'RFU'<2>:'(144,0,0,0)';BIDI;
    'RFU'<1>:'(227,0,0,0)';BIDI;
    'RFU'<0>:'(205,0,0,0)';BIDI;
    'S0_N':'(84,0,0,0)';$S;BIDI;
    'S1_N':'(89,0,0,0)';$S;BIDI;
    'S2_N_C'<0>:'(93,0,0,0)';$S;BIDI;
    'S3_N_C'<1>:'(237,0,0,0)';$S;BIDI;
    'SA'<2>:'(238,0,0,0)';BIDI;
    'SA'<1>:'(140,0,0,0)';BIDI;
    'SA'<0>:'(139,0,0,0)';BIDI;
    'SAVE_N_NC':'(230,0,0,0)';$S;BIDI;
    'SCL':'(141,0,0,0)';$S;BIDI;
    'SDA':'(285,0,0,0)';$S;BIDI;
    'VDD'<25>:'(0,0,0,59)';
    'VDD'<24>:'(0,0,0,61)';
    'VDD'<23>:'(0,0,0,64)';
    'VDD'<22>:'(0,0,0,67)';
    'VDD'<21>:'(0,0,0,70)';
    'VDD'<20>:'(0,0,0,73)';
    'VDD'<19>:'(0,0,0,76)';
    'VDD'<18>:'(0,0,0,80)';
    'VDD'<17>:'(0,0,0,83)';
    'VDD'<16>:'(0,0,0,85)';
    'VDD'<15>:'(0,0,0,88)';
    'VDD'<14>:'(0,0,0,90)';
    'VDD'<13>:'(0,0,0,92)';
    'VDD'<12>:'(0,0,0,204)';
    'VDD'<11>:'(0,0,0,206)';
    'VDD'<10>:'(0,0,0,209)';
    'VDD'<9>:'(0,0,0,212)';
    'VDD'<8>:'(0,0,0,215)';
    'VDD'<7>:'(0,0,0,217)';
    'VDD'<6>:'(0,0,0,220)';
    'VDD'<5>:'(0,0,0,223)';
    'VDD'<4>:'(0,0,0,226)';
    'VDD'<3>:'(0,0,0,229)';
    'VDD'<2>:'(0,0,0,231)';
    'VDD'<1>:'(0,0,0,233)';
    'VDD'<0>:'(0,0,0,236)';
    'VDDSPD':'(284,0,0,0)';$S;BIDI;
    'VPP'<4>:'(0,0,0,142)';
    'VPP'<3>:'(0,0,0,143)';
    'VPP'<2>:'(0,0,0,288)';
    'VPP'<1>:'(0,0,0,286)';
    'VPP'<0>:'(0,0,0,287)';
    'VREFCA':'(146,0,0,0)';$S;BIDI;
    'VSS'<93>:'(0,0,2,0)';
    'VSS'<92>:'(0,0,4,0)';
    'VSS'<91>:'(0,0,6,0)';
    'VSS'<90>:'(0,0,9,0)';
    'VSS'<89>:'(0,0,11,0)';
    'VSS'<88>:'(0,0,13,0)';
    'VSS'<87>:'(0,0,15,0)';
    'VSS'<86>:'(0,0,17,0)';
    'VSS'<85>:'(0,0,20,0)';
    'VSS'<84>:'(0,0,22,0)';
    'VSS'<83>:'(0,0,24,0)';
    'VSS'<82>:'(0,0,26,0)';
    'VSS'<81>:'(0,0,28,0)';
    'VSS'<80>:'(0,0,31,0)';
    'VSS'<79>:'(0,0,33,0)';
    'VSS'<78>:'(0,0,35,0)';
    'VSS'<77>:'(0,0,37,0)';
    'VSS'<76>:'(0,0,39,0)';
    'VSS'<75>:'(0,0,42,0)';
    'VSS'<74>:'(0,0,44,0)';
    'VSS'<73>:'(0,0,46,0)';
    'VSS'<72>:'(0,0,48,0)';
    'VSS'<71>:'(0,0,50,0)';
    'VSS'<70>:'(0,0,53,0)';
    'VSS'<69>:'(0,0,55,0)';
    'VSS'<68>:'(0,0,57,0)';
    'VSS'<67>:'(0,0,94,0)';
    'VSS'<66>:'(0,0,96,0)';
    'VSS'<65>:'(0,0,98,0)';
    'VSS'<64>:'(0,0,101,0)';
    'VSS'<63>:'(0,0,103,0)';
    'VSS'<62>:'(0,0,105,0)';
    'VSS'<61>:'(0,0,107,0)';
    'VSS'<60>:'(0,0,109,0)';
    'VSS'<59>:'(0,0,112,0)';
    'VSS'<58>:'(0,0,114,0)';
    'VSS'<57>:'(0,0,116,0)';
    'VSS'<56>:'(0,0,118,0)';
    'VSS'<55>:'(0,0,120,0)';
    'VSS'<54>:'(0,0,123,0)';
    'VSS'<53>:'(0,0,125,0)';
    'VSS'<52>:'(0,0,127,0)';
    'VSS'<51>:'(0,0,129,0)';
    'VSS'<50>:'(0,0,131,0)';
    'VSS'<49>:'(0,0,134,0)';
    'VSS'<48>:'(0,0,136,0)';
    'VSS'<47>:'(0,0,138,0)';
    'VSS'<46>:'(0,0,147,0)';
    'VSS'<45>:'(0,0,149,0)';
    'VSS'<44>:'(0,0,151,0)';
    'VSS'<43>:'(0,0,154,0)';
    'VSS'<42>:'(0,0,156,0)';
    'VSS'<41>:'(0,0,158,0)';
    'VSS'<40>:'(0,0,160,0)';
    'VSS'<39>:'(0,0,162,0)';
    'VSS'<38>:'(0,0,165,0)';
    'VSS'<37>:'(0,0,167,0)';
    'VSS'<36>:'(0,0,169,0)';
    'VSS'<35>:'(0,0,171,0)';
    'VSS'<34>:'(0,0,173,0)';
    'VSS'<33>:'(0,0,176,0)';
    'VSS'<32>:'(0,0,178,0)';
    'VSS'<31>:'(0,0,180,0)';
    'VSS'<30>:'(0,0,182,0)';
    'VSS'<29>:'(0,0,184,0)';
    'VSS'<28>:'(0,0,187,0)';
    'VSS'<27>:'(0,0,189,0)';
    'VSS'<26>:'(0,0,191,0)';
    'VSS'<25>:'(0,0,193,0)';
    'VSS'<24>:'(0,0,195,0)';
    'VSS'<23>:'(0,0,198,0)';
    'VSS'<22>:'(0,0,200,0)';
    'VSS'<21>:'(0,0,202,0)';
    'VSS'<20>:'(0,0,239,0)';
    'VSS'<19>:'(0,0,241,0)';
    'VSS'<18>:'(0,0,243,0)';
    'VSS'<17>:'(0,0,246,0)';
    'VSS'<16>:'(0,0,248,0)';
    'VSS'<15>:'(0,0,250,0)';
    'VSS'<14>:'(0,0,252,0)';
    'VSS'<13>:'(0,0,254,0)';
    'VSS'<12>:'(0,0,257,0)';
    'VSS'<11>:'(0,0,259,0)';
    'VSS'<10>:'(0,0,261,0)';
    'VSS'<9>:'(0,0,263,0)';
    'VSS'<8>:'(0,0,265,0)';
    'VSS'<7>:'(0,0,268,0)';
    'VSS'<6>:'(0,0,270,0)';
    'VSS'<5>:'(0,0,272,0)';
    'VSS'<4>:'(0,0,274,0)';
    'VSS'<3>:'(0,0,276,0)';
    'VSS'<2>:'(0,0,279,0)';
    'VSS'<1>:'(0,0,281,0)';
    'VSS'<0>:'(0,0,283,0)';
    'VTT'<1>:'(0,0,0,77)';
    'VTT'<0>:'(0,0,0,221)';
end_primitive;
primitive 'SCONN288_H44441004_PIP-SCONN,HA';body 'SCONN288_H44441004';
    '12V'<1>:'(0,0,0,1)';
    '12V'<0>:'(0,0,0,145)';
    'A0':'(79,0,0,0)';$S;BIDI;
    'A1':'(72,0,0,0)';$S;BIDI;
    'A10':'(225,0,0,0)';$S;BIDI;
    'A11':'(210,0,0,0)';$S;BIDI;
    'A12':'(65,0,0,0)';$S;BIDI;
    'A13':'(232,0,0,0)';$S;BIDI;
    'A14_WE_N':'(228,0,0,0)';$S;BIDI;
    'A15_CAS_N':'(86,0,0,0)';$S;BIDI;
    'A16_RAS_N':'(82,0,0,0)';$S;BIDI;
    'A17':'(234,0,0,0)';$S;BIDI;
    'A2':'(216,0,0,0)';$S;BIDI;
    'A3':'(71,0,0,0)';$S;BIDI;
    'A4':'(214,0,0,0)';$S;BIDI;
    'A5':'(213,0,0,0)';$S;BIDI;
    'A6':'(69,0,0,0)';$S;BIDI;
    'A7':'(211,0,0,0)';$S;BIDI;
    'A8':'(68,0,0,0)';$S;BIDI;
    'A9':'(66,0,0,0)';$S;BIDI;
    'ACT_N':'(62,0,0,0)';$S;BIDI;
    'ALERT_N':'(208,0,0,0)';$S;BIDI;
    'BA'<1>:'(224,0,0,0)';BIDI;
    'BA'<0>:'(81,0,0,0)';BIDI;
    'BG'<1>:'(207,0,0,0)';BIDI;
    'BG'<0>:'(63,0,0,0)';BIDI;
    'C'<2>:'(235,0,0,0)';$S;BIDI;
    'CB'<7>:'(199,0,0,0)';BIDI;
    'CB'<6>:'(54,0,0,0)';BIDI;
    'CB'<5>:'(192,0,0,0)';BIDI;
    'CB'<4>:'(47,0,0,0)';BIDI;
    'CB'<3>:'(201,0,0,0)';BIDI;
    'CB'<2>:'(56,0,0,0)';BIDI;
    'CB'<1>:'(194,0,0,0)';BIDI;
    'CB'<0>:'(49,0,0,0)';BIDI;
    'CK0N':'(75,0,0,0)';$S;BIDI;
    'CK0P':'(74,0,0,0)';$S;BIDI;
    'CK1N':'(219,0,0,0)';$S;BIDI;
    'CK1P':'(218,0,0,0)';$S;BIDI;
    'CKE'<1>:'(203,0,0,0)';BIDI;
    'CKE'<0>:'(60,0,0,0)';BIDI;
    'DQ'<63>:'(280,0,0,0)';BIDI;
    'DQ'<62>:'(135,0,0,0)';BIDI;
    'DQ'<61>:'(273,0,0,0)';BIDI;
    'DQ'<60>:'(128,0,0,0)';BIDI;
    'DQ'<59>:'(282,0,0,0)';BIDI;
    'DQ'<58>:'(137,0,0,0)';BIDI;
    'DQ'<57>:'(275,0,0,0)';BIDI;
    'DQ'<56>:'(130,0,0,0)';BIDI;
    'DQ'<55>:'(269,0,0,0)';BIDI;
    'DQ'<54>:'(124,0,0,0)';BIDI;
    'DQ'<53>:'(262,0,0,0)';BIDI;
    'DQ'<52>:'(117,0,0,0)';BIDI;
    'DQ'<51>:'(271,0,0,0)';BIDI;
    'DQ'<50>:'(126,0,0,0)';BIDI;
    'DQ'<49>:'(264,0,0,0)';BIDI;
    'DQ'<48>:'(119,0,0,0)';BIDI;
    'DQ'<47>:'(258,0,0,0)';BIDI;
    'DQ'<46>:'(113,0,0,0)';BIDI;
    'DQ'<45>:'(251,0,0,0)';BIDI;
    'DQ'<44>:'(106,0,0,0)';BIDI;
    'DQ'<43>:'(260,0,0,0)';BIDI;
    'DQ'<42>:'(115,0,0,0)';BIDI;
    'DQ'<41>:'(253,0,0,0)';BIDI;
    'DQ'<40>:'(108,0,0,0)';BIDI;
    'DQ'<39>:'(247,0,0,0)';BIDI;
    'DQ'<38>:'(102,0,0,0)';BIDI;
    'DQ'<37>:'(240,0,0,0)';BIDI;
    'DQ'<36>:'(95,0,0,0)';BIDI;
    'DQ'<35>:'(249,0,0,0)';BIDI;
    'DQ'<34>:'(104,0,0,0)';BIDI;
    'DQ'<33>:'(242,0,0,0)';BIDI;
    'DQ'<32>:'(97,0,0,0)';BIDI;
    'DQ'<31>:'(188,0,0,0)';BIDI;
    'DQ'<30>:'(43,0,0,0)';BIDI;
    'DQ'<29>:'(181,0,0,0)';BIDI;
    'DQ'<28>:'(36,0,0,0)';BIDI;
    'DQ'<27>:'(190,0,0,0)';BIDI;
    'DQ'<26>:'(45,0,0,0)';BIDI;
    'DQ'<25>:'(183,0,0,0)';BIDI;
    'DQ'<24>:'(38,0,0,0)';BIDI;
    'DQ'<23>:'(177,0,0,0)';BIDI;
    'DQ'<22>:'(32,0,0,0)';BIDI;
    'DQ'<21>:'(170,0,0,0)';BIDI;
    'DQ'<20>:'(25,0,0,0)';BIDI;
    'DQ'<19>:'(179,0,0,0)';BIDI;
    'DQ'<18>:'(34,0,0,0)';BIDI;
    'DQ'<17>:'(172,0,0,0)';BIDI;
    'DQ'<16>:'(27,0,0,0)';BIDI;
    'DQ'<15>:'(166,0,0,0)';BIDI;
    'DQ'<14>:'(21,0,0,0)';BIDI;
    'DQ'<13>:'(159,0,0,0)';BIDI;
    'DQ'<12>:'(14,0,0,0)';BIDI;
    'DQ'<11>:'(168,0,0,0)';BIDI;
    'DQ'<10>:'(23,0,0,0)';BIDI;
    'DQ'<9>:'(161,0,0,0)';BIDI;
    'DQ'<8>:'(16,0,0,0)';BIDI;
    'DQ'<7>:'(155,0,0,0)';BIDI;
    'DQ'<6>:'(10,0,0,0)';BIDI;
    'DQ'<5>:'(148,0,0,0)';BIDI;
    'DQ'<4>:'(3,0,0,0)';BIDI;
    'DQ'<3>:'(157,0,0,0)';BIDI;
    'DQ'<2>:'(12,0,0,0)';BIDI;
    'DQ'<1>:'(150,0,0,0)';BIDI;
    'DQ'<0>:'(5,0,0,0)';BIDI;
    'DQS0N':'(0,152,0,0)';$S;BIDI;
    'DQS0P':'(0,153,0,0)';$S;BIDI;
    'DQS10N':'(0,19,0,0)';$S;BIDI;
    'DQS10P':'(0,18,0,0)';$S;BIDI;
    'DQS11N':'(0,30,0,0)';$S;BIDI;
    'DQS11P':'(0,29,0,0)';$S;BIDI;
    'DQS12N':'(0,41,0,0)';$S;BIDI;
    'DQS12P':'(0,40,0,0)';$S;BIDI;
    'DQS13N':'(0,100,0,0)';$S;BIDI;
    'DQS13P':'(0,99,0,0)';$S;BIDI;
    'DQS14N':'(0,111,0,0)';$S;BIDI;
    'DQS14P':'(0,110,0,0)';$S;BIDI;
    'DQS15N':'(0,122,0,0)';$S;BIDI;
    'DQS15P':'(0,121,0,0)';$S;BIDI;
    'DQS16N':'(0,133,0,0)';$S;BIDI;
    'DQS16P':'(0,132,0,0)';$S;BIDI;
    'DQS17N':'(0,52,0,0)';$S;BIDI;
    'DQS17P':'(0,51,0,0)';$S;BIDI;
    'DQS1N':'(0,163,0,0)';$S;BIDI;
    'DQS1P':'(0,164,0,0)';$S;BIDI;
    'DQS2N':'(0,174,0,0)';$S;BIDI;
    'DQS2P':'(0,175,0,0)';$S;BIDI;
    'DQS3N':'(0,185,0,0)';$S;BIDI;
    'DQS3P':'(0,186,0,0)';$S;BIDI;
    'DQS4N':'(0,244,0,0)';$S;BIDI;
    'DQS4P':'(0,245,0,0)';$S;BIDI;
    'DQS5N':'(0,255,0,0)';$S;BIDI;
    'DQS5P':'(0,256,0,0)';$S;BIDI;
    'DQS6N':'(0,266,0,0)';$S;BIDI;
    'DQS6P':'(0,267,0,0)';$S;BIDI;
    'DQS7N':'(0,277,0,0)';$S;BIDI;
    'DQS7P':'(0,278,0,0)';$S;BIDI;
    'DQS8N':'(0,196,0,0)';$S;BIDI;
    'DQS8P':'(0,197,0,0)';$S;BIDI;
    'DQS9N':'(0,8,0,0)';$S;BIDI;
    'DQS9P':'(0,7,0,0)';$S;BIDI;
    'EVENT_N':'(78,0,0,0)';$S;BIDI;
    'ODT'<1>:'(91,0,0,0)';BIDI;
    'ODT'<0>:'(87,0,0,0)';BIDI;
    'PAR':'(222,0,0,0)';$S;BIDI;
    'RESET_N':'(58,0,0,0)';$S;BIDI;
    'RFU'<2>:'(144,0,0,0)';BIDI;
    'RFU'<1>:'(227,0,0,0)';BIDI;
    'RFU'<0>:'(205,0,0,0)';BIDI;
    'S0_N':'(84,0,0,0)';$S;BIDI;
    'S1_N':'(89,0,0,0)';$S;BIDI;
    'S2_N_C'<0>:'(93,0,0,0)';$S;BIDI;
    'S3_N_C'<1>:'(237,0,0,0)';$S;BIDI;
    'SA'<2>:'(238,0,0,0)';BIDI;
    'SA'<1>:'(140,0,0,0)';BIDI;
    'SA'<0>:'(139,0,0,0)';BIDI;
    'SAVE_N_NC':'(230,0,0,0)';$S;BIDI;
    'SCL':'(141,0,0,0)';$S;BIDI;
    'SDA':'(285,0,0,0)';$S;BIDI;
    'VDD'<25>:'(0,0,0,59)';
    'VDD'<24>:'(0,0,0,61)';
    'VDD'<23>:'(0,0,0,64)';
    'VDD'<22>:'(0,0,0,67)';
    'VDD'<21>:'(0,0,0,70)';
    'VDD'<20>:'(0,0,0,73)';
    'VDD'<19>:'(0,0,0,76)';
    'VDD'<18>:'(0,0,0,80)';
    'VDD'<17>:'(0,0,0,83)';
    'VDD'<16>:'(0,0,0,85)';
    'VDD'<15>:'(0,0,0,88)';
    'VDD'<14>:'(0,0,0,90)';
    'VDD'<13>:'(0,0,0,92)';
    'VDD'<12>:'(0,0,0,204)';
    'VDD'<11>:'(0,0,0,206)';
    'VDD'<10>:'(0,0,0,209)';
    'VDD'<9>:'(0,0,0,212)';
    'VDD'<8>:'(0,0,0,215)';
    'VDD'<7>:'(0,0,0,217)';
    'VDD'<6>:'(0,0,0,220)';
    'VDD'<5>:'(0,0,0,223)';
    'VDD'<4>:'(0,0,0,226)';
    'VDD'<3>:'(0,0,0,229)';
    'VDD'<2>:'(0,0,0,231)';
    'VDD'<1>:'(0,0,0,233)';
    'VDD'<0>:'(0,0,0,236)';
    'VDDSPD':'(284,0,0,0)';$S;BIDI;
    'VPP'<4>:'(0,0,0,142)';
    'VPP'<3>:'(0,0,0,143)';
    'VPP'<2>:'(0,0,0,288)';
    'VPP'<1>:'(0,0,0,286)';
    'VPP'<0>:'(0,0,0,287)';
    'VREFCA':'(146,0,0,0)';$S;BIDI;
    'VSS'<93>:'(0,0,2,0)';
    'VSS'<92>:'(0,0,4,0)';
    'VSS'<91>:'(0,0,6,0)';
    'VSS'<90>:'(0,0,9,0)';
    'VSS'<89>:'(0,0,11,0)';
    'VSS'<88>:'(0,0,13,0)';
    'VSS'<87>:'(0,0,15,0)';
    'VSS'<86>:'(0,0,17,0)';
    'VSS'<85>:'(0,0,20,0)';
    'VSS'<84>:'(0,0,22,0)';
    'VSS'<83>:'(0,0,24,0)';
    'VSS'<82>:'(0,0,26,0)';
    'VSS'<81>:'(0,0,28,0)';
    'VSS'<80>:'(0,0,31,0)';
    'VSS'<79>:'(0,0,33,0)';
    'VSS'<78>:'(0,0,35,0)';
    'VSS'<77>:'(0,0,37,0)';
    'VSS'<76>:'(0,0,39,0)';
    'VSS'<75>:'(0,0,42,0)';
    'VSS'<74>:'(0,0,44,0)';
    'VSS'<73>:'(0,0,46,0)';
    'VSS'<72>:'(0,0,48,0)';
    'VSS'<71>:'(0,0,50,0)';
    'VSS'<70>:'(0,0,53,0)';
    'VSS'<69>:'(0,0,55,0)';
    'VSS'<68>:'(0,0,57,0)';
    'VSS'<67>:'(0,0,94,0)';
    'VSS'<66>:'(0,0,96,0)';
    'VSS'<65>:'(0,0,98,0)';
    'VSS'<64>:'(0,0,101,0)';
    'VSS'<63>:'(0,0,103,0)';
    'VSS'<62>:'(0,0,105,0)';
    'VSS'<61>:'(0,0,107,0)';
    'VSS'<60>:'(0,0,109,0)';
    'VSS'<59>:'(0,0,112,0)';
    'VSS'<58>:'(0,0,114,0)';
    'VSS'<57>:'(0,0,116,0)';
    'VSS'<56>:'(0,0,118,0)';
    'VSS'<55>:'(0,0,120,0)';
    'VSS'<54>:'(0,0,123,0)';
    'VSS'<53>:'(0,0,125,0)';
    'VSS'<52>:'(0,0,127,0)';
    'VSS'<51>:'(0,0,129,0)';
    'VSS'<50>:'(0,0,131,0)';
    'VSS'<49>:'(0,0,134,0)';
    'VSS'<48>:'(0,0,136,0)';
    'VSS'<47>:'(0,0,138,0)';
    'VSS'<46>:'(0,0,147,0)';
    'VSS'<45>:'(0,0,149,0)';
    'VSS'<44>:'(0,0,151,0)';
    'VSS'<43>:'(0,0,154,0)';
    'VSS'<42>:'(0,0,156,0)';
    'VSS'<41>:'(0,0,158,0)';
    'VSS'<40>:'(0,0,160,0)';
    'VSS'<39>:'(0,0,162,0)';
    'VSS'<38>:'(0,0,165,0)';
    'VSS'<37>:'(0,0,167,0)';
    'VSS'<36>:'(0,0,169,0)';
    'VSS'<35>:'(0,0,171,0)';
    'VSS'<34>:'(0,0,173,0)';
    'VSS'<33>:'(0,0,176,0)';
    'VSS'<32>:'(0,0,178,0)';
    'VSS'<31>:'(0,0,180,0)';
    'VSS'<30>:'(0,0,182,0)';
    'VSS'<29>:'(0,0,184,0)';
    'VSS'<28>:'(0,0,187,0)';
    'VSS'<27>:'(0,0,189,0)';
    'VSS'<26>:'(0,0,191,0)';
    'VSS'<25>:'(0,0,193,0)';
    'VSS'<24>:'(0,0,195,0)';
    'VSS'<23>:'(0,0,198,0)';
    'VSS'<22>:'(0,0,200,0)';
    'VSS'<21>:'(0,0,202,0)';
    'VSS'<20>:'(0,0,239,0)';
    'VSS'<19>:'(0,0,241,0)';
    'VSS'<18>:'(0,0,243,0)';
    'VSS'<17>:'(0,0,246,0)';
    'VSS'<16>:'(0,0,248,0)';
    'VSS'<15>:'(0,0,250,0)';
    'VSS'<14>:'(0,0,252,0)';
    'VSS'<13>:'(0,0,254,0)';
    'VSS'<12>:'(0,0,257,0)';
    'VSS'<11>:'(0,0,259,0)';
    'VSS'<10>:'(0,0,261,0)';
    'VSS'<9>:'(0,0,263,0)';
    'VSS'<8>:'(0,0,265,0)';
    'VSS'<7>:'(0,0,268,0)';
    'VSS'<6>:'(0,0,270,0)';
    'VSS'<5>:'(0,0,272,0)';
    'VSS'<4>:'(0,0,274,0)';
    'VSS'<3>:'(0,0,276,0)';
    'VSS'<2>:'(0,0,279,0)';
    'VSS'<1>:'(0,0,281,0)';
    'VSS'<0>:'(0,0,283,0)';
    'VTT'<1>:'(0,0,0,77)';
    'VTT'<0>:'(0,0,0,221)';
end_primitive;
primitive 'SCONN60_C21100002_SMLF-CONN,C2A';body 'SCONN60_C21100002';
    'IO1':'(1)';
    'IO3':'(3)';
    'IO5':'(5)';
    'IO7':'(7)';
    'IO9':'(9)';
    'IO11':'(11)';
    'IO13':'(13)';
    'IO15':'(15)';
    'IO17':'(17)';
    'IO19':'(19)';
    'IO21':'(21)';
    'IO23':'(23)';
    'IO25':'(25)';
    'IO27':'(27)';
    'IO29':'(29)';
    'IO31':'(31)';
    'IO33':'(33)';
    'IO35':'(35)';
    'IO37':'(37)';
    'IO39':'(39)';
    'IO41':'(41)';
    'IO43':'(43)';
    'IO45':'(45)';
    'IO47':'(47)';
    'IO49':'(49)';
    'IO2':'(2)';
    'IO4':'(4)';
    'IO6':'(6)';
    'IO8':'(8)';
    'IO10':'(10)';
    'IO12':'(12)';
    'IO14':'(14)';
    'IO16':'(16)';
    'IO18':'(18)';
    'IO20':'(20)';
    'IO22':'(22)';
    'IO24':'(24)';
    'IO26':'(26)';
    'IO28':'(28)';
    'IO30':'(30)';
    'IO32':'(32)';
    'IO34':'(34)';
    'IO36':'(36)';
    'IO38':'(38)';
    'IO40':'(40)';
    'IO42':'(42)';
    'IO44':'(44)';
    'IO46':'(46)';
    'IO48':'(48)';
    'IO50':'(50)';
    'IO51':'(51)';
    'IO52':'(52)';
    'IO53':'(53)';
    'IO54':'(54)';
    'IO55':'(55)';
    'IO56':'(56)';
    'IO57':'(57)';
    'IO58':'(58)';
    'IO59':'(59)';
    'IO60':'(60)';
end_primitive;
primitive 'SCONN64_H87568002_A_SMT-CONN,HA';body 'SCONN64_H87568002_A';
    'IO1':'(1)';BIDI;
    'IO10':'(10)';BIDI;
    'IO11':'(11)';BIDI;
    'IO12':'(12)';BIDI;
    'IO13':'(13)';BIDI;
    'IO14':'(14)';BIDI;
    'IO15':'(15)';BIDI;
    'IO16':'(16)';BIDI;
    'IO17':'(17)';BIDI;
    'IO18':'(18)';BIDI;
    'IO19':'(19)';BIDI;
    'IO2':'(2)';BIDI;
    'IO20':'(20)';BIDI;
    'IO21':'(21)';BIDI;
    'IO22':'(22)';BIDI;
    'IO23':'(23)';BIDI;
    'IO24':'(24)';BIDI;
    'IO25':'(25)';BIDI;
    'IO26':'(26)';BIDI;
    'IO27':'(27)';BIDI;
    'IO28':'(28)';BIDI;
    'IO29':'(29)';BIDI;
    'IO3':'(3)';BIDI;
    'IO30':'(30)';BIDI;
    'IO31':'(31)';BIDI;
    'IO32':'(32)';BIDI;
    'IO33':'(33)';BIDI;
    'IO34':'(34)';BIDI;
    'IO35':'(35)';BIDI;
    'IO36':'(36)';BIDI;
    'IO37':'(37)';BIDI;
    'IO38':'(38)';BIDI;
    'IO39':'(39)';BIDI;
    'IO4':'(4)';BIDI;
    'IO40':'(40)';BIDI;
    'IO41':'(41)';BIDI;
    'IO42':'(42)';BIDI;
    'IO43':'(43)';BIDI;
    'IO44':'(44)';BIDI;
    'IO45':'(45)';BIDI;
    'IO46':'(46)';BIDI;
    'IO47':'(47)';BIDI;
    'IO48':'(48)';BIDI;
    'IO49':'(49)';BIDI;
    'IO5':'(5)';BIDI;
    'IO50':'(50)';BIDI;
    'IO51':'(51)';BIDI;
    'IO52':'(52)';BIDI;
    'IO53':'(53)';BIDI;
    'IO54':'(54)';BIDI;
    'IO55':'(55)';BIDI;
    'IO56':'(56)';BIDI;
    'IO57':'(57)';BIDI;
    'IO58':'(58)';BIDI;
    'IO59':'(59)';BIDI;
    'IO6':'(6)';BIDI;
    'IO60':'(60)';BIDI;
    'IO61':'(61)';BIDI;
    'IO62':'(62)';BIDI;
    'IO63':'(63)';BIDI;
    'IO64':'(64)';BIDI;
    'IO7':'(7)';BIDI;
    'IO8':'(8)';BIDI;
    'IO9':'(9)';BIDI;
end_primitive;
primitive 'SCONN80_E67482007_SM-CONN,E674A';body 'SCONN80_E67482007';
    'IO1':'(1)';BIDI;
    'IO10':'(10)';BIDI;
    'IO11':'(11)';BIDI;
    'IO12':'(12)';BIDI;
    'IO13':'(13)';BIDI;
    'IO14':'(14)';BIDI;
    'IO15':'(15)';BIDI;
    'IO16':'(16)';BIDI;
    'IO17':'(17)';BIDI;
    'IO18':'(18)';BIDI;
    'IO19':'(19)';BIDI;
    'IO2':'(2)';BIDI;
    'IO20':'(20)';BIDI;
    'IO21':'(21)';BIDI;
    'IO22':'(22)';BIDI;
    'IO23':'(23)';BIDI;
    'IO24':'(24)';BIDI;
    'IO25':'(25)';BIDI;
    'IO26':'(26)';BIDI;
    'IO27':'(27)';BIDI;
    'IO28':'(28)';BIDI;
    'IO29':'(29)';BIDI;
    'IO3':'(3)';BIDI;
    'IO30':'(30)';BIDI;
    'IO31':'(31)';BIDI;
    'IO32':'(32)';BIDI;
    'IO33':'(33)';BIDI;
    'IO34':'(34)';BIDI;
    'IO35':'(35)';BIDI;
    'IO36':'(36)';BIDI;
    'IO37':'(37)';BIDI;
    'IO38':'(38)';BIDI;
    'IO39':'(39)';BIDI;
    'IO4':'(4)';BIDI;
    'IO40':'(40)';BIDI;
    'IO41':'(41)';BIDI;
    'IO42':'(42)';BIDI;
    'IO43':'(43)';BIDI;
    'IO44':'(44)';BIDI;
    'IO45':'(45)';BIDI;
    'IO46':'(46)';BIDI;
    'IO47':'(47)';BIDI;
    'IO48':'(48)';BIDI;
    'IO49':'(49)';BIDI;
    'IO5':'(5)';BIDI;
    'IO50':'(50)';BIDI;
    'IO51':'(51)';BIDI;
    'IO52':'(52)';BIDI;
    'IO53':'(53)';BIDI;
    'IO54':'(54)';BIDI;
    'IO55':'(55)';BIDI;
    'IO56':'(56)';BIDI;
    'IO57':'(57)';BIDI;
    'IO58':'(58)';BIDI;
    'IO59':'(59)';BIDI;
    'IO6':'(6)';BIDI;
    'IO60':'(60)';BIDI;
    'IO61':'(61)';BIDI;
    'IO62':'(62)';BIDI;
    'IO63':'(63)';BIDI;
    'IO64':'(64)';BIDI;
    'IO65':'(65)';BIDI;
    'IO66':'(66)';BIDI;
    'IO67':'(67)';BIDI;
    'IO68':'(68)';BIDI;
    'IO69':'(69)';BIDI;
    'IO7':'(7)';BIDI;
    'IO70':'(70)';BIDI;
    'IO71':'(71)';BIDI;
    'IO72':'(72)';BIDI;
    'IO73':'(73)';BIDI;
    'IO74':'(74)';BIDI;
    'IO75':'(75)';BIDI;
    'IO76':'(76)';BIDI;
    'IO77':'(77)';BIDI;
    'IO78':'(78)';BIDI;
    'IO79':'(79)';BIDI;
    'IO8':'(8)';BIDI;
    'IO80':'(80)';BIDI;
    'IO9':'(9)';BIDI;
end_primitive;
primitive 'SE100U16VM-48-GP_SMD-TCG2-SE10A';body 'SE100U16VM-48-GP';
    '1':'(1)';
    '2':'(2)';
end_primitive;
primitive 'SHUNT_SH0201-EMPTY,N_A';body 'SHUNT';
    'A':'(1)';
    'B':'(2)';
end_primitive;
primitive 'SKT-MINI67P-41-GP_SOCKET-G4-SKA';body 'SKT-MINI67P-41-GP';
    '1':'(1)';
    '3':'(3)';
    '5':'(5)';
    '7':'(7)';
    '9':'(9)';
    '11':'(11)';
    '13':'(13)';
    '15':'(15)';
    '17':'(17)';
    '19':'(19)';
    '21':'(21)';
    '23':'(23)';
    '25':'(25)';
    '27':'(27)';
    '29':'(29)';
    '31':'(31)';
    '33':'(33)';
    '35':'(35)';
    '37':'(37)';
    '39':'(39)';
    '41':'(41)';
    '43':'(43)';
    '45':'(45)';
    '47':'(47)';
    '49':'(49)';
    '51':'(51)';
    '53':'(53)';
    '55':'(55)';
    '57':'(57)';
    '67':'(67)';
    '69':'(69)';
    '71':'(71)';
    '73':'(73)';
    '75':'(75)';
    '2':'(2)';
    '4':'(4)';
    '6':'(6)';
    '8':'(8)';
    '10':'(10)';
    '12':'(12)';
    '14':'(14)';
    '16':'(16)';
    '18':'(18)';
    '20':'(20)';
    '22':'(22)';
    '24':'(24)';
    '26':'(26)';
    '28':'(28)';
    '30':'(30)';
    '32':'(32)';
    '34':'(34)';
    '36':'(36)';
    '38':'(38)';
    '40':'(40)';
    '42':'(42)';
    '44':'(44)';
    '46':'(46)';
    '48':'(48)';
    '50':'(50)';
    '52':'(52)';
    '54':'(54)';
    '56':'(56)';
    '58':'(58)';
    '68':'(68)';
    '70':'(70)';
    '72':'(72)';
    '74':'(74)';
    '76':'(76)';
    '77':'(77)';
    'NP1':'(NP1)';
    'NP2':'(NP2)';
end_primitive;
primitive 'SKT-RJ45-LED-XFOR-1-GP_SOCKET-A';body 'SKT-RJ45-LED-XFOR-1-GP';
    'L1':'(L1)';
    'L2':'(L2)';
    'L3':'(L3)';
    'L4':'(L4)';
    'R1':'(R1)';
    'R2':'(R2)';
    'R3':'(R3)';
    'R4':'(R4)';
    'R5':'(R5)';
    'R6':'(R6)';
    'R7':'(R7)';
    'R8':'(R8)';
    'R9':'(R9)';
    'R10':'(R10)';
    'R11':'(R11)';
    '1':'(1)';
    '2':'(2)';
end_primitive;
primitive 'SKT-SATA7P-6P-165-GP-U1_SOCKETA';body 'SKT-SATA7P-6P-165-GP-U1';
    'S1':'(S1)';
    'S2':'(S2)';
    'S3':'(S3)';
    'S4':'(S4)';
    'S5':'(S5)';
    'S6':'(S6)';
    'S7':'(S7)';
    'P1':'(P1)';
    'P2':'(P2)';
    'P3':'(P3)';
    'P4':'(P4)';
    'P5':'(P5)';
    'P6':'(P6)';
    'NP1':'(NP1)';
    'NP2':'(NP2)';
    'H1':'(H1)';
    'H2':'(H2)';
end_primitive;
primitive 'SKT-USB32-8-GP_SOCKET-G4-SKT-UA';body 'SKT-USB32-8-GP';
    'SSTXP1':'(A2)';
    'SSTXN1':'(A3)';
    'CC1':'(A5)';
    'DP1':'(A6)';
    'DN1':'(A7)';
    'CC2':'(B5)';
    'DP2':'(B6)';
    'DN2':'(B7)';
    'SSRXN1':'(B10)';
    'SSRXP1':'(B11)';
    'VBUS'<0>:'(A4)';
    'VBUS'<1>:'(A9)';
    'VBUS'<2>:'(B4)';
    'VBUS'<3>:'(B9)';
    'SSRXP2':'(A11)';
    'SSRXN2':'(A10)';
    'SSTXP2':'(B2)';
    'SSTXN2':'(B3)';
    'NP1':'(NP1)';
    'NP2':'(NP2)';
    'SBU1':'(A8)';
    'SBU2':'(B8)';
    'PTH1':'(PTH1)';
    'PTH2':'(PTH2)';
    'PTH3':'(PTH3)';
    'PTH4':'(PTH4)';
    'PTH5':'(PTH5)';
    'PTH6':'(PTH6)';
    'PTH7':'(PTH7)';
    'PTH8':'(PTH8)';
    'GND'<0>:'(A1)';
    'GND'<1>:'(A12)';
    'GND'<2>:'(B1)';
    'GND'<3>:'(B12)';
end_primitive;
primitive 'SKX_EXT_B_BGA1-IC,TBD';body 'SKX_EXT_B';
    'BCLK0_DN':'(AU24,0,0,0,0,0,0,0,0,0,0,0,0,0,0,0,0,0,0,0,0,0,0,0,0,0,0,0,0,0)~
';$S;IN;
    'BCLK0_DP':'(AW24,0,0,0,0,0,0,0,0,0,0,0,0,0,0,0,0,0,0,0,0,0,0,0,0,0,0,0,0,0)~
';$S;IN;
    'BCLK1_DN':'(CR26,0,0,0,0,0,0,0,0,0,0,0,0,0,0,0,0,0,0,0,0,0,0,0,0,0,0,0,0,0)~
';$S;IN;
    'BCLK1_DP':'(CP27,0,0,0,0,0,0,0,0,0,0,0,0,0,0,0,0,0,0,0,0,0,0,0,0,0,0,0,0,0)~
';$S;IN;
    'BCLK2_DN':'(CT25,0,0,0,0,0,0,0,0,0,0,0,0,0,0,0,0,0,0,0,0,0,0,0,0,0,0,0,0,0)~
';$S;IN;
    'BCLK2_DP':'(CU26,0,0,0,0,0,0,0,0,0,0,0,0,0,0,0,0,0,0,0,0,0,0,0,0,0,0,0,0,0)~
';$S;IN;
    'BIST_ENABLE':'(BA20,0,0,0,0,0,0,0,0,0,0,0,0,0,0,0,0,0,0,0,0,0,0,0,0,0,0,0,0~
,0)';$S;IN;
    'BMCINIT':'(BD23,0,0,0,0,0,0,0,0,0,0,0,0,0,0,0,0,0,0,0,0,0,0,0,0,0,0,0,0,0)';$S;IN;
    'BPM_N'<7>:'(AC12,0,0,0,0,0,0,0,0,0,0,0,0,0,0,0,0,0,0,0,0,0,0,0,0,0,0,0,0,0)~
';BIDI;
    'BPM_N'<6>:'(AE12,0,0,0,0,0,0,0,0,0,0,0,0,0,0,0,0,0,0,0,0,0,0,0,0,0,0,0,0,0)~
';BIDI;
    'BPM_N'<5>:'(Y11,0,0,0,0,0,0,0,0,0,0,0,0,0,0,0,0,0,0,0,0,0,0,0,0,0,0,0,0,0)';BIDI;
    'BPM_N'<4>:'(AA12,0,0,0,0,0,0,0,0,0,0,0,0,0,0,0,0,0,0,0,0,0,0,0,0,0,0,0,0,0)~
';BIDI;
    'BPM_N'<3>:'(AF11,0,0,0,0,0,0,0,0,0,0,0,0,0,0,0,0,0,0,0,0,0,0,0,0,0,0,0,0,0)~
';BIDI;
    'BPM_N'<2>:'(AG10,0,0,0,0,0,0,0,0,0,0,0,0,0,0,0,0,0,0,0,0,0,0,0,0,0,0,0,0,0)~
';BIDI;
    'BPM_N'<1>:'(AH11,0,0,0,0,0,0,0,0,0,0,0,0,0,0,0,0,0,0,0,0,0,0,0,0,0,0,0,0,0)~
';BIDI;
    'BPM_N'<0>:'(AJ10,0,0,0,0,0,0,0,0,0,0,0,0,0,0,0,0,0,0,0,0,0,0,0,0,0,0,0,0,0)~
';BIDI;
    'CATERR_N':'(AL14,0,0,0,0,0,0,0,0,0,0,0,0,0,0,0,0,0,0,0,0,0,0,0,0,0,0,0,0,0)~
';$S;BIDI;
    'CD_HFI0_I2CCLK':'(0,0,0,0,0,0,0,0,BN22,0,0,0,0,0,0,0,0,0,0,0,0,0,0,0,0,0,0,~
0,0,0)';$S;BIDI;
    'CD_HFI0_I2CDAT':'(0,0,0,0,0,0,0,0,BP23,0,0,0,0,0,0,0,0,0,0,0,0,0,0,0,0,0,0,~
0,0,0)';$S;BIDI;
    'CD_HFI0_INT_N':'(0,0,0,0,0,0,0,0,BP19,0,0,0,0,0,0,0,0,0,0,0,0,0,0,0,0,0,0,0~
,0,0)';$S;IN;
    'CD_HFI0_LED_N':'(0,0,0,0,0,0,0,0,BK21,0,0,0,0,0,0,0,0,0,0,0,0,0,0,0,0,0,0,0~
,0,0)';$S;OUT;
    'CD_HFI0_MODPRST_N':'(0,0,0,0,0,0,0,0,BR20,0,0,0,0,0,0,0,0,0,0,0,0,0,0,0,0,0~
,0,0,0,0)';$S;IN;
    'CD_HFI0_RESET_N':'(0,0,0,0,0,0,0,0,BN24,0,0,0,0,0,0,0,0,0,0,0,0,0,0,0,0,0,0~
,0,0,0)';$S;OUT;
    'CD_HFI1_I2CCLK':'(0,0,0,0,0,0,0,0,BJ22,0,0,0,0,0,0,0,0,0,0,0,0,0,0,0,0,0,0,~
0,0,0)';$S;BIDI;
    'CD_HFI1_I2CDAT':'(0,0,0,0,0,0,0,0,BH23,0,0,0,0,0,0,0,0,0,0,0,0,0,0,0,0,0,0,~
0,0,0)';$S;BIDI;
    'CD_HFI1_INT_N':'(0,0,0,0,0,0,0,0,BM21,0,0,0,0,0,0,0,0,0,0,0,0,0,0,0,0,0,0,0~
,0,0)';$S;IN;
    'CD_HFI1_LED_N':'(0,0,0,0,0,0,0,0,BM23,0,0,0,0,0,0,0,0,0,0,0,0,0,0,0,0,0,0,0~
,0,0)';$S;OUT;
    'CD_HFI1_MODPRST_N':'(0,0,0,0,0,0,0,0,BT19,0,0,0,0,0,0,0,0,0,0,0,0,0,0,0,0,0~
,0,0,0,0)';$S;IN;
    'CD_HFI1_RESET_N':'(0,0,0,0,0,0,0,0,BK23,0,0,0,0,0,0,0,0,0,0,0,0,0,0,0,0,0,0~
,0,0,0)';$S;OUT;
    'CD_HFI_REFCLK_DN':'(0,0,0,0,0,0,0,0,BE16,0,0,0,0,0,0,0,0,0,0,0,0,0,0,0,0,0,~
0,0,0,0)';$S;IN;
    'CD_HFI_REFCLK_DP':'(0,0,0,0,0,0,0,0,BG16,0,0,0,0,0,0,0,0,0,0,0,0,0,0,0,0,0,~
0,0,0,0)';$S;IN;
    'CD_PE_REFCLK_DN':'(0,0,0,0,0,0,0,0,BU24,0,0,0,0,0,0,0,0,0,0,0,0,0,0,0,0,0,0~
,0,0,0)';$S;IN;
    'CD_PE_REFCLK_DP':'(0,0,0,0,0,0,0,0,BW24,0,0,0,0,0,0,0,0,0,0,0,0,0,0,0,0,0,0~
,0,0,0)';$S;IN;
    'CD_POR_N':'(0,0,0,0,0,0,0,0,CF25,0,0,0,0,0,0,0,0,0,0,0,0,0,0,0,0,0,0,0,0,0)~
';$S;BIDI;
    'CD_TCLK':'(0,0,0,0,0,0,0,0,CB23,0,0,0,0,0,0,0,0,0,0,0,0,0,0,0,0,0,0,0,0,0)';$S;IN;
    'CD_TDI':'(0,0,0,0,0,0,0,0,BY21,0,0,0,0,0,0,0,0,0,0,0,0,0,0,0,0,0,0,0,0,0)';~
$S;IN;
    'CD_TDO':'(0,0,0,0,0,0,0,0,CC22,0,0,0,0,0,0,0,0,0,0,0,0,0,0,0,0,0,0,0,0,0)';~
$S;OUT;
    'CD_TMS':'(0,0,0,0,0,0,0,0,CE24,0,0,0,0,0,0,0,0,0,0,0,0,0,0,0,0,0,0,0,0,0)';~
$S;IN;
    'CD_TRST_N':'(0,0,0,0,0,0,0,0,CD23,0,0,0,0,0,0,0,0,0,0,0,0,0,0,0,0,0,0,0,0,0~
)';$S;IN;
    'CD_VCCIN'<3>:'(0,0,0,0,0,0,0,0,0,0,0,0,0,0,0,0,0,0,0,0,BY27,0,0,0,0,0,0,0,0~
,0)';
    'CD_VCCIN'<2>:'(0,0,0,0,0,0,0,0,0,0,0,0,0,0,0,0,0,0,0,0,BV27,0,0,0,0,0,0,0,0~
,0)';
    'CD_VCCIN'<1>:'(0,0,0,0,0,0,0,0,0,0,0,0,0,0,0,0,0,0,0,0,BU26,0,0,0,0,0,0,0,0~
,0)';
    'CD_VCCIN'<0>:'(0,0,0,0,0,0,0,0,0,0,0,0,0,0,0,0,0,0,0,0,BT27,0,0,0,0,0,0,0,0~
,0)';
    'CD_VCCP'<15>:'(0,0,0,0,0,0,0,0,0,0,0,0,0,0,0,0,0,0,0,0,BM11,0,0,0,0,0,0,0,0~
,0)';
    'CD_VCCP'<14>:'(0,0,0,0,0,0,0,0,0,0,0,0,0,0,0,0,0,0,0,0,BN12,0,0,0,0,0,0,0,0~
,0)';
    'CD_VCCP'<13>:'(0,0,0,0,0,0,0,0,0,0,0,0,0,0,0,0,0,0,0,0,BN14,0,0,0,0,0,0,0,0~
,0)';
    'CD_VCCP'<12>:'(0,0,0,0,0,0,0,0,0,0,0,0,0,0,0,0,0,0,0,0,BP11,0,0,0,0,0,0,0,0~
,0)';
    'CD_VCCP'<11>:'(0,0,0,0,0,0,0,0,0,0,0,0,0,0,0,0,0,0,0,0,BP13,0,0,0,0,0,0,0,0~
,0)';
    'CD_VCCP'<10>:'(0,0,0,0,0,0,0,0,0,0,0,0,0,0,0,0,0,0,0,0,BP15,0,0,0,0,0,0,0,0~
,0)';
    'CD_VCCP'<9>:'(0,0,0,0,0,0,0,0,0,0,0,0,0,0,0,0,0,0,0,0,BR12,0,0,0,0,0,0,0,0,~
0)';
    'CD_VCCP'<8>:'(0,0,0,0,0,0,0,0,0,0,0,0,0,0,0,0,0,0,0,0,BR14,0,0,0,0,0,0,0,0,~
0)';
    'CD_VCCP'<7>:'(0,0,0,0,0,0,0,0,0,0,0,0,0,0,0,0,0,0,0,0,BT11,0,0,0,0,0,0,0,0,~
0)';
    'CD_VCCP'<6>:'(0,0,0,0,0,0,0,0,0,0,0,0,0,0,0,0,0,0,0,0,BT13,0,0,0,0,0,0,0,0,~
0)';
    'CD_VCCP'<5>:'(0,0,0,0,0,0,0,0,0,0,0,0,0,0,0,0,0,0,0,0,BT15,0,0,0,0,0,0,0,0,~
0)';
    'CD_VCCP'<4>:'(0,0,0,0,0,0,0,0,0,0,0,0,0,0,0,0,0,0,0,0,BU12,0,0,0,0,0,0,0,0,~
0)';
    'CD_VCCP'<3>:'(0,0,0,0,0,0,0,0,0,0,0,0,0,0,0,0,0,0,0,0,BU14,0,0,0,0,0,0,0,0,~
0)';
    'CD_VCCP'<2>:'(0,0,0,0,0,0,0,0,0,0,0,0,0,0,0,0,0,0,0,0,BV11,0,0,0,0,0,0,0,0,~
0)';
    'CD_VCCP'<1>:'(0,0,0,0,0,0,0,0,0,0,0,0,0,0,0,0,0,0,0,0,BV13,0,0,0,0,0,0,0,0,~
0)';
    'CD_VCCP'<0>:'(0,0,0,0,0,0,0,0,0,0,0,0,0,0,0,0,0,0,0,0,BV15,0,0,0,0,0,0,0,0,~
0)';
    'CD_VCCP_SENSE'<1>:'(0,0,0,0,0,0,0,0,0,0,0,0,0,0,0,0,0,0,0,0,0,BT17,0,0,0,0,~
0,0,0,0)';
    'CD_VCCP_SENSE'<0>:'(0,0,0,0,0,0,0,0,0,0,0,0,0,0,0,0,0,0,0,0,0,BU16,0,0,0,0,~
0,0,0,0)';
    'CD_VCC_CORE'<12>:'(0,0,0,0,0,0,0,0,0,0,0,0,0,0,0,0,0,0,0,0,BD13,0,0,0,0,0,0~
,0,0,0)';
    'CD_VCC_CORE'<11>:'(0,0,0,0,0,0,0,0,0,0,0,0,0,0,0,0,0,0,0,0,BE12,0,0,0,0,0,0~
,0,0,0)';
    'CD_VCC_CORE'<10>:'(0,0,0,0,0,0,0,0,0,0,0,0,0,0,0,0,0,0,0,0,BE14,0,0,0,0,0,0~
,0,0,0)';
    'CD_VCC_CORE'<9>:'(0,0,0,0,0,0,0,0,0,0,0,0,0,0,0,0,0,0,0,0,BF11,0,0,0,0,0,0,~
0,0,0)';
    'CD_VCC_CORE'<8>:'(0,0,0,0,0,0,0,0,0,0,0,0,0,0,0,0,0,0,0,0,BF13,0,0,0,0,0,0,~
0,0,0)';
    'CD_VCC_CORE'<7>:'(0,0,0,0,0,0,0,0,0,0,0,0,0,0,0,0,0,0,0,0,BG12,0,0,0,0,0,0,~
0,0,0)';
    'CD_VCC_CORE'<6>:'(0,0,0,0,0,0,0,0,0,0,0,0,0,0,0,0,0,0,0,0,BG14,0,0,0,0,0,0,~
0,0,0)';
    'CD_VCC_CORE'<5>:'(0,0,0,0,0,0,0,0,0,0,0,0,0,0,0,0,0,0,0,0,BH13,0,0,0,0,0,0,~
0,0,0)';
    'CD_VCC_CORE'<4>:'(0,0,0,0,0,0,0,0,0,0,0,0,0,0,0,0,0,0,0,0,BJ12,0,0,0,0,0,0,~
0,0,0)';
    'CD_VCC_CORE'<3>:'(0,0,0,0,0,0,0,0,0,0,0,0,0,0,0,0,0,0,0,0,BJ14,0,0,0,0,0,0,~
0,0,0)';
    'CD_VCC_CORE'<2>:'(0,0,0,0,0,0,0,0,0,0,0,0,0,0,0,0,0,0,0,0,BK13,0,0,0,0,0,0,~
0,0,0)';
    'CD_VCC_CORE'<1>:'(0,0,0,0,0,0,0,0,0,0,0,0,0,0,0,0,0,0,0,0,BK15,0,0,0,0,0,0,~
0,0,0)';
    'CD_VCC_CORE'<0>:'(0,0,0,0,0,0,0,0,0,0,0,0,0,0,0,0,0,0,0,0,BL14,0,0,0,0,0,0,~
0,0,0)';
    'CD_VCC_CORE_SENSE':'(0,0,0,0,0,0,0,0,0,0,0,0,0,0,0,0,0,0,0,0,0,BN16,0,0,0,0~
,0,0,0,0)';$S;
    'CD_VPP'<3>:'(0,0,0,0,0,0,0,0,0,0,0,0,0,0,0,0,0,0,0,0,A8,0,0,0,0,0,0,0,0,0)';
    'CD_VPP'<2>:'(0,0,0,0,0,0,0,0,0,0,0,0,0,0,0,0,0,0,0,0,A10,0,0,0,0,0,0,0,0,0)~
';
    'CD_VPP'<1>:'(0,0,0,0,0,0,0,0,0,0,0,0,0,0,0,0,0,0,0,0,A12,0,0,0,0,0,0,0,0,0)~
';
    'CD_VPP'<0>:'(0,0,0,0,0,0,0,0,0,0,0,0,0,0,0,0,0,0,0,0,B11,0,0,0,0,0,0,0,0,0)~
';
    'CD_VSS_VCC_CORE_SENSE':'(0,0,0,0,0,0,0,0,0,0,0,0,0,0,0,0,0,0,0,0,0,BL16,0,0~
,0,0,0,0,0,0)';$S;
    'DDR012_DRAM_PWR_OK':'(AN30,0,0,0,0,0,0,0,0,0,0,0,0,0,0,0,0,0,0,0,0,0,0,0,0,~
0,0,0,0,0)';$S;IN;
    'DDR012_RCOMP'<2>:'(AC42,0,0,0,0,0,0,0,0,0,0,0,0,0,0,0,0,0,0,0,0,0,0,0,0,0,0~
,0,0,0)';BIDI;
    'DDR012_RCOMP'<1>:'(AB43,0,0,0,0,0,0,0,0,0,0,0,0,0,0,0,0,0,0,0,0,0,0,0,0,0,0~
,0,0,0)';BIDI;
    'DDR012_RCOMP'<0>:'(Y43,0,0,0,0,0,0,0,0,0,0,0,0,0,0,0,0,0,0,0,0,0,0,0,0,0,0,~
0,0,0)';BIDI;
    'DDR012_RESET_N':'(U64,0,0,0,0,0,0,0,0,0,0,0,0,0,0,0,0,0,0,0,0,0,0,0,0,0,0,0~
,0,0)';$S;OUT;
    'DDR012_SPDSCL':'(AJ18,0,0,0,0,0,0,0,0,0,0,0,0,0,0,0,0,0,0,0,0,0,0,0,0,0,0,0~
,0,0)';$S;BIDI;
    'DDR012_SPDSDA':'(AF17,0,0,0,0,0,0,0,0,0,0,0,0,0,0,0,0,0,0,0,0,0,0,0,0,0,0,0~
,0,0)';$S;BIDI;
    'DDR0_ACT_N':'(0,0,J60,0,0,0,0,0,0,0,0,0,0,0,0,0,0,0,0,0,0,0,0,0,0,0,0,0,0,0~
)';$S;OUT;
    'DDR0_ALERT_N':'(0,0,B61,0,0,0,0,0,0,0,0,0,0,0,0,0,0,0,0,0,0,0,0,0,0,0,0,0,0~
,0)';$S;IN;
    'DDR0_BA'<1>:'(0,0,G54,0,0,0,0,0,0,0,0,0,0,0,0,0,0,0,0,0,0,0,0,0,0,0,0,0,0,0~
)';OUT;
    'DDR0_BA'<0>:'(0,0,C52,0,0,0,0,0,0,0,0,0,0,0,0,0,0,0,0,0,0,0,0,0,0,0,0,0,0,0~
)';OUT;
    'DDR0_BG'<1>:'(0,0,F63,0,0,0,0,0,0,0,0,0,0,0,0,0,0,0,0,0,0,0,0,0,0,0,0,0,0,0~
)';OUT;
    'DDR0_BG'<0>:'(0,0,D61,0,0,0,0,0,0,0,0,0,0,0,0,0,0,0,0,0,0,0,0,0,0,0,0,0,0,0~
)';OUT;
    'DDR0_CAVREF':'(AJ64,0,0,0,0,0,0,0,0,0,0,0,0,0,0,0,0,0,0,0,0,0,0,0,0,0,0,0,0~
,0)';$S;OUT;
    'DDR0_CID'<2>:'(0,0,G46,0,0,0,0,0,0,0,0,0,0,0,0,0,0,0,0,0,0,0,0,0,0,0,0,0,0,~
0)';$S;OUT;
    'DDR0_CKE'<3>:'(0,0,D63,0,0,0,0,0,0,0,0,0,0,0,0,0,0,0,0,0,0,0,0,0,0,0,0,0,0,~
0)';OUT;
    'DDR0_CKE'<2>:'(0,0,B63,0,0,0,0,0,0,0,0,0,0,0,0,0,0,0,0,0,0,0,0,0,0,0,0,0,0,~
0)';OUT;
    'DDR0_CKE'<1>:'(0,0,C64,0,0,0,0,0,0,0,0,0,0,0,0,0,0,0,0,0,0,0,0,0,0,0,0,0,0,~
0)';OUT;
    'DDR0_CKE'<0>:'(0,0,C62,0,0,0,0,0,0,0,0,0,0,0,0,0,0,0,0,0,0,0,0,0,0,0,0,0,0,~
0)';OUT;
    'DDR0_CLK_DN'<3>:'(0,0,C56,0,0,0,0,0,0,0,0,0,0,0,0,0,0,0,0,0,0,0,0,0,0,0,0,0~
,0,0)';OUT;
    'DDR0_CLK_DN'<2>:'(0,0,J56,0,0,0,0,0,0,0,0,0,0,0,0,0,0,0,0,0,0,0,0,0,0,0,0,0~
,0,0)';OUT;
    'DDR0_CLK_DN'<1>:'(0,0,C54,0,0,0,0,0,0,0,0,0,0,0,0,0,0,0,0,0,0,0,0,0,0,0,0,0~
,0,0)';OUT;
    'DDR0_CLK_DN'<0>:'(0,0,F55,0,0,0,0,0,0,0,0,0,0,0,0,0,0,0,0,0,0,0,0,0,0,0,0,0~
,0,0)';OUT;
    'DDR0_CLK_DP'<3>:'(0,0,B57,0,0,0,0,0,0,0,0,0,0,0,0,0,0,0,0,0,0,0,0,0,0,0,0,0~
,0,0)';OUT;
    'DDR0_CLK_DP'<2>:'(0,0,G56,0,0,0,0,0,0,0,0,0,0,0,0,0,0,0,0,0,0,0,0,0,0,0,0,0~
,0,0)';OUT;
    'DDR0_CLK_DP'<1>:'(0,0,B55,0,0,0,0,0,0,0,0,0,0,0,0,0,0,0,0,0,0,0,0,0,0,0,0,0~
,0,0)';OUT;
    'DDR0_CLK_DP'<0>:'(0,0,D55,0,0,0,0,0,0,0,0,0,0,0,0,0,0,0,0,0,0,0,0,0,0,0,0,0~
,0,0)';OUT;
    'DDR0_CS_N'<7>:'(0,0,K45,0,0,0,0,0,0,0,0,0,0,0,0,0,0,0,0,0,0,0,0,0,0,0,0,0,0~
,0)';OUT;
    'DDR0_CS_N'<6>:'(0,0,F45,0,0,0,0,0,0,0,0,0,0,0,0,0,0,0,0,0,0,0,0,0,0,0,0,0,0~
,0)';OUT;
    'DDR0_CS_N'<5>:'(0,0,D49,0,0,0,0,0,0,0,0,0,0,0,0,0,0,0,0,0,0,0,0,0,0,0,0,0,0~
,0)';OUT;
    'DDR0_CS_N'<4>:'(0,0,B51,0,0,0,0,0,0,0,0,0,0,0,0,0,0,0,0,0,0,0,0,0,0,0,0,0,0~
,0)';OUT;
    'DDR0_CS_N'<3>:'(0,0,F47,0,0,0,0,0,0,0,0,0,0,0,0,0,0,0,0,0,0,0,0,0,0,0,0,0,0~
,0)';OUT;
    'DDR0_CS_N'<2>:'(0,0,D47,0,0,0,0,0,0,0,0,0,0,0,0,0,0,0,0,0,0,0,0,0,0,0,0,0,0~
,0)';OUT;
    'DDR0_CS_N'<1>:'(0,0,F49,0,0,0,0,0,0,0,0,0,0,0,0,0,0,0,0,0,0,0,0,0,0,0,0,0,0~
,0)';OUT;
    'DDR0_CS_N'<0>:'(0,0,G52,0,0,0,0,0,0,0,0,0,0,0,0,0,0,0,0,0,0,0,0,0,0,0,0,0,0~
,0)';OUT;
    'DDR0_DQ'<63>:'(0,0,K23,0,0,0,0,0,0,0,0,0,0,0,0,0,0,0,0,0,0,0,0,0,0,0,0,0,0,~
0)';BIDI;
    'DDR0_DQ'<62>:'(0,0,H23,0,0,0,0,0,0,0,0,0,0,0,0,0,0,0,0,0,0,0,0,0,0,0,0,0,0,~
0)';BIDI;
    'DDR0_DQ'<61>:'(0,0,N26,0,0,0,0,0,0,0,0,0,0,0,0,0,0,0,0,0,0,0,0,0,0,0,0,0,0,~
0)';BIDI;
    'DDR0_DQ'<60>:'(0,0,L26,0,0,0,0,0,0,0,0,0,0,0,0,0,0,0,0,0,0,0,0,0,0,0,0,0,0,~
0)';BIDI;
    'DDR0_DQ'<59>:'(0,0,T23,0,0,0,0,0,0,0,0,0,0,0,0,0,0,0,0,0,0,0,0,0,0,0,0,0,0,~
0)';BIDI;
    'DDR0_DQ'<58>:'(0,0,P23,0,0,0,0,0,0,0,0,0,0,0,0,0,0,0,0,0,0,0,0,0,0,0,0,0,0,~
0)';BIDI;
    'DDR0_DQ'<57>:'(0,0,P25,0,0,0,0,0,0,0,0,0,0,0,0,0,0,0,0,0,0,0,0,0,0,0,0,0,0,~
0)';BIDI;
    'DDR0_DQ'<56>:'(0,0,K25,0,0,0,0,0,0,0,0,0,0,0,0,0,0,0,0,0,0,0,0,0,0,0,0,0,0,~
0)';BIDI;
    'DDR0_DQ'<55>:'(0,0,P29,0,0,0,0,0,0,0,0,0,0,0,0,0,0,0,0,0,0,0,0,0,0,0,0,0,0,~
0)';BIDI;
    'DDR0_DQ'<54>:'(0,0,K29,0,0,0,0,0,0,0,0,0,0,0,0,0,0,0,0,0,0,0,0,0,0,0,0,0,0,~
0)';BIDI;
    'DDR0_DQ'<53>:'(0,0,N32,0,0,0,0,0,0,0,0,0,0,0,0,0,0,0,0,0,0,0,0,0,0,0,0,0,0,~
0)';BIDI;
    'DDR0_DQ'<52>:'(0,0,L32,0,0,0,0,0,0,0,0,0,0,0,0,0,0,0,0,0,0,0,0,0,0,0,0,0,0,~
0)';BIDI;
    'DDR0_DQ'<51>:'(0,0,N28,0,0,0,0,0,0,0,0,0,0,0,0,0,0,0,0,0,0,0,0,0,0,0,0,0,0,~
0)';BIDI;
    'DDR0_DQ'<50>:'(0,0,L28,0,0,0,0,0,0,0,0,0,0,0,0,0,0,0,0,0,0,0,0,0,0,0,0,0,0,~
0)';BIDI;
    'DDR0_DQ'<49>:'(0,0,P31,0,0,0,0,0,0,0,0,0,0,0,0,0,0,0,0,0,0,0,0,0,0,0,0,0,0,~
0)';BIDI;
    'DDR0_DQ'<48>:'(0,0,K31,0,0,0,0,0,0,0,0,0,0,0,0,0,0,0,0,0,0,0,0,0,0,0,0,0,0,~
0)';BIDI;
    'DDR0_DQ'<47>:'(0,0,P35,0,0,0,0,0,0,0,0,0,0,0,0,0,0,0,0,0,0,0,0,0,0,0,0,0,0,~
0)';BIDI;
    'DDR0_DQ'<46>:'(0,0,K35,0,0,0,0,0,0,0,0,0,0,0,0,0,0,0,0,0,0,0,0,0,0,0,0,0,0,~
0)';BIDI;
    'DDR0_DQ'<45>:'(0,0,N38,0,0,0,0,0,0,0,0,0,0,0,0,0,0,0,0,0,0,0,0,0,0,0,0,0,0,~
0)';BIDI;
    'DDR0_DQ'<44>:'(0,0,L38,0,0,0,0,0,0,0,0,0,0,0,0,0,0,0,0,0,0,0,0,0,0,0,0,0,0,~
0)';BIDI;
    'DDR0_DQ'<43>:'(0,0,N34,0,0,0,0,0,0,0,0,0,0,0,0,0,0,0,0,0,0,0,0,0,0,0,0,0,0,~
0)';BIDI;
    'DDR0_DQ'<42>:'(0,0,L34,0,0,0,0,0,0,0,0,0,0,0,0,0,0,0,0,0,0,0,0,0,0,0,0,0,0,~
0)';BIDI;
    'DDR0_DQ'<41>:'(0,0,P37,0,0,0,0,0,0,0,0,0,0,0,0,0,0,0,0,0,0,0,0,0,0,0,0,0,0,~
0)';BIDI;
    'DDR0_DQ'<40>:'(0,0,K37,0,0,0,0,0,0,0,0,0,0,0,0,0,0,0,0,0,0,0,0,0,0,0,0,0,0,~
0)';BIDI;
    'DDR0_DQ'<39>:'(0,0,F39,0,0,0,0,0,0,0,0,0,0,0,0,0,0,0,0,0,0,0,0,0,0,0,0,0,0,~
0)';BIDI;
    'DDR0_DQ'<38>:'(0,0,B39,0,0,0,0,0,0,0,0,0,0,0,0,0,0,0,0,0,0,0,0,0,0,0,0,0,0,~
0)';BIDI;
    'DDR0_DQ'<37>:'(0,0,F41,0,0,0,0,0,0,0,0,0,0,0,0,0,0,0,0,0,0,0,0,0,0,0,0,0,0,~
0)';BIDI;
    'DDR0_DQ'<36>:'(0,0,E42,0,0,0,0,0,0,0,0,0,0,0,0,0,0,0,0,0,0,0,0,0,0,0,0,0,0,~
0)';BIDI;
    'DDR0_DQ'<35>:'(0,0,E38,0,0,0,0,0,0,0,0,0,0,0,0,0,0,0,0,0,0,0,0,0,0,0,0,0,0,~
0)';BIDI;
    'DDR0_DQ'<34>:'(0,0,C38,0,0,0,0,0,0,0,0,0,0,0,0,0,0,0,0,0,0,0,0,0,0,0,0,0,0,~
0)';BIDI;
    'DDR0_DQ'<33>:'(0,0,B41,0,0,0,0,0,0,0,0,0,0,0,0,0,0,0,0,0,0,0,0,0,0,0,0,0,0,~
0)';BIDI;
    'DDR0_DQ'<32>:'(0,0,C42,0,0,0,0,0,0,0,0,0,0,0,0,0,0,0,0,0,0,0,0,0,0,0,0,0,0,~
0)';BIDI;
    'DDR0_DQ'<31>:'(0,0,R74,0,0,0,0,0,0,0,0,0,0,0,0,0,0,0,0,0,0,0,0,0,0,0,0,0,0,~
0)';BIDI;
    'DDR0_DQ'<30>:'(0,0,L74,0,0,0,0,0,0,0,0,0,0,0,0,0,0,0,0,0,0,0,0,0,0,0,0,0,0,~
0)';BIDI;
    'DDR0_DQ'<29>:'(0,0,P77,0,0,0,0,0,0,0,0,0,0,0,0,0,0,0,0,0,0,0,0,0,0,0,0,0,0,~
0)';BIDI;
    'DDR0_DQ'<28>:'(0,0,M77,0,0,0,0,0,0,0,0,0,0,0,0,0,0,0,0,0,0,0,0,0,0,0,0,0,0,~
0)';BIDI;
    'DDR0_DQ'<27>:'(0,0,P73,0,0,0,0,0,0,0,0,0,0,0,0,0,0,0,0,0,0,0,0,0,0,0,0,0,0,~
0)';BIDI;
    'DDR0_DQ'<26>:'(0,0,M73,0,0,0,0,0,0,0,0,0,0,0,0,0,0,0,0,0,0,0,0,0,0,0,0,0,0,~
0)';BIDI;
    'DDR0_DQ'<25>:'(0,0,R76,0,0,0,0,0,0,0,0,0,0,0,0,0,0,0,0,0,0,0,0,0,0,0,0,0,0,~
0)';BIDI;
    'DDR0_DQ'<24>:'(0,0,L76,0,0,0,0,0,0,0,0,0,0,0,0,0,0,0,0,0,0,0,0,0,0,0,0,0,0,~
0)';BIDI;
    'DDR0_DQ'<23>:'(0,0,N80,0,0,0,0,0,0,0,0,0,0,0,0,0,0,0,0,0,0,0,0,0,0,0,0,0,0,~
0)';BIDI;
    'DDR0_DQ'<22>:'(0,0,R82,0,0,0,0,0,0,0,0,0,0,0,0,0,0,0,0,0,0,0,0,0,0,0,0,0,0,~
0)';BIDI;
    'DDR0_DQ'<21>:'(0,0,V79,0,0,0,0,0,0,0,0,0,0,0,0,0,0,0,0,0,0,0,0,0,0,0,0,0,0,~
0)';BIDI;
    'DDR0_DQ'<20>:'(0,0,W80,0,0,0,0,0,0,0,0,0,0,0,0,0,0,0,0,0,0,0,0,0,0,0,0,0,0,~
0)';BIDI;
    'DDR0_DQ'<19>:'(0,0,M81,0,0,0,0,0,0,0,0,0,0,0,0,0,0,0,0,0,0,0,0,0,0,0,0,0,0,~
0)';BIDI;
    'DDR0_DQ'<18>:'(0,0,N82,0,0,0,0,0,0,0,0,0,0,0,0,0,0,0,0,0,0,0,0,0,0,0,0,0,0,~
0)';BIDI;
    'DDR0_DQ'<17>:'(0,0,T79,0,0,0,0,0,0,0,0,0,0,0,0,0,0,0,0,0,0,0,0,0,0,0,0,0,0,~
0)';BIDI;
    'DDR0_DQ'<16>:'(0,0,V81,0,0,0,0,0,0,0,0,0,0,0,0,0,0,0,0,0,0,0,0,0,0,0,0,0,0,~
0)';BIDI;
    'DDR0_DQ'<15>:'(0,0,N84,0,0,0,0,0,0,0,0,0,0,0,0,0,0,0,0,0,0,0,0,0,0,0,0,0,0,~
0)';BIDI;
    'DDR0_DQ'<14>:'(0,0,N86,0,0,0,0,0,0,0,0,0,0,0,0,0,0,0,0,0,0,0,0,0,0,0,0,0,0,~
0)';BIDI;
    'DDR0_DQ'<13>:'(0,0,AA84,0,0,0,0,0,0,0,0,0,0,0,0,0,0,0,0,0,0,0,0,0,0,0,0,0,0~
,0)';BIDI;
    'DDR0_DQ'<12>:'(0,0,AA86,0,0,0,0,0,0,0,0,0,0,0,0,0,0,0,0,0,0,0,0,0,0,0,0,0,0~
,0)';BIDI;
    'DDR0_DQ'<11>:'(0,0,L84,0,0,0,0,0,0,0,0,0,0,0,0,0,0,0,0,0,0,0,0,0,0,0,0,0,0,~
0)';BIDI;
    'DDR0_DQ'<10>:'(0,0,L86,0,0,0,0,0,0,0,0,0,0,0,0,0,0,0,0,0,0,0,0,0,0,0,0,0,0,~
0)';BIDI;
    'DDR0_DQ'<9>:'(0,0,W84,0,0,0,0,0,0,0,0,0,0,0,0,0,0,0,0,0,0,0,0,0,0,0,0,0,0,0~
)';BIDI;
    'DDR0_DQ'<8>:'(0,0,W86,0,0,0,0,0,0,0,0,0,0,0,0,0,0,0,0,0,0,0,0,0,0,0,0,0,0,0~
)';BIDI;
    'DDR0_DQ'<7>:'(0,0,AG84,0,0,0,0,0,0,0,0,0,0,0,0,0,0,0,0,0,0,0,0,0,0,0,0,0,0,~
0)';BIDI;
    'DDR0_DQ'<6>:'(0,0,AG86,0,0,0,0,0,0,0,0,0,0,0,0,0,0,0,0,0,0,0,0,0,0,0,0,0,0,~
0)';BIDI;
    'DDR0_DQ'<5>:'(0,0,AR84,0,0,0,0,0,0,0,0,0,0,0,0,0,0,0,0,0,0,0,0,0,0,0,0,0,0,~
0)';BIDI;
    'DDR0_DQ'<4>:'(0,0,AR86,0,0,0,0,0,0,0,0,0,0,0,0,0,0,0,0,0,0,0,0,0,0,0,0,0,0,~
0)';BIDI;
    'DDR0_DQ'<3>:'(0,0,AE84,0,0,0,0,0,0,0,0,0,0,0,0,0,0,0,0,0,0,0,0,0,0,0,0,0,0,~
0)';BIDI;
    'DDR0_DQ'<2>:'(0,0,AE86,0,0,0,0,0,0,0,0,0,0,0,0,0,0,0,0,0,0,0,0,0,0,0,0,0,0,~
0)';BIDI;
    'DDR0_DQ'<1>:'(0,0,AN84,0,0,0,0,0,0,0,0,0,0,0,0,0,0,0,0,0,0,0,0,0,0,0,0,0,0,~
0)';BIDI;
    'DDR0_DQ'<0>:'(0,0,AN86,0,0,0,0,0,0,0,0,0,0,0,0,0,0,0,0,0,0,0,0,0,0,0,0,0,0,~
0)';BIDI;
    'DDR0_DQS_DN'<17>:'(0,0,AB67,0,0,0,0,0,0,0,0,0,0,0,0,0,0,0,0,0,0,0,0,0,0,0,0~
,0,0,0)';BIDI;
    'DDR0_DQS_DN'<16>:'(0,0,J24,0,0,0,0,0,0,0,0,0,0,0,0,0,0,0,0,0,0,0,0,0,0,0,0,~
0,0,0)';BIDI;
    'DDR0_DQS_DN'<15>:'(0,0,J30,0,0,0,0,0,0,0,0,0,0,0,0,0,0,0,0,0,0,0,0,0,0,0,0,~
0,0,0)';BIDI;
    'DDR0_DQS_DN'<14>:'(0,0,J36,0,0,0,0,0,0,0,0,0,0,0,0,0,0,0,0,0,0,0,0,0,0,0,0,~
0,0,0)';BIDI;
    'DDR0_DQS_DN'<13>:'(0,0,A40,0,0,0,0,0,0,0,0,0,0,0,0,0,0,0,0,0,0,0,0,0,0,0,0,~
0,0,0)';BIDI;
    'DDR0_DQS_DN'<12>:'(0,0,K75,0,0,0,0,0,0,0,0,0,0,0,0,0,0,0,0,0,0,0,0,0,0,0,0,~
0,0,0)';BIDI;
    'DDR0_DQS_DN'<11>:'(0,0,U82,0,0,0,0,0,0,0,0,0,0,0,0,0,0,0,0,0,0,0,0,0,0,0,0,~
0,0,0)';BIDI;
    'DDR0_DQS_DN'<10>:'(0,0,U84,0,0,0,0,0,0,0,0,0,0,0,0,0,0,0,0,0,0,0,0,0,0,0,0,~
0,0,0)';BIDI;
    'DDR0_DQS_DN'<9>:'(0,0,AL84,0,0,0,0,0,0,0,0,0,0,0,0,0,0,0,0,0,0,0,0,0,0,0,0,~
0,0,0)';BIDI;
    'DDR0_DQS_DN'<8>:'(0,0,AH67,0,0,0,0,0,0,0,0,0,0,0,0,0,0,0,0,0,0,0,0,0,0,0,0,~
0,0,0)';BIDI;
    'DDR0_DQS_DN'<7>:'(0,0,N24,0,0,0,0,0,0,0,0,0,0,0,0,0,0,0,0,0,0,0,0,0,0,0,0,0~
,0,0)';BIDI;
    'DDR0_DQS_DN'<6>:'(0,0,R30,0,0,0,0,0,0,0,0,0,0,0,0,0,0,0,0,0,0,0,0,0,0,0,0,0~
,0,0)';BIDI;
    'DDR0_DQS_DN'<5>:'(0,0,R36,0,0,0,0,0,0,0,0,0,0,0,0,0,0,0,0,0,0,0,0,0,0,0,0,0~
,0,0)';BIDI;
    'DDR0_DQS_DN'<4>:'(0,0,G40,0,0,0,0,0,0,0,0,0,0,0,0,0,0,0,0,0,0,0,0,0,0,0,0,0~
,0,0)';BIDI;
    'DDR0_DQS_DN'<3>:'(0,0,T75,0,0,0,0,0,0,0,0,0,0,0,0,0,0,0,0,0,0,0,0,0,0,0,0,0~
,0,0)';BIDI;
    'DDR0_DQS_DN'<2>:'(0,0,P79,0,0,0,0,0,0,0,0,0,0,0,0,0,0,0,0,0,0,0,0,0,0,0,0,0~
,0,0)';BIDI;
    'DDR0_DQS_DN'<1>:'(0,0,R84,0,0,0,0,0,0,0,0,0,0,0,0,0,0,0,0,0,0,0,0,0,0,0,0,0~
,0,0)';BIDI;
    'DDR0_DQS_DN'<0>:'(0,0,AJ84,0,0,0,0,0,0,0,0,0,0,0,0,0,0,0,0,0,0,0,0,0,0,0,0,~
0,0,0)';BIDI;
    'DDR0_DQS_DP'<17>:'(0,0,AD67,0,0,0,0,0,0,0,0,0,0,0,0,0,0,0,0,0,0,0,0,0,0,0,0~
,0,0,0)';BIDI;
    'DDR0_DQS_DP'<16>:'(0,0,L24,0,0,0,0,0,0,0,0,0,0,0,0,0,0,0,0,0,0,0,0,0,0,0,0,~
0,0,0)';BIDI;
    'DDR0_DQS_DP'<15>:'(0,0,L30,0,0,0,0,0,0,0,0,0,0,0,0,0,0,0,0,0,0,0,0,0,0,0,0,~
0,0,0)';BIDI;
    'DDR0_DQS_DP'<14>:'(0,0,L36,0,0,0,0,0,0,0,0,0,0,0,0,0,0,0,0,0,0,0,0,0,0,0,0,~
0,0,0)';BIDI;
    'DDR0_DQS_DP'<13>:'(0,0,C40,0,0,0,0,0,0,0,0,0,0,0,0,0,0,0,0,0,0,0,0,0,0,0,0,~
0,0,0)';BIDI;
    'DDR0_DQS_DP'<12>:'(0,0,M75,0,0,0,0,0,0,0,0,0,0,0,0,0,0,0,0,0,0,0,0,0,0,0,0,~
0,0,0)';BIDI;
    'DDR0_DQS_DP'<11>:'(0,0,T81,0,0,0,0,0,0,0,0,0,0,0,0,0,0,0,0,0,0,0,0,0,0,0,0,~
0,0,0)';BIDI;
    'DDR0_DQS_DP'<10>:'(0,0,V85,0,0,0,0,0,0,0,0,0,0,0,0,0,0,0,0,0,0,0,0,0,0,0,0,~
0,0,0)';BIDI;
    'DDR0_DQS_DP'<9>:'(0,0,AM85,0,0,0,0,0,0,0,0,0,0,0,0,0,0,0,0,0,0,0,0,0,0,0,0,~
0,0,0)';BIDI;
    'DDR0_DQS_DP'<8>:'(0,0,AF67,0,0,0,0,0,0,0,0,0,0,0,0,0,0,0,0,0,0,0,0,0,0,0,0,~
0,0,0)';BIDI;
    'DDR0_DQS_DP'<7>:'(0,0,R24,0,0,0,0,0,0,0,0,0,0,0,0,0,0,0,0,0,0,0,0,0,0,0,0,0~
,0,0)';BIDI;
    'DDR0_DQS_DP'<6>:'(0,0,N30,0,0,0,0,0,0,0,0,0,0,0,0,0,0,0,0,0,0,0,0,0,0,0,0,0~
,0,0)';BIDI;
    'DDR0_DQS_DP'<5>:'(0,0,N36,0,0,0,0,0,0,0,0,0,0,0,0,0,0,0,0,0,0,0,0,0,0,0,0,0~
,0,0)';BIDI;
    'DDR0_DQS_DP'<4>:'(0,0,E40,0,0,0,0,0,0,0,0,0,0,0,0,0,0,0,0,0,0,0,0,0,0,0,0,0~
,0,0)';BIDI;
    'DDR0_DQS_DP'<3>:'(0,0,P75,0,0,0,0,0,0,0,0,0,0,0,0,0,0,0,0,0,0,0,0,0,0,0,0,0~
,0,0)';BIDI;
    'DDR0_DQS_DP'<2>:'(0,0,R80,0,0,0,0,0,0,0,0,0,0,0,0,0,0,0,0,0,0,0,0,0,0,0,0,0~
,0,0)';BIDI;
    'DDR0_DQS_DP'<1>:'(0,0,P85,0,0,0,0,0,0,0,0,0,0,0,0,0,0,0,0,0,0,0,0,0,0,0,0,0~
,0,0)';BIDI;
    'DDR0_DQS_DP'<0>:'(0,0,AH85,0,0,0,0,0,0,0,0,0,0,0,0,0,0,0,0,0,0,0,0,0,0,0,0,~
0,0,0)';BIDI;
    'DDR0_ECC'<7>:'(0,0,AG66,0,0,0,0,0,0,0,0,0,0,0,0,0,0,0,0,0,0,0,0,0,0,0,0,0,0~
,0)';BIDI;
    'DDR0_ECC'<6>:'(0,0,AC66,0,0,0,0,0,0,0,0,0,0,0,0,0,0,0,0,0,0,0,0,0,0,0,0,0,0~
,0)';BIDI;
    'DDR0_ECC'<5>:'(0,0,AF69,0,0,0,0,0,0,0,0,0,0,0,0,0,0,0,0,0,0,0,0,0,0,0,0,0,0~
,0)';BIDI;
    'DDR0_ECC'<4>:'(0,0,AD69,0,0,0,0,0,0,0,0,0,0,0,0,0,0,0,0,0,0,0,0,0,0,0,0,0,0~
,0)';BIDI;
    'DDR0_ECC'<3>:'(0,0,AF65,0,0,0,0,0,0,0,0,0,0,0,0,0,0,0,0,0,0,0,0,0,0,0,0,0,0~
,0)';BIDI;
    'DDR0_ECC'<2>:'(0,0,AD65,0,0,0,0,0,0,0,0,0,0,0,0,0,0,0,0,0,0,0,0,0,0,0,0,0,0~
,0)';BIDI;
    'DDR0_ECC'<1>:'(0,0,AG68,0,0,0,0,0,0,0,0,0,0,0,0,0,0,0,0,0,0,0,0,0,0,0,0,0,0~
,0)';BIDI;
    'DDR0_ECC'<0>:'(0,0,AC68,0,0,0,0,0,0,0,0,0,0,0,0,0,0,0,0,0,0,0,0,0,0,0,0,0,0~
,0)';BIDI;
    'DDR0_MA'<17>:'(0,0,K47,0,0,0,0,0,0,0,0,0,0,0,0,0,0,0,0,0,0,0,0,0,0,0,0,0,0,~
0)';OUT;
    'DDR0_MA'<16>:'(0,0,D51,0,0,0,0,0,0,0,0,0,0,0,0,0,0,0,0,0,0,0,0,0,0,0,0,0,0,~
0)';OUT;
    'DDR0_MA'<15>:'(0,0,K49,0,0,0,0,0,0,0,0,0,0,0,0,0,0,0,0,0,0,0,0,0,0,0,0,0,0,~
0)';OUT;
    'DDR0_MA'<14>:'(0,0,F51,0,0,0,0,0,0,0,0,0,0,0,0,0,0,0,0,0,0,0,0,0,0,0,0,0,0,~
0)';OUT;
    'DDR0_MA'<13>:'(0,0,J48,0,0,0,0,0,0,0,0,0,0,0,0,0,0,0,0,0,0,0,0,0,0,0,0,0,0,~
0)';OUT;
    'DDR0_MA'<12>:'(0,0,J64,0,0,0,0,0,0,0,0,0,0,0,0,0,0,0,0,0,0,0,0,0,0,0,0,0,0,~
0)';OUT;
    'DDR0_MA'<11>:'(0,0,G62,0,0,0,0,0,0,0,0,0,0,0,0,0,0,0,0,0,0,0,0,0,0,0,0,0,0,~
0)';OUT;
    'DDR0_MA'<10>:'(0,0,J54,0,0,0,0,0,0,0,0,0,0,0,0,0,0,0,0,0,0,0,0,0,0,0,0,0,0,~
0)';OUT;
    'DDR0_MA'<9>:'(0,0,F61,0,0,0,0,0,0,0,0,0,0,0,0,0,0,0,0,0,0,0,0,0,0,0,0,0,0,0~
)';OUT;
    'DDR0_MA'<8>:'(0,0,C60,0,0,0,0,0,0,0,0,0,0,0,0,0,0,0,0,0,0,0,0,0,0,0,0,0,0,0~
)';OUT;
    'DDR0_MA'<7>:'(0,0,G60,0,0,0,0,0,0,0,0,0,0,0,0,0,0,0,0,0,0,0,0,0,0,0,0,0,0,0~
)';OUT;
    'DDR0_MA'<6>:'(0,0,D59,0,0,0,0,0,0,0,0,0,0,0,0,0,0,0,0,0,0,0,0,0,0,0,0,0,0,0~
)';OUT;
    'DDR0_MA'<5>:'(0,0,F59,0,0,0,0,0,0,0,0,0,0,0,0,0,0,0,0,0,0,0,0,0,0,0,0,0,0,0~
)';OUT;
    'DDR0_MA'<4>:'(0,0,G58,0,0,0,0,0,0,0,0,0,0,0,0,0,0,0,0,0,0,0,0,0,0,0,0,0,0,0~
)';OUT;
    'DDR0_MA'<3>:'(0,0,C58,0,0,0,0,0,0,0,0,0,0,0,0,0,0,0,0,0,0,0,0,0,0,0,0,0,0,0~
)';OUT;
    'DDR0_MA'<2>:'(0,0,D57,0,0,0,0,0,0,0,0,0,0,0,0,0,0,0,0,0,0,0,0,0,0,0,0,0,0,0~
)';OUT;
    'DDR0_MA'<1>:'(0,0,F57,0,0,0,0,0,0,0,0,0,0,0,0,0,0,0,0,0,0,0,0,0,0,0,0,0,0,0~
)';OUT;
    'DDR0_MA'<0>:'(0,0,F53,0,0,0,0,0,0,0,0,0,0,0,0,0,0,0,0,0,0,0,0,0,0,0,0,0,0,0~
)';OUT;
    'DDR0_ODT'<3>:'(0,0,G48,0,0,0,0,0,0,0,0,0,0,0,0,0,0,0,0,0,0,0,0,0,0,0,0,0,0,~
0)';OUT;
    'DDR0_ODT'<2>:'(0,0,G50,0,0,0,0,0,0,0,0,0,0,0,0,0,0,0,0,0,0,0,0,0,0,0,0,0,0,~
0)';OUT;
    'DDR0_ODT'<1>:'(0,0,C48,0,0,0,0,0,0,0,0,0,0,0,0,0,0,0,0,0,0,0,0,0,0,0,0,0,0,~
0)';OUT;
    'DDR0_ODT'<0>:'(0,0,C50,0,0,0,0,0,0,0,0,0,0,0,0,0,0,0,0,0,0,0,0,0,0,0,0,0,0,~
0)';OUT;
    'DDR0_PAR':'(0,0,D53,0,0,0,0,0,0,0,0,0,0,0,0,0,0,0,0,0,0,0,0,0,0,0,0,0,0,0)';$S;OUT;
    'DDR1_ACT_N':'(0,0,0,T63,0,0,0,0,0,0,0,0,0,0,0,0,0,0,0,0,0,0,0,0,0,0,0,0,0,0~
)';$S;OUT;
    'DDR1_ALERT_N':'(0,0,0,W62,0,0,0,0,0,0,0,0,0,0,0,0,0,0,0,0,0,0,0,0,0,0,0,0,0~
,0)';$S;IN;
    'DDR1_BA'<1>:'(0,0,0,K55,0,0,0,0,0,0,0,0,0,0,0,0,0,0,0,0,0,0,0,0,0,0,0,0,0,0~
)';OUT;
    'DDR1_BA'<0>:'(0,0,0,T53,0,0,0,0,0,0,0,0,0,0,0,0,0,0,0,0,0,0,0,0,0,0,0,0,0,0~
)';OUT;
    'DDR1_BG'<1>:'(0,0,0,N60,0,0,0,0,0,0,0,0,0,0,0,0,0,0,0,0,0,0,0,0,0,0,0,0,0,0~
)';OUT;
    'DDR1_BG'<0>:'(0,0,0,M61,0,0,0,0,0,0,0,0,0,0,0,0,0,0,0,0,0,0,0,0,0,0,0,0,0,0~
)';OUT;
    'DDR1_CAVREF':'(AK63,0,0,0,0,0,0,0,0,0,0,0,0,0,0,0,0,0,0,0,0,0,0,0,0,0,0,0,0~
,0)';$S;OUT;
    'DDR1_CID'<2>:'(0,0,0,M47,0,0,0,0,0,0,0,0,0,0,0,0,0,0,0,0,0,0,0,0,0,0,0,0,0,~
0)';$S;OUT;
    'DDR1_CKE'<3>:'(0,0,0,L64,0,0,0,0,0,0,0,0,0,0,0,0,0,0,0,0,0,0,0,0,0,0,0,0,0,~
0)';OUT;
    'DDR1_CKE'<2>:'(0,0,0,K63,0,0,0,0,0,0,0,0,0,0,0,0,0,0,0,0,0,0,0,0,0,0,0,0,0,~
0)';OUT;
    'DDR1_CKE'<1>:'(0,0,0,R64,0,0,0,0,0,0,0,0,0,0,0,0,0,0,0,0,0,0,0,0,0,0,0,0,0,~
0)';OUT;
    'DDR1_CKE'<0>:'(0,0,0,N62,0,0,0,0,0,0,0,0,0,0,0,0,0,0,0,0,0,0,0,0,0,0,0,0,0,~
0)';OUT;
    'DDR1_CLK_DN'<3>:'(0,0,0,R56,0,0,0,0,0,0,0,0,0,0,0,0,0,0,0,0,0,0,0,0,0,0,0,0~
,0,0)';OUT;
    'DDR1_CLK_DN'<2>:'(0,0,0,N56,0,0,0,0,0,0,0,0,0,0,0,0,0,0,0,0,0,0,0,0,0,0,0,0~
,0,0)';OUT;
    'DDR1_CLK_DN'<1>:'(0,0,0,R54,0,0,0,0,0,0,0,0,0,0,0,0,0,0,0,0,0,0,0,0,0,0,0,0~
,0,0)';OUT;
    'DDR1_CLK_DN'<0>:'(0,0,0,M53,0,0,0,0,0,0,0,0,0,0,0,0,0,0,0,0,0,0,0,0,0,0,0,0~
,0,0)';OUT;
    'DDR1_CLK_DP'<3>:'(0,0,0,T57,0,0,0,0,0,0,0,0,0,0,0,0,0,0,0,0,0,0,0,0,0,0,0,0~
,0,0)';OUT;
    'DDR1_CLK_DP'<2>:'(0,0,0,M57,0,0,0,0,0,0,0,0,0,0,0,0,0,0,0,0,0,0,0,0,0,0,0,0~
,0,0)';OUT;
    'DDR1_CLK_DP'<1>:'(0,0,0,T55,0,0,0,0,0,0,0,0,0,0,0,0,0,0,0,0,0,0,0,0,0,0,0,0~
,0,0)';OUT;
    'DDR1_CLK_DP'<0>:'(0,0,0,N54,0,0,0,0,0,0,0,0,0,0,0,0,0,0,0,0,0,0,0,0,0,0,0,0~
,0,0)';OUT;
    'DDR1_CS_N'<7>:'(0,0,0,R46,0,0,0,0,0,0,0,0,0,0,0,0,0,0,0,0,0,0,0,0,0,0,0,0,0~
,0)';OUT;
    'DDR1_CS_N'<6>:'(0,0,0,M45,0,0,0,0,0,0,0,0,0,0,0,0,0,0,0,0,0,0,0,0,0,0,0,0,0~
,0)';OUT;
    'DDR1_CS_N'<5>:'(0,0,0,T49,0,0,0,0,0,0,0,0,0,0,0,0,0,0,0,0,0,0,0,0,0,0,0,0,0~
,0)';OUT;
    'DDR1_CS_N'<4>:'(0,0,0,J50,0,0,0,0,0,0,0,0,0,0,0,0,0,0,0,0,0,0,0,0,0,0,0,0,0~
,0)';OUT;
    'DDR1_CS_N'<3>:'(0,0,0,V47,0,0,0,0,0,0,0,0,0,0,0,0,0,0,0,0,0,0,0,0,0,0,0,0,0~
,0)';OUT;
    'DDR1_CS_N'<2>:'(0,0,0,N46,0,0,0,0,0,0,0,0,0,0,0,0,0,0,0,0,0,0,0,0,0,0,0,0,0~
,0)';OUT;
    'DDR1_CS_N'<1>:'(0,0,0,R50,0,0,0,0,0,0,0,0,0,0,0,0,0,0,0,0,0,0,0,0,0,0,0,0,0~
,0)';OUT;
    'DDR1_CS_N'<0>:'(0,0,0,K51,0,0,0,0,0,0,0,0,0,0,0,0,0,0,0,0,0,0,0,0,0,0,0,0,0~
,0)';OUT;
    'DDR1_DQ'<63>:'(0,0,0,AA26,0,0,0,0,0,0,0,0,0,0,0,0,0,0,0,0,0,0,0,0,0,0,0,0,0~
,0)';BIDI;
    'DDR1_DQ'<62>:'(0,0,0,U26,0,0,0,0,0,0,0,0,0,0,0,0,0,0,0,0,0,0,0,0,0,0,0,0,0,~
0)';BIDI;
    'DDR1_DQ'<61>:'(0,0,0,Y29,0,0,0,0,0,0,0,0,0,0,0,0,0,0,0,0,0,0,0,0,0,0,0,0,0,~
0)';BIDI;
    'DDR1_DQ'<60>:'(0,0,0,V29,0,0,0,0,0,0,0,0,0,0,0,0,0,0,0,0,0,0,0,0,0,0,0,0,0,~
0)';BIDI;
    'DDR1_DQ'<59>:'(0,0,0,Y25,0,0,0,0,0,0,0,0,0,0,0,0,0,0,0,0,0,0,0,0,0,0,0,0,0,~
0)';BIDI;
    'DDR1_DQ'<58>:'(0,0,0,V25,0,0,0,0,0,0,0,0,0,0,0,0,0,0,0,0,0,0,0,0,0,0,0,0,0,~
0)';BIDI;
    'DDR1_DQ'<57>:'(0,0,0,AA28,0,0,0,0,0,0,0,0,0,0,0,0,0,0,0,0,0,0,0,0,0,0,0,0,0~
,0)';BIDI;
    'DDR1_DQ'<56>:'(0,0,0,U28,0,0,0,0,0,0,0,0,0,0,0,0,0,0,0,0,0,0,0,0,0,0,0,0,0,~
0)';BIDI;
    'DDR1_DQ'<55>:'(0,0,0,F27,0,0,0,0,0,0,0,0,0,0,0,0,0,0,0,0,0,0,0,0,0,0,0,0,0,~
0)';BIDI;
    'DDR1_DQ'<54>:'(0,0,0,B27,0,0,0,0,0,0,0,0,0,0,0,0,0,0,0,0,0,0,0,0,0,0,0,0,0,~
0)';BIDI;
    'DDR1_DQ'<53>:'(0,0,0,F29,0,0,0,0,0,0,0,0,0,0,0,0,0,0,0,0,0,0,0,0,0,0,0,0,0,~
0)';BIDI;
    'DDR1_DQ'<52>:'(0,0,0,E30,0,0,0,0,0,0,0,0,0,0,0,0,0,0,0,0,0,0,0,0,0,0,0,0,0,~
0)';BIDI;
    'DDR1_DQ'<51>:'(0,0,0,E26,0,0,0,0,0,0,0,0,0,0,0,0,0,0,0,0,0,0,0,0,0,0,0,0,0,~
0)';BIDI;
    'DDR1_DQ'<50>:'(0,0,0,C26,0,0,0,0,0,0,0,0,0,0,0,0,0,0,0,0,0,0,0,0,0,0,0,0,0,~
0)';BIDI;
    'DDR1_DQ'<49>:'(0,0,0,B29,0,0,0,0,0,0,0,0,0,0,0,0,0,0,0,0,0,0,0,0,0,0,0,0,0,~
0)';BIDI;
    'DDR1_DQ'<48>:'(0,0,0,C30,0,0,0,0,0,0,0,0,0,0,0,0,0,0,0,0,0,0,0,0,0,0,0,0,0,~
0)';BIDI;
    'DDR1_DQ'<47>:'(0,0,0,F33,0,0,0,0,0,0,0,0,0,0,0,0,0,0,0,0,0,0,0,0,0,0,0,0,0,~
0)';BIDI;
    'DDR1_DQ'<46>:'(0,0,0,B33,0,0,0,0,0,0,0,0,0,0,0,0,0,0,0,0,0,0,0,0,0,0,0,0,0,~
0)';BIDI;
    'DDR1_DQ'<45>:'(0,0,0,F35,0,0,0,0,0,0,0,0,0,0,0,0,0,0,0,0,0,0,0,0,0,0,0,0,0,~
0)';BIDI;
    'DDR1_DQ'<44>:'(0,0,0,E36,0,0,0,0,0,0,0,0,0,0,0,0,0,0,0,0,0,0,0,0,0,0,0,0,0,~
0)';BIDI;
    'DDR1_DQ'<43>:'(0,0,0,E32,0,0,0,0,0,0,0,0,0,0,0,0,0,0,0,0,0,0,0,0,0,0,0,0,0,~
0)';BIDI;
    'DDR1_DQ'<42>:'(0,0,0,C32,0,0,0,0,0,0,0,0,0,0,0,0,0,0,0,0,0,0,0,0,0,0,0,0,0,~
0)';BIDI;
    'DDR1_DQ'<41>:'(0,0,0,B35,0,0,0,0,0,0,0,0,0,0,0,0,0,0,0,0,0,0,0,0,0,0,0,0,0,~
0)';BIDI;
    'DDR1_DQ'<40>:'(0,0,0,C36,0,0,0,0,0,0,0,0,0,0,0,0,0,0,0,0,0,0,0,0,0,0,0,0,0,~
0)';BIDI;
    'DDR1_DQ'<39>:'(0,0,0,P41,0,0,0,0,0,0,0,0,0,0,0,0,0,0,0,0,0,0,0,0,0,0,0,0,0,~
0)';BIDI;
    'DDR1_DQ'<38>:'(0,0,0,K41,0,0,0,0,0,0,0,0,0,0,0,0,0,0,0,0,0,0,0,0,0,0,0,0,0,~
0)';BIDI;
    'DDR1_DQ'<37>:'(0,0,0,T43,0,0,0,0,0,0,0,0,0,0,0,0,0,0,0,0,0,0,0,0,0,0,0,0,0,~
0)';BIDI;
    'DDR1_DQ'<36>:'(0,0,0,P43,0,0,0,0,0,0,0,0,0,0,0,0,0,0,0,0,0,0,0,0,0,0,0,0,0,~
0)';BIDI;
    'DDR1_DQ'<35>:'(0,0,0,N40,0,0,0,0,0,0,0,0,0,0,0,0,0,0,0,0,0,0,0,0,0,0,0,0,0,~
0)';BIDI;
    'DDR1_DQ'<34>:'(0,0,0,L40,0,0,0,0,0,0,0,0,0,0,0,0,0,0,0,0,0,0,0,0,0,0,0,0,0,~
0)';BIDI;
    'DDR1_DQ'<33>:'(0,0,0,H43,0,0,0,0,0,0,0,0,0,0,0,0,0,0,0,0,0,0,0,0,0,0,0,0,0,~
0)';BIDI;
    'DDR1_DQ'<32>:'(0,0,0,K43,0,0,0,0,0,0,0,0,0,0,0,0,0,0,0,0,0,0,0,0,0,0,0,0,0,~
0)';BIDI;
    'DDR1_DQ'<31>:'(0,0,0,G72,0,0,0,0,0,0,0,0,0,0,0,0,0,0,0,0,0,0,0,0,0,0,0,0,0,~
0)';BIDI;
    'DDR1_DQ'<30>:'(0,0,0,C72,0,0,0,0,0,0,0,0,0,0,0,0,0,0,0,0,0,0,0,0,0,0,0,0,0,~
0)';BIDI;
    'DDR1_DQ'<29>:'(0,0,0,G74,0,0,0,0,0,0,0,0,0,0,0,0,0,0,0,0,0,0,0,0,0,0,0,0,0,~
0)';BIDI;
    'DDR1_DQ'<28>:'(0,0,0,F75,0,0,0,0,0,0,0,0,0,0,0,0,0,0,0,0,0,0,0,0,0,0,0,0,0,~
0)';BIDI;
    'DDR1_DQ'<27>:'(0,0,0,F71,0,0,0,0,0,0,0,0,0,0,0,0,0,0,0,0,0,0,0,0,0,0,0,0,0,~
0)';BIDI;
    'DDR1_DQ'<26>:'(0,0,0,D71,0,0,0,0,0,0,0,0,0,0,0,0,0,0,0,0,0,0,0,0,0,0,0,0,0,~
0)';BIDI;
    'DDR1_DQ'<25>:'(0,0,0,C74,0,0,0,0,0,0,0,0,0,0,0,0,0,0,0,0,0,0,0,0,0,0,0,0,0,~
0)';BIDI;
    'DDR1_DQ'<24>:'(0,0,0,D75,0,0,0,0,0,0,0,0,0,0,0,0,0,0,0,0,0,0,0,0,0,0,0,0,0,~
0)';BIDI;
    'DDR1_DQ'<23>:'(0,0,0,J78,0,0,0,0,0,0,0,0,0,0,0,0,0,0,0,0,0,0,0,0,0,0,0,0,0,~
0)';BIDI;
    'DDR1_DQ'<22>:'(0,0,0,E78,0,0,0,0,0,0,0,0,0,0,0,0,0,0,0,0,0,0,0,0,0,0,0,0,0,~
0)';BIDI;
    'DDR1_DQ'<21>:'(0,0,0,H81,0,0,0,0,0,0,0,0,0,0,0,0,0,0,0,0,0,0,0,0,0,0,0,0,0,~
0)';BIDI;
    'DDR1_DQ'<20>:'(0,0,0,F81,0,0,0,0,0,0,0,0,0,0,0,0,0,0,0,0,0,0,0,0,0,0,0,0,0,~
0)';BIDI;
    'DDR1_DQ'<19>:'(0,0,0,H77,0,0,0,0,0,0,0,0,0,0,0,0,0,0,0,0,0,0,0,0,0,0,0,0,0,~
0)';BIDI;
    'DDR1_DQ'<18>:'(0,0,0,F77,0,0,0,0,0,0,0,0,0,0,0,0,0,0,0,0,0,0,0,0,0,0,0,0,0,~
0)';BIDI;
    'DDR1_DQ'<17>:'(0,0,0,J80,0,0,0,0,0,0,0,0,0,0,0,0,0,0,0,0,0,0,0,0,0,0,0,0,0,~
0)';BIDI;
    'DDR1_DQ'<16>:'(0,0,0,E80,0,0,0,0,0,0,0,0,0,0,0,0,0,0,0,0,0,0,0,0,0,0,0,0,0,~
0)';BIDI;
    'DDR1_DQ'<15>:'(0,0,0,AC80,0,0,0,0,0,0,0,0,0,0,0,0,0,0,0,0,0,0,0,0,0,0,0,0,0~
,0)';BIDI;
    'DDR1_DQ'<14>:'(0,0,0,AE82,0,0,0,0,0,0,0,0,0,0,0,0,0,0,0,0,0,0,0,0,0,0,0,0,0~
,0)';BIDI;
    'DDR1_DQ'<13>:'(0,0,0,AH79,0,0,0,0,0,0,0,0,0,0,0,0,0,0,0,0,0,0,0,0,0,0,0,0,0~
,0)';BIDI;
    'DDR1_DQ'<12>:'(0,0,0,AJ80,0,0,0,0,0,0,0,0,0,0,0,0,0,0,0,0,0,0,0,0,0,0,0,0,0~
,0)';BIDI;
    'DDR1_DQ'<11>:'(0,0,0,AB81,0,0,0,0,0,0,0,0,0,0,0,0,0,0,0,0,0,0,0,0,0,0,0,0,0~
,0)';BIDI;
    'DDR1_DQ'<10>:'(0,0,0,AC82,0,0,0,0,0,0,0,0,0,0,0,0,0,0,0,0,0,0,0,0,0,0,0,0,0~
,0)';BIDI;
    'DDR1_DQ'<9>:'(0,0,0,AF79,0,0,0,0,0,0,0,0,0,0,0,0,0,0,0,0,0,0,0,0,0,0,0,0,0,~
0)';BIDI;
    'DDR1_DQ'<8>:'(0,0,0,AH81,0,0,0,0,0,0,0,0,0,0,0,0,0,0,0,0,0,0,0,0,0,0,0,0,0,~
0)';BIDI;
    'DDR1_DQ'<7>:'(0,0,0,AN80,0,0,0,0,0,0,0,0,0,0,0,0,0,0,0,0,0,0,0,0,0,0,0,0,0,~
0)';BIDI;
    'DDR1_DQ'<6>:'(0,0,0,AR82,0,0,0,0,0,0,0,0,0,0,0,0,0,0,0,0,0,0,0,0,0,0,0,0,0,~
0)';BIDI;
    'DDR1_DQ'<5>:'(0,0,0,AV79,0,0,0,0,0,0,0,0,0,0,0,0,0,0,0,0,0,0,0,0,0,0,0,0,0,~
0)';BIDI;
    'DDR1_DQ'<4>:'(0,0,0,AW80,0,0,0,0,0,0,0,0,0,0,0,0,0,0,0,0,0,0,0,0,0,0,0,0,0,~
0)';BIDI;
    'DDR1_DQ'<3>:'(0,0,0,AM81,0,0,0,0,0,0,0,0,0,0,0,0,0,0,0,0,0,0,0,0,0,0,0,0,0,~
0)';BIDI;
    'DDR1_DQ'<2>:'(0,0,0,AN82,0,0,0,0,0,0,0,0,0,0,0,0,0,0,0,0,0,0,0,0,0,0,0,0,0,~
0)';BIDI;
    'DDR1_DQ'<1>:'(0,0,0,AT79,0,0,0,0,0,0,0,0,0,0,0,0,0,0,0,0,0,0,0,0,0,0,0,0,0,~
0)';BIDI;
    'DDR1_DQ'<0>:'(0,0,0,AV81,0,0,0,0,0,0,0,0,0,0,0,0,0,0,0,0,0,0,0,0,0,0,0,0,0,~
0)';BIDI;
    'DDR1_DQS_DN'<17>:'(0,0,0,G68,0,0,0,0,0,0,0,0,0,0,0,0,0,0,0,0,0,0,0,0,0,0,0,~
0,0,0)';BIDI;
    'DDR1_DQS_DN'<16>:'(0,0,0,T27,0,0,0,0,0,0,0,0,0,0,0,0,0,0,0,0,0,0,0,0,0,0,0,~
0,0,0)';BIDI;
    'DDR1_DQS_DN'<15>:'(0,0,0,A28,0,0,0,0,0,0,0,0,0,0,0,0,0,0,0,0,0,0,0,0,0,0,0,~
0,0,0)';BIDI;
    'DDR1_DQS_DN'<14>:'(0,0,0,A34,0,0,0,0,0,0,0,0,0,0,0,0,0,0,0,0,0,0,0,0,0,0,0,~
0,0,0)';BIDI;
    'DDR1_DQS_DN'<13>:'(0,0,0,J42,0,0,0,0,0,0,0,0,0,0,0,0,0,0,0,0,0,0,0,0,0,0,0,~
0,0,0)';BIDI;
    'DDR1_DQS_DN'<12>:'(0,0,0,B73,0,0,0,0,0,0,0,0,0,0,0,0,0,0,0,0,0,0,0,0,0,0,0,~
0,0,0)';BIDI;
    'DDR1_DQS_DN'<11>:'(0,0,0,D79,0,0,0,0,0,0,0,0,0,0,0,0,0,0,0,0,0,0,0,0,0,0,0,~
0,0,0)';BIDI;
    'DDR1_DQS_DN'<10>:'(0,0,0,AG82,0,0,0,0,0,0,0,0,0,0,0,0,0,0,0,0,0,0,0,0,0,0,0~
,0,0,0)';BIDI;
    'DDR1_DQS_DN'<9>:'(0,0,0,AU82,0,0,0,0,0,0,0,0,0,0,0,0,0,0,0,0,0,0,0,0,0,0,0,~
0,0,0)';BIDI;
    'DDR1_DQS_DN'<8>:'(0,0,0,N68,0,0,0,0,0,0,0,0,0,0,0,0,0,0,0,0,0,0,0,0,0,0,0,0~
,0,0)';BIDI;
    'DDR1_DQS_DN'<7>:'(0,0,0,AB27,0,0,0,0,0,0,0,0,0,0,0,0,0,0,0,0,0,0,0,0,0,0,0,~
0,0,0)';BIDI;
    'DDR1_DQS_DN'<6>:'(0,0,0,G28,0,0,0,0,0,0,0,0,0,0,0,0,0,0,0,0,0,0,0,0,0,0,0,0~
,0,0)';BIDI;
    'DDR1_DQS_DN'<5>:'(0,0,0,G34,0,0,0,0,0,0,0,0,0,0,0,0,0,0,0,0,0,0,0,0,0,0,0,0~
,0,0)';BIDI;
    'DDR1_DQS_DN'<4>:'(0,0,0,N42,0,0,0,0,0,0,0,0,0,0,0,0,0,0,0,0,0,0,0,0,0,0,0,0~
,0,0)';BIDI;
    'DDR1_DQS_DN'<3>:'(0,0,0,H73,0,0,0,0,0,0,0,0,0,0,0,0,0,0,0,0,0,0,0,0,0,0,0,0~
,0,0)';BIDI;
    'DDR1_DQS_DN'<2>:'(0,0,0,K79,0,0,0,0,0,0,0,0,0,0,0,0,0,0,0,0,0,0,0,0,0,0,0,0~
,0,0)';BIDI;
    'DDR1_DQS_DN'<1>:'(0,0,0,AD79,0,0,0,0,0,0,0,0,0,0,0,0,0,0,0,0,0,0,0,0,0,0,0,~
0,0,0)';BIDI;
    'DDR1_DQS_DN'<0>:'(0,0,0,AP79,0,0,0,0,0,0,0,0,0,0,0,0,0,0,0,0,0,0,0,0,0,0,0,~
0,0,0)';BIDI;
    'DDR1_DQS_DP'<17>:'(0,0,0,J68,0,0,0,0,0,0,0,0,0,0,0,0,0,0,0,0,0,0,0,0,0,0,0,~
0,0,0)';BIDI;
    'DDR1_DQS_DP'<16>:'(0,0,0,V27,0,0,0,0,0,0,0,0,0,0,0,0,0,0,0,0,0,0,0,0,0,0,0,~
0,0,0)';BIDI;
    'DDR1_DQS_DP'<15>:'(0,0,0,C28,0,0,0,0,0,0,0,0,0,0,0,0,0,0,0,0,0,0,0,0,0,0,0,~
0,0,0)';BIDI;
    'DDR1_DQS_DP'<14>:'(0,0,0,C34,0,0,0,0,0,0,0,0,0,0,0,0,0,0,0,0,0,0,0,0,0,0,0,~
0,0,0)';BIDI;
    'DDR1_DQS_DP'<13>:'(0,0,0,L42,0,0,0,0,0,0,0,0,0,0,0,0,0,0,0,0,0,0,0,0,0,0,0,~
0,0,0)';BIDI;
    'DDR1_DQS_DP'<12>:'(0,0,0,D73,0,0,0,0,0,0,0,0,0,0,0,0,0,0,0,0,0,0,0,0,0,0,0,~
0,0,0)';BIDI;
    'DDR1_DQS_DP'<11>:'(0,0,0,F79,0,0,0,0,0,0,0,0,0,0,0,0,0,0,0,0,0,0,0,0,0,0,0,~
0,0,0)';BIDI;
    'DDR1_DQS_DP'<10>:'(0,0,0,AF81,0,0,0,0,0,0,0,0,0,0,0,0,0,0,0,0,0,0,0,0,0,0,0~
,0,0,0)';BIDI;
    'DDR1_DQS_DP'<9>:'(0,0,0,AT81,0,0,0,0,0,0,0,0,0,0,0,0,0,0,0,0,0,0,0,0,0,0,0,~
0,0,0)';BIDI;
    'DDR1_DQS_DP'<8>:'(0,0,0,L68,0,0,0,0,0,0,0,0,0,0,0,0,0,0,0,0,0,0,0,0,0,0,0,0~
,0,0)';BIDI;
    'DDR1_DQS_DP'<7>:'(0,0,0,Y27,0,0,0,0,0,0,0,0,0,0,0,0,0,0,0,0,0,0,0,0,0,0,0,0~
,0,0)';BIDI;
    'DDR1_DQS_DP'<6>:'(0,0,0,E28,0,0,0,0,0,0,0,0,0,0,0,0,0,0,0,0,0,0,0,0,0,0,0,0~
,0,0)';BIDI;
    'DDR1_DQS_DP'<5>:'(0,0,0,E34,0,0,0,0,0,0,0,0,0,0,0,0,0,0,0,0,0,0,0,0,0,0,0,0~
,0,0)';BIDI;
    'DDR1_DQS_DP'<4>:'(0,0,0,R42,0,0,0,0,0,0,0,0,0,0,0,0,0,0,0,0,0,0,0,0,0,0,0,0~
,0,0)';BIDI;
    'DDR1_DQS_DP'<3>:'(0,0,0,F73,0,0,0,0,0,0,0,0,0,0,0,0,0,0,0,0,0,0,0,0,0,0,0,0~
,0,0)';BIDI;
    'DDR1_DQS_DP'<2>:'(0,0,0,H79,0,0,0,0,0,0,0,0,0,0,0,0,0,0,0,0,0,0,0,0,0,0,0,0~
,0,0)';BIDI;
    'DDR1_DQS_DP'<1>:'(0,0,0,AE80,0,0,0,0,0,0,0,0,0,0,0,0,0,0,0,0,0,0,0,0,0,0,0,~
0,0,0)';BIDI;
    'DDR1_DQS_DP'<0>:'(0,0,0,AR80,0,0,0,0,0,0,0,0,0,0,0,0,0,0,0,0,0,0,0,0,0,0,0,~
0,0,0)';BIDI;
    'DDR1_ECC'<7>:'(0,0,0,M67,0,0,0,0,0,0,0,0,0,0,0,0,0,0,0,0,0,0,0,0,0,0,0,0,0,~
0)';BIDI;
    'DDR1_ECC'<6>:'(0,0,0,H67,0,0,0,0,0,0,0,0,0,0,0,0,0,0,0,0,0,0,0,0,0,0,0,0,0,~
0)';BIDI;
    'DDR1_ECC'<5>:'(0,0,0,M69,0,0,0,0,0,0,0,0,0,0,0,0,0,0,0,0,0,0,0,0,0,0,0,0,0,~
0)';BIDI;
    'DDR1_ECC'<4>:'(0,0,0,L70,0,0,0,0,0,0,0,0,0,0,0,0,0,0,0,0,0,0,0,0,0,0,0,0,0,~
0)';BIDI;
    'DDR1_ECC'<3>:'(0,0,0,L66,0,0,0,0,0,0,0,0,0,0,0,0,0,0,0,0,0,0,0,0,0,0,0,0,0,~
0)';BIDI;
    'DDR1_ECC'<2>:'(0,0,0,J66,0,0,0,0,0,0,0,0,0,0,0,0,0,0,0,0,0,0,0,0,0,0,0,0,0,~
0)';BIDI;
    'DDR1_ECC'<1>:'(0,0,0,H69,0,0,0,0,0,0,0,0,0,0,0,0,0,0,0,0,0,0,0,0,0,0,0,0,0,~
0)';BIDI;
    'DDR1_ECC'<0>:'(0,0,0,J70,0,0,0,0,0,0,0,0,0,0,0,0,0,0,0,0,0,0,0,0,0,0,0,0,0,~
0)';BIDI;
    'DDR1_MA'<17>:'(0,0,0,N48,0,0,0,0,0,0,0,0,0,0,0,0,0,0,0,0,0,0,0,0,0,0,0,0,0,~
0)';OUT;
    'DDR1_MA'<16>:'(0,0,0,R52,0,0,0,0,0,0,0,0,0,0,0,0,0,0,0,0,0,0,0,0,0,0,0,0,0,~
0)';OUT;
    'DDR1_MA'<15>:'(0,0,0,N52,0,0,0,0,0,0,0,0,0,0,0,0,0,0,0,0,0,0,0,0,0,0,0,0,0,~
0)';OUT;
    'DDR1_MA'<14>:'(0,0,0,T51,0,0,0,0,0,0,0,0,0,0,0,0,0,0,0,0,0,0,0,0,0,0,0,0,0,~
0)';OUT;
    'DDR1_MA'<13>:'(0,0,0,M51,0,0,0,0,0,0,0,0,0,0,0,0,0,0,0,0,0,0,0,0,0,0,0,0,0,~
0)';OUT;
    'DDR1_MA'<12>:'(0,0,0,T61,0,0,0,0,0,0,0,0,0,0,0,0,0,0,0,0,0,0,0,0,0,0,0,0,0,~
0)';OUT;
    'DDR1_MA'<11>:'(0,0,0,R60,0,0,0,0,0,0,0,0,0,0,0,0,0,0,0,0,0,0,0,0,0,0,0,0,0,~
0)';OUT;
    'DDR1_MA'<10>:'(0,0,0,M55,0,0,0,0,0,0,0,0,0,0,0,0,0,0,0,0,0,0,0,0,0,0,0,0,0,~
0)';OUT;
    'DDR1_MA'<9>:'(0,0,0,K59,0,0,0,0,0,0,0,0,0,0,0,0,0,0,0,0,0,0,0,0,0,0,0,0,0,0~
)';OUT;
    'DDR1_MA'<8>:'(0,0,0,W60,0,0,0,0,0,0,0,0,0,0,0,0,0,0,0,0,0,0,0,0,0,0,0,0,0,0~
)';OUT;
    'DDR1_MA'<7>:'(0,0,0,V61,0,0,0,0,0,0,0,0,0,0,0,0,0,0,0,0,0,0,0,0,0,0,0,0,0,0~
)';OUT;
    'DDR1_MA'<6>:'(0,0,0,T59,0,0,0,0,0,0,0,0,0,0,0,0,0,0,0,0,0,0,0,0,0,0,0,0,0,0~
)';OUT;
    'DDR1_MA'<5>:'(0,0,0,R58,0,0,0,0,0,0,0,0,0,0,0,0,0,0,0,0,0,0,0,0,0,0,0,0,0,0~
)';OUT;
    'DDR1_MA'<4>:'(0,0,0,M59,0,0,0,0,0,0,0,0,0,0,0,0,0,0,0,0,0,0,0,0,0,0,0,0,0,0~
)';OUT;
    'DDR1_MA'<3>:'(0,0,0,N58,0,0,0,0,0,0,0,0,0,0,0,0,0,0,0,0,0,0,0,0,0,0,0,0,0,0~
)';OUT;
    'DDR1_MA'<2>:'(0,0,0,K57,0,0,0,0,0,0,0,0,0,0,0,0,0,0,0,0,0,0,0,0,0,0,0,0,0,0~
)';OUT;
    'DDR1_MA'<1>:'(0,0,0,J58,0,0,0,0,0,0,0,0,0,0,0,0,0,0,0,0,0,0,0,0,0,0,0,0,0,0~
)';OUT;
    'DDR1_MA'<0>:'(0,0,0,J52,0,0,0,0,0,0,0,0,0,0,0,0,0,0,0,0,0,0,0,0,0,0,0,0,0,0~
)';OUT;
    'DDR1_ODT'<3>:'(0,0,0,T47,0,0,0,0,0,0,0,0,0,0,0,0,0,0,0,0,0,0,0,0,0,0,0,0,0,~
0)';OUT;
    'DDR1_ODT'<2>:'(0,0,0,M49,0,0,0,0,0,0,0,0,0,0,0,0,0,0,0,0,0,0,0,0,0,0,0,0,0,~
0)';OUT;
    'DDR1_ODT'<1>:'(0,0,0,R48,0,0,0,0,0,0,0,0,0,0,0,0,0,0,0,0,0,0,0,0,0,0,0,0,0,~
0)';OUT;
    'DDR1_ODT'<0>:'(0,0,0,N50,0,0,0,0,0,0,0,0,0,0,0,0,0,0,0,0,0,0,0,0,0,0,0,0,0,~
0)';OUT;
    'DDR1_PAR':'(0,0,0,K53,0,0,0,0,0,0,0,0,0,0,0,0,0,0,0,0,0,0,0,0,0,0,0,0,0,0)';$S;OUT;
    'DDR2_ACT_N':'(0,0,0,0,AB61,0,0,0,0,0,0,0,0,0,0,0,0,0,0,0,0,0,0,0,0,0,0,0,0,~
0)';$S;OUT;
    'DDR2_ALERT_N':'(0,0,0,0,AD61,0,0,0,0,0,0,0,0,0,0,0,0,0,0,0,0,0,0,0,0,0,0,0,~
0,0)';$S;IN;
    'DDR2_BA'<1>:'(0,0,0,0,AE56,0,0,0,0,0,0,0,0,0,0,0,0,0,0,0,0,0,0,0,0,0,0,0,0,~
0)';OUT;
    'DDR2_BA'<0>:'(0,0,0,0,W52,0,0,0,0,0,0,0,0,0,0,0,0,0,0,0,0,0,0,0,0,0,0,0,0,0~
)';OUT;
    'DDR2_BG'<1>:'(0,0,0,0,AE62,0,0,0,0,0,0,0,0,0,0,0,0,0,0,0,0,0,0,0,0,0,0,0,0,~
0)';OUT;
    'DDR2_BG'<0>:'(0,0,0,0,AA60,0,0,0,0,0,0,0,0,0,0,0,0,0,0,0,0,0,0,0,0,0,0,0,0,~
0)';OUT;
    'DDR2_CAVREF':'(AH63,0,0,0,0,0,0,0,0,0,0,0,0,0,0,0,0,0,0,0,0,0,0,0,0,0,0,0,0~
,0)';$S;OUT;
    'DDR2_CID'<2>:'(0,0,0,0,AB45,0,0,0,0,0,0,0,0,0,0,0,0,0,0,0,0,0,0,0,0,0,0,0,0~
,0)';$S;OUT;
    'DDR2_CKE'<3>:'(0,0,0,0,AB63,0,0,0,0,0,0,0,0,0,0,0,0,0,0,0,0,0,0,0,0,0,0,0,0~
,0)';OUT;
    'DDR2_CKE'<2>:'(0,0,0,0,V63,0,0,0,0,0,0,0,0,0,0,0,0,0,0,0,0,0,0,0,0,0,0,0,0,~
0)';OUT;
    'DDR2_CKE'<1>:'(0,0,0,0,AD63,0,0,0,0,0,0,0,0,0,0,0,0,0,0,0,0,0,0,0,0,0,0,0,0~
,0)';OUT;
    'DDR2_CKE'<0>:'(0,0,0,0,AA62,0,0,0,0,0,0,0,0,0,0,0,0,0,0,0,0,0,0,0,0,0,0,0,0~
,0)';OUT;
    'DDR2_CLK_DN'<3>:'(0,0,0,0,W56,0,0,0,0,0,0,0,0,0,0,0,0,0,0,0,0,0,0,0,0,0,0,0~
,0,0)';OUT;
    'DDR2_CLK_DN'<2>:'(0,0,0,0,AA56,0,0,0,0,0,0,0,0,0,0,0,0,0,0,0,0,0,0,0,0,0,0,~
0,0,0)';OUT;
    'DDR2_CLK_DN'<1>:'(0,0,0,0,W54,0,0,0,0,0,0,0,0,0,0,0,0,0,0,0,0,0,0,0,0,0,0,0~
,0,0)';OUT;
    'DDR2_CLK_DN'<0>:'(0,0,0,0,AA54,0,0,0,0,0,0,0,0,0,0,0,0,0,0,0,0,0,0,0,0,0,0,~
0,0,0)';OUT;
    'DDR2_CLK_DP'<3>:'(0,0,0,0,V57,0,0,0,0,0,0,0,0,0,0,0,0,0,0,0,0,0,0,0,0,0,0,0~
,0,0)';OUT;
    'DDR2_CLK_DP'<2>:'(0,0,0,0,AB57,0,0,0,0,0,0,0,0,0,0,0,0,0,0,0,0,0,0,0,0,0,0,~
0,0,0)';OUT;
    'DDR2_CLK_DP'<1>:'(0,0,0,0,V55,0,0,0,0,0,0,0,0,0,0,0,0,0,0,0,0,0,0,0,0,0,0,0~
,0,0)';OUT;
    'DDR2_CLK_DP'<0>:'(0,0,0,0,AB55,0,0,0,0,0,0,0,0,0,0,0,0,0,0,0,0,0,0,0,0,0,0,~
0,0,0)';OUT;
    'DDR2_CS_N'<7>:'(0,0,0,0,V45,0,0,0,0,0,0,0,0,0,0,0,0,0,0,0,0,0,0,0,0,0,0,0,0~
,0)';OUT;
    'DDR2_CS_N'<6>:'(0,0,0,0,T45,0,0,0,0,0,0,0,0,0,0,0,0,0,0,0,0,0,0,0,0,0,0,0,0~
,0)';OUT;
    'DDR2_CS_N'<5>:'(0,0,0,0,W48,0,0,0,0,0,0,0,0,0,0,0,0,0,0,0,0,0,0,0,0,0,0,0,0~
,0)';OUT;
    'DDR2_CS_N'<4>:'(0,0,0,0,AB51,0,0,0,0,0,0,0,0,0,0,0,0,0,0,0,0,0,0,0,0,0,0,0,~
0,0)';OUT;
    'DDR2_CS_N'<3>:'(0,0,0,0,AA46,0,0,0,0,0,0,0,0,0,0,0,0,0,0,0,0,0,0,0,0,0,0,0,~
0,0)';OUT;
    'DDR2_CS_N'<2>:'(0,0,0,0,W46,0,0,0,0,0,0,0,0,0,0,0,0,0,0,0,0,0,0,0,0,0,0,0,0~
,0)';OUT;
    'DDR2_CS_N'<1>:'(0,0,0,0,AB49,0,0,0,0,0,0,0,0,0,0,0,0,0,0,0,0,0,0,0,0,0,0,0,~
0,0)';OUT;
    'DDR2_CS_N'<0>:'(0,0,0,0,V51,0,0,0,0,0,0,0,0,0,0,0,0,0,0,0,0,0,0,0,0,0,0,0,0~
,0)';OUT;
    'DDR2_DQ'<63>:'(0,0,0,0,AH23,0,0,0,0,0,0,0,0,0,0,0,0,0,0,0,0,0,0,0,0,0,0,0,0~
,0)';BIDI;
    'DDR2_DQ'<62>:'(0,0,0,0,AD23,0,0,0,0,0,0,0,0,0,0,0,0,0,0,0,0,0,0,0,0,0,0,0,0~
,0)';BIDI;
    'DDR2_DQ'<61>:'(0,0,0,0,AG26,0,0,0,0,0,0,0,0,0,0,0,0,0,0,0,0,0,0,0,0,0,0,0,0~
,0)';BIDI;
    'DDR2_DQ'<60>:'(0,0,0,0,AE26,0,0,0,0,0,0,0,0,0,0,0,0,0,0,0,0,0,0,0,0,0,0,0,0~
,0)';BIDI;
    'DDR2_DQ'<59>:'(0,0,0,0,AG22,0,0,0,0,0,0,0,0,0,0,0,0,0,0,0,0,0,0,0,0,0,0,0,0~
,0)';BIDI;
    'DDR2_DQ'<58>:'(0,0,0,0,AE22,0,0,0,0,0,0,0,0,0,0,0,0,0,0,0,0,0,0,0,0,0,0,0,0~
,0)';BIDI;
    'DDR2_DQ'<57>:'(0,0,0,0,AH25,0,0,0,0,0,0,0,0,0,0,0,0,0,0,0,0,0,0,0,0,0,0,0,0~
,0)';BIDI;
    'DDR2_DQ'<56>:'(0,0,0,0,AD25,0,0,0,0,0,0,0,0,0,0,0,0,0,0,0,0,0,0,0,0,0,0,0,0~
,0)';BIDI;
    'DDR2_DQ'<55>:'(0,0,0,0,AH29,0,0,0,0,0,0,0,0,0,0,0,0,0,0,0,0,0,0,0,0,0,0,0,0~
,0)';BIDI;
    'DDR2_DQ'<54>:'(0,0,0,0,AD29,0,0,0,0,0,0,0,0,0,0,0,0,0,0,0,0,0,0,0,0,0,0,0,0~
,0)';BIDI;
    'DDR2_DQ'<53>:'(0,0,0,0,AG32,0,0,0,0,0,0,0,0,0,0,0,0,0,0,0,0,0,0,0,0,0,0,0,0~
,0)';BIDI;
    'DDR2_DQ'<52>:'(0,0,0,0,AE32,0,0,0,0,0,0,0,0,0,0,0,0,0,0,0,0,0,0,0,0,0,0,0,0~
,0)';BIDI;
    'DDR2_DQ'<51>:'(0,0,0,0,AG28,0,0,0,0,0,0,0,0,0,0,0,0,0,0,0,0,0,0,0,0,0,0,0,0~
,0)';BIDI;
    'DDR2_DQ'<50>:'(0,0,0,0,AE28,0,0,0,0,0,0,0,0,0,0,0,0,0,0,0,0,0,0,0,0,0,0,0,0~
,0)';BIDI;
    'DDR2_DQ'<49>:'(0,0,0,0,AH31,0,0,0,0,0,0,0,0,0,0,0,0,0,0,0,0,0,0,0,0,0,0,0,0~
,0)';BIDI;
    'DDR2_DQ'<48>:'(0,0,0,0,AD31,0,0,0,0,0,0,0,0,0,0,0,0,0,0,0,0,0,0,0,0,0,0,0,0~
,0)';BIDI;
    'DDR2_DQ'<47>:'(0,0,0,0,AA32,0,0,0,0,0,0,0,0,0,0,0,0,0,0,0,0,0,0,0,0,0,0,0,0~
,0)';BIDI;
    'DDR2_DQ'<46>:'(0,0,0,0,U32,0,0,0,0,0,0,0,0,0,0,0,0,0,0,0,0,0,0,0,0,0,0,0,0,~
0)';BIDI;
    'DDR2_DQ'<45>:'(0,0,0,0,Y35,0,0,0,0,0,0,0,0,0,0,0,0,0,0,0,0,0,0,0,0,0,0,0,0,~
0)';BIDI;
    'DDR2_DQ'<44>:'(0,0,0,0,V35,0,0,0,0,0,0,0,0,0,0,0,0,0,0,0,0,0,0,0,0,0,0,0,0,~
0)';BIDI;
    'DDR2_DQ'<43>:'(0,0,0,0,Y31,0,0,0,0,0,0,0,0,0,0,0,0,0,0,0,0,0,0,0,0,0,0,0,0,~
0)';BIDI;
    'DDR2_DQ'<42>:'(0,0,0,0,V31,0,0,0,0,0,0,0,0,0,0,0,0,0,0,0,0,0,0,0,0,0,0,0,0,~
0)';BIDI;
    'DDR2_DQ'<41>:'(0,0,0,0,AA34,0,0,0,0,0,0,0,0,0,0,0,0,0,0,0,0,0,0,0,0,0,0,0,0~
,0)';BIDI;
    'DDR2_DQ'<40>:'(0,0,0,0,U34,0,0,0,0,0,0,0,0,0,0,0,0,0,0,0,0,0,0,0,0,0,0,0,0,~
0)';BIDI;
    'DDR2_DQ'<39>:'(0,0,0,0,AA38,0,0,0,0,0,0,0,0,0,0,0,0,0,0,0,0,0,0,0,0,0,0,0,0~
,0)';BIDI;
    'DDR2_DQ'<38>:'(0,0,0,0,U38,0,0,0,0,0,0,0,0,0,0,0,0,0,0,0,0,0,0,0,0,0,0,0,0,~
0)';BIDI;
    'DDR2_DQ'<37>:'(0,0,0,0,Y41,0,0,0,0,0,0,0,0,0,0,0,0,0,0,0,0,0,0,0,0,0,0,0,0,~
0)';BIDI;
    'DDR2_DQ'<36>:'(0,0,0,0,V41,0,0,0,0,0,0,0,0,0,0,0,0,0,0,0,0,0,0,0,0,0,0,0,0,~
0)';BIDI;
    'DDR2_DQ'<35>:'(0,0,0,0,Y37,0,0,0,0,0,0,0,0,0,0,0,0,0,0,0,0,0,0,0,0,0,0,0,0,~
0)';BIDI;
    'DDR2_DQ'<34>:'(0,0,0,0,V37,0,0,0,0,0,0,0,0,0,0,0,0,0,0,0,0,0,0,0,0,0,0,0,0,~
0)';BIDI;
    'DDR2_DQ'<33>:'(0,0,0,0,AA40,0,0,0,0,0,0,0,0,0,0,0,0,0,0,0,0,0,0,0,0,0,0,0,0~
,0)';BIDI;
    'DDR2_DQ'<32>:'(0,0,0,0,U40,0,0,0,0,0,0,0,0,0,0,0,0,0,0,0,0,0,0,0,0,0,0,0,0,~
0)';BIDI;
    'DDR2_DQ'<31>:'(0,0,0,0,AT65,0,0,0,0,0,0,0,0,0,0,0,0,0,0,0,0,0,0,0,0,0,0,0,0~
,0)';BIDI;
    'DDR2_DQ'<30>:'(0,0,0,0,AM65,0,0,0,0,0,0,0,0,0,0,0,0,0,0,0,0,0,0,0,0,0,0,0,0~
,0)';BIDI;
    'DDR2_DQ'<29>:'(0,0,0,0,AR68,0,0,0,0,0,0,0,0,0,0,0,0,0,0,0,0,0,0,0,0,0,0,0,0~
,0)';BIDI;
    'DDR2_DQ'<28>:'(0,0,0,0,AN68,0,0,0,0,0,0,0,0,0,0,0,0,0,0,0,0,0,0,0,0,0,0,0,0~
,0)';BIDI;
    'DDR2_DQ'<27>:'(0,0,0,0,AR64,0,0,0,0,0,0,0,0,0,0,0,0,0,0,0,0,0,0,0,0,0,0,0,0~
,0)';BIDI;
    'DDR2_DQ'<26>:'(0,0,0,0,AN64,0,0,0,0,0,0,0,0,0,0,0,0,0,0,0,0,0,0,0,0,0,0,0,0~
,0)';BIDI;
    'DDR2_DQ'<25>:'(0,0,0,0,AT67,0,0,0,0,0,0,0,0,0,0,0,0,0,0,0,0,0,0,0,0,0,0,0,0~
,0)';BIDI;
    'DDR2_DQ'<24>:'(0,0,0,0,AM67,0,0,0,0,0,0,0,0,0,0,0,0,0,0,0,0,0,0,0,0,0,0,0,0~
,0)';BIDI;
    'DDR2_DQ'<23>:'(0,0,0,0,V69,0,0,0,0,0,0,0,0,0,0,0,0,0,0,0,0,0,0,0,0,0,0,0,0,~
0)';BIDI;
    'DDR2_DQ'<22>:'(0,0,0,0,T71,0,0,0,0,0,0,0,0,0,0,0,0,0,0,0,0,0,0,0,0,0,0,0,0,~
0)';BIDI;
    'DDR2_DQ'<21>:'(0,0,0,0,AB71,0,0,0,0,0,0,0,0,0,0,0,0,0,0,0,0,0,0,0,0,0,0,0,0~
,0)';BIDI;
    'DDR2_DQ'<20>:'(0,0,0,0,AA72,0,0,0,0,0,0,0,0,0,0,0,0,0,0,0,0,0,0,0,0,0,0,0,0~
,0)';BIDI;
    'DDR2_DQ'<19>:'(0,0,0,0,T69,0,0,0,0,0,0,0,0,0,0,0,0,0,0,0,0,0,0,0,0,0,0,0,0,~
0)';BIDI;
    'DDR2_DQ'<18>:'(0,0,0,0,R70,0,0,0,0,0,0,0,0,0,0,0,0,0,0,0,0,0,0,0,0,0,0,0,0,~
0)';BIDI;
    'DDR2_DQ'<17>:'(0,0,0,0,AA70,0,0,0,0,0,0,0,0,0,0,0,0,0,0,0,0,0,0,0,0,0,0,0,0~
,0)';BIDI;
    'DDR2_DQ'<16>:'(0,0,0,0,W72,0,0,0,0,0,0,0,0,0,0,0,0,0,0,0,0,0,0,0,0,0,0,0,0,~
0)';BIDI;
    'DDR2_DQ'<15>:'(0,0,0,0,Y75,0,0,0,0,0,0,0,0,0,0,0,0,0,0,0,0,0,0,0,0,0,0,0,0,~
0)';BIDI;
    'DDR2_DQ'<14>:'(0,0,0,0,AB77,0,0,0,0,0,0,0,0,0,0,0,0,0,0,0,0,0,0,0,0,0,0,0,0~
,0)';BIDI;
    'DDR2_DQ'<13>:'(0,0,0,0,AE74,0,0,0,0,0,0,0,0,0,0,0,0,0,0,0,0,0,0,0,0,0,0,0,0~
,0)';BIDI;
    'DDR2_DQ'<12>:'(0,0,0,0,AF75,0,0,0,0,0,0,0,0,0,0,0,0,0,0,0,0,0,0,0,0,0,0,0,0~
,0)';BIDI;
    'DDR2_DQ'<11>:'(0,0,0,0,W76,0,0,0,0,0,0,0,0,0,0,0,0,0,0,0,0,0,0,0,0,0,0,0,0,~
0)';BIDI;
    'DDR2_DQ'<10>:'(0,0,0,0,Y77,0,0,0,0,0,0,0,0,0,0,0,0,0,0,0,0,0,0,0,0,0,0,0,0,~
0)';BIDI;
    'DDR2_DQ'<9>:'(0,0,0,0,AC74,0,0,0,0,0,0,0,0,0,0,0,0,0,0,0,0,0,0,0,0,0,0,0,0,~
0)';BIDI;
    'DDR2_DQ'<8>:'(0,0,0,0,AE76,0,0,0,0,0,0,0,0,0,0,0,0,0,0,0,0,0,0,0,0,0,0,0,0,~
0)';BIDI;
    'DDR2_DQ'<7>:'(0,0,0,0,AK75,0,0,0,0,0,0,0,0,0,0,0,0,0,0,0,0,0,0,0,0,0,0,0,0,~
0)';BIDI;
    'DDR2_DQ'<6>:'(0,0,0,0,AM77,0,0,0,0,0,0,0,0,0,0,0,0,0,0,0,0,0,0,0,0,0,0,0,0,~
0)';BIDI;
    'DDR2_DQ'<5>:'(0,0,0,0,AR74,0,0,0,0,0,0,0,0,0,0,0,0,0,0,0,0,0,0,0,0,0,0,0,0,~
0)';BIDI;
    'DDR2_DQ'<4>:'(0,0,0,0,AT75,0,0,0,0,0,0,0,0,0,0,0,0,0,0,0,0,0,0,0,0,0,0,0,0,~
0)';BIDI;
    'DDR2_DQ'<3>:'(0,0,0,0,AJ76,0,0,0,0,0,0,0,0,0,0,0,0,0,0,0,0,0,0,0,0,0,0,0,0,~
0)';BIDI;
    'DDR2_DQ'<2>:'(0,0,0,0,AK77,0,0,0,0,0,0,0,0,0,0,0,0,0,0,0,0,0,0,0,0,0,0,0,0,~
0)';BIDI;
    'DDR2_DQ'<1>:'(0,0,0,0,AN74,0,0,0,0,0,0,0,0,0,0,0,0,0,0,0,0,0,0,0,0,0,0,0,0,~
0)';BIDI;
    'DDR2_DQ'<0>:'(0,0,0,0,AR76,0,0,0,0,0,0,0,0,0,0,0,0,0,0,0,0,0,0,0,0,0,0,0,0,~
0)';BIDI;
    'DDR2_DQS_DN'<17>:'(0,0,0,0,AT71,0,0,0,0,0,0,0,0,0,0,0,0,0,0,0,0,0,0,0,0,0,0~
,0,0,0)';BIDI;
    'DDR2_DQS_DN'<16>:'(0,0,0,0,AC24,0,0,0,0,0,0,0,0,0,0,0,0,0,0,0,0,0,0,0,0,0,0~
,0,0,0)';BIDI;
    'DDR2_DQS_DN'<15>:'(0,0,0,0,AC30,0,0,0,0,0,0,0,0,0,0,0,0,0,0,0,0,0,0,0,0,0,0~
,0,0,0)';BIDI;
    'DDR2_DQS_DN'<14>:'(0,0,0,0,T33,0,0,0,0,0,0,0,0,0,0,0,0,0,0,0,0,0,0,0,0,0,0,~
0,0,0)';BIDI;
    'DDR2_DQS_DN'<13>:'(0,0,0,0,T39,0,0,0,0,0,0,0,0,0,0,0,0,0,0,0,0,0,0,0,0,0,0,~
0,0,0)';BIDI;
    'DDR2_DQS_DN'<12>:'(0,0,0,0,AL66,0,0,0,0,0,0,0,0,0,0,0,0,0,0,0,0,0,0,0,0,0,0~
,0,0,0)';BIDI;
    'DDR2_DQS_DN'<11>:'(0,0,0,0,U72,0,0,0,0,0,0,0,0,0,0,0,0,0,0,0,0,0,0,0,0,0,0,~
0,0,0)';BIDI;
    'DDR2_DQS_DN'<10>:'(0,0,0,0,AD77,0,0,0,0,0,0,0,0,0,0,0,0,0,0,0,0,0,0,0,0,0,0~
,0,0,0)';BIDI;
    'DDR2_DQS_DN'<9>:'(0,0,0,0,AP77,0,0,0,0,0,0,0,0,0,0,0,0,0,0,0,0,0,0,0,0,0,0,~
0,0,0)';BIDI;
    'DDR2_DQS_DN'<8>:'(0,0,0,0,BB71,0,0,0,0,0,0,0,0,0,0,0,0,0,0,0,0,0,0,0,0,0,0,~
0,0,0)';BIDI;
    'DDR2_DQS_DN'<7>:'(0,0,0,0,AJ24,0,0,0,0,0,0,0,0,0,0,0,0,0,0,0,0,0,0,0,0,0,0,~
0,0,0)';BIDI;
    'DDR2_DQS_DN'<6>:'(0,0,0,0,AJ30,0,0,0,0,0,0,0,0,0,0,0,0,0,0,0,0,0,0,0,0,0,0,~
0,0,0)';BIDI;
    'DDR2_DQS_DN'<5>:'(0,0,0,0,AB33,0,0,0,0,0,0,0,0,0,0,0,0,0,0,0,0,0,0,0,0,0,0,~
0,0,0)';BIDI;
    'DDR2_DQS_DN'<4>:'(0,0,0,0,AB39,0,0,0,0,0,0,0,0,0,0,0,0,0,0,0,0,0,0,0,0,0,0,~
0,0,0)';BIDI;
    'DDR2_DQS_DN'<3>:'(0,0,0,0,AU66,0,0,0,0,0,0,0,0,0,0,0,0,0,0,0,0,0,0,0,0,0,0,~
0,0,0)';BIDI;
    'DDR2_DQS_DN'<2>:'(0,0,0,0,Y69,0,0,0,0,0,0,0,0,0,0,0,0,0,0,0,0,0,0,0,0,0,0,0~
,0,0)';BIDI;
    'DDR2_DQS_DN'<1>:'(0,0,0,0,AA74,0,0,0,0,0,0,0,0,0,0,0,0,0,0,0,0,0,0,0,0,0,0,~
0,0,0)';BIDI;
    'DDR2_DQS_DN'<0>:'(0,0,0,0,AL74,0,0,0,0,0,0,0,0,0,0,0,0,0,0,0,0,0,0,0,0,0,0,~
0,0,0)';BIDI;
    'DDR2_DQS_DP'<17>:'(0,0,0,0,AV71,0,0,0,0,0,0,0,0,0,0,0,0,0,0,0,0,0,0,0,0,0,0~
,0,0,0)';BIDI;
    'DDR2_DQS_DP'<16>:'(0,0,0,0,AE24,0,0,0,0,0,0,0,0,0,0,0,0,0,0,0,0,0,0,0,0,0,0~
,0,0,0)';BIDI;
    'DDR2_DQS_DP'<15>:'(0,0,0,0,AE30,0,0,0,0,0,0,0,0,0,0,0,0,0,0,0,0,0,0,0,0,0,0~
,0,0,0)';BIDI;
    'DDR2_DQS_DP'<14>:'(0,0,0,0,V33,0,0,0,0,0,0,0,0,0,0,0,0,0,0,0,0,0,0,0,0,0,0,~
0,0,0)';BIDI;
    'DDR2_DQS_DP'<13>:'(0,0,0,0,V39,0,0,0,0,0,0,0,0,0,0,0,0,0,0,0,0,0,0,0,0,0,0,~
0,0,0)';BIDI;
    'DDR2_DQS_DP'<12>:'(0,0,0,0,AN66,0,0,0,0,0,0,0,0,0,0,0,0,0,0,0,0,0,0,0,0,0,0~
,0,0,0)';BIDI;
    'DDR2_DQS_DP'<11>:'(0,0,0,0,V71,0,0,0,0,0,0,0,0,0,0,0,0,0,0,0,0,0,0,0,0,0,0,~
0,0,0)';BIDI;
    'DDR2_DQS_DP'<10>:'(0,0,0,0,AC76,0,0,0,0,0,0,0,0,0,0,0,0,0,0,0,0,0,0,0,0,0,0~
,0,0,0)';BIDI;
    'DDR2_DQS_DP'<9>:'(0,0,0,0,AN76,0,0,0,0,0,0,0,0,0,0,0,0,0,0,0,0,0,0,0,0,0,0,~
0,0,0)';BIDI;
    'DDR2_DQS_DP'<8>:'(0,0,0,0,AY71,0,0,0,0,0,0,0,0,0,0,0,0,0,0,0,0,0,0,0,0,0,0,~
0,0,0)';BIDI;
    'DDR2_DQS_DP'<7>:'(0,0,0,0,AG24,0,0,0,0,0,0,0,0,0,0,0,0,0,0,0,0,0,0,0,0,0,0,~
0,0,0)';BIDI;
    'DDR2_DQS_DP'<6>:'(0,0,0,0,AG30,0,0,0,0,0,0,0,0,0,0,0,0,0,0,0,0,0,0,0,0,0,0,~
0,0,0)';BIDI;
    'DDR2_DQS_DP'<5>:'(0,0,0,0,Y33,0,0,0,0,0,0,0,0,0,0,0,0,0,0,0,0,0,0,0,0,0,0,0~
,0,0)';BIDI;
    'DDR2_DQS_DP'<4>:'(0,0,0,0,Y39,0,0,0,0,0,0,0,0,0,0,0,0,0,0,0,0,0,0,0,0,0,0,0~
,0,0)';BIDI;
    'DDR2_DQS_DP'<3>:'(0,0,0,0,AR66,0,0,0,0,0,0,0,0,0,0,0,0,0,0,0,0,0,0,0,0,0,0,~
0,0,0)';BIDI;
    'DDR2_DQS_DP'<2>:'(0,0,0,0,W70,0,0,0,0,0,0,0,0,0,0,0,0,0,0,0,0,0,0,0,0,0,0,0~
,0,0)';BIDI;
    'DDR2_DQS_DP'<1>:'(0,0,0,0,AB75,0,0,0,0,0,0,0,0,0,0,0,0,0,0,0,0,0,0,0,0,0,0,~
0,0,0)';BIDI;
    'DDR2_DQS_DP'<0>:'(0,0,0,0,AM75,0,0,0,0,0,0,0,0,0,0,0,0,0,0,0,0,0,0,0,0,0,0,~
0,0,0)';BIDI;
    'DDR2_ECC'<7>:'(0,0,0,0,BA70,0,0,0,0,0,0,0,0,0,0,0,0,0,0,0,0,0,0,0,0,0,0,0,0~
,0)';BIDI;
    'DDR2_ECC'<6>:'(0,0,0,0,AU70,0,0,0,0,0,0,0,0,0,0,0,0,0,0,0,0,0,0,0,0,0,0,0,0~
,0)';BIDI;
    'DDR2_ECC'<5>:'(0,0,0,0,AY73,0,0,0,0,0,0,0,0,0,0,0,0,0,0,0,0,0,0,0,0,0,0,0,0~
,0)';BIDI;
    'DDR2_ECC'<4>:'(0,0,0,0,AV73,0,0,0,0,0,0,0,0,0,0,0,0,0,0,0,0,0,0,0,0,0,0,0,0~
,0)';BIDI;
    'DDR2_ECC'<3>:'(0,0,0,0,AY69,0,0,0,0,0,0,0,0,0,0,0,0,0,0,0,0,0,0,0,0,0,0,0,0~
,0)';BIDI;
    'DDR2_ECC'<2>:'(0,0,0,0,AV69,0,0,0,0,0,0,0,0,0,0,0,0,0,0,0,0,0,0,0,0,0,0,0,0~
,0)';BIDI;
    'DDR2_ECC'<1>:'(0,0,0,0,BA72,0,0,0,0,0,0,0,0,0,0,0,0,0,0,0,0,0,0,0,0,0,0,0,0~
,0)';BIDI;
    'DDR2_ECC'<0>:'(0,0,0,0,AU72,0,0,0,0,0,0,0,0,0,0,0,0,0,0,0,0,0,0,0,0,0,0,0,0~
,0)';BIDI;
    'DDR2_MA'<17>:'(0,0,0,0,AC46,0,0,0,0,0,0,0,0,0,0,0,0,0,0,0,0,0,0,0,0,0,0,0,0~
,0)';OUT;
    'DDR2_MA'<16>:'(0,0,0,0,AA52,0,0,0,0,0,0,0,0,0,0,0,0,0,0,0,0,0,0,0,0,0,0,0,0~
,0)';OUT;
    'DDR2_MA'<15>:'(0,0,0,0,AE54,0,0,0,0,0,0,0,0,0,0,0,0,0,0,0,0,0,0,0,0,0,0,0,0~
,0)';OUT;
    'DDR2_MA'<14>:'(0,0,0,0,W50,0,0,0,0,0,0,0,0,0,0,0,0,0,0,0,0,0,0,0,0,0,0,0,0,~
0)';OUT;
    'DDR2_MA'<13>:'(0,0,0,0,AD53,0,0,0,0,0,0,0,0,0,0,0,0,0,0,0,0,0,0,0,0,0,0,0,0~
,0)';OUT;
    'DDR2_MA'<12>:'(0,0,0,0,AG62,0,0,0,0,0,0,0,0,0,0,0,0,0,0,0,0,0,0,0,0,0,0,0,0~
,0)';OUT;
    'DDR2_MA'<11>:'(0,0,0,0,AG60,0,0,0,0,0,0,0,0,0,0,0,0,0,0,0,0,0,0,0,0,0,0,0,0~
,0)';OUT;
    'DDR2_MA'<10>:'(0,0,0,0,AD55,0,0,0,0,0,0,0,0,0,0,0,0,0,0,0,0,0,0,0,0,0,0,0,0~
,0)';OUT;
    'DDR2_MA'<9>:'(0,0,0,0,AG58,0,0,0,0,0,0,0,0,0,0,0,0,0,0,0,0,0,0,0,0,0,0,0,0,~
0)';OUT;
    'DDR2_MA'<8>:'(0,0,0,0,AD59,0,0,0,0,0,0,0,0,0,0,0,0,0,0,0,0,0,0,0,0,0,0,0,0,~
0)';OUT;
    'DDR2_MA'<7>:'(0,0,0,0,AE60,0,0,0,0,0,0,0,0,0,0,0,0,0,0,0,0,0,0,0,0,0,0,0,0,~
0)';OUT;
    'DDR2_MA'<6>:'(0,0,0,0,AB59,0,0,0,0,0,0,0,0,0,0,0,0,0,0,0,0,0,0,0,0,0,0,0,0,~
0)';OUT;
    'DDR2_MA'<5>:'(0,0,0,0,V59,0,0,0,0,0,0,0,0,0,0,0,0,0,0,0,0,0,0,0,0,0,0,0,0,0~
)';OUT;
    'DDR2_MA'<4>:'(0,0,0,0,AA58,0,0,0,0,0,0,0,0,0,0,0,0,0,0,0,0,0,0,0,0,0,0,0,0,~
0)';OUT;
    'DDR2_MA'<3>:'(0,0,0,0,W58,0,0,0,0,0,0,0,0,0,0,0,0,0,0,0,0,0,0,0,0,0,0,0,0,0~
)';OUT;
    'DDR2_MA'<2>:'(0,0,0,0,AD57,0,0,0,0,0,0,0,0,0,0,0,0,0,0,0,0,0,0,0,0,0,0,0,0,~
0)';OUT;
    'DDR2_MA'<1>:'(0,0,0,0,AE58,0,0,0,0,0,0,0,0,0,0,0,0,0,0,0,0,0,0,0,0,0,0,0,0,~
0)';OUT;
    'DDR2_MA'<0>:'(0,0,0,0,AB53,0,0,0,0,0,0,0,0,0,0,0,0,0,0,0,0,0,0,0,0,0,0,0,0,~
0)';OUT;
    'DDR2_ODT'<3>:'(0,0,0,0,AB47,0,0,0,0,0,0,0,0,0,0,0,0,0,0,0,0,0,0,0,0,0,0,0,0~
,0)';OUT;
    'DDR2_ODT'<2>:'(0,0,0,0,V49,0,0,0,0,0,0,0,0,0,0,0,0,0,0,0,0,0,0,0,0,0,0,0,0,~
0)';OUT;
    'DDR2_ODT'<1>:'(0,0,0,0,AA48,0,0,0,0,0,0,0,0,0,0,0,0,0,0,0,0,0,0,0,0,0,0,0,0~
,0)';OUT;
    'DDR2_ODT'<0>:'(0,0,0,0,AA50,0,0,0,0,0,0,0,0,0,0,0,0,0,0,0,0,0,0,0,0,0,0,0,0~
,0)';OUT;
    'DDR2_PAR':'(0,0,0,0,V53,0,0,0,0,0,0,0,0,0,0,0,0,0,0,0,0,0,0,0,0,0,0,0,0,0)';$S;OUT;
    'DDR345_DRAM_PWR_OK':'(CR28,0,0,0,0,0,0,0,0,0,0,0,0,0,0,0,0,0,0,0,0,0,0,0,0,~
0,0,0,0,0)';$S;IN;
    'DDR345_RCOMP'<2>:'(DD49,0,0,0,0,0,0,0,0,0,0,0,0,0,0,0,0,0,0,0,0,0,0,0,0,0,0~
,0,0,0)';BIDI;
    'DDR345_RCOMP'<1>:'(DD47,0,0,0,0,0,0,0,0,0,0,0,0,0,0,0,0,0,0,0,0,0,0,0,0,0,0~
,0,0,0)';BIDI;
    'DDR345_RCOMP'<0>:'(DC48,0,0,0,0,0,0,0,0,0,0,0,0,0,0,0,0,0,0,0,0,0,0,0,0,0,0~
,0,0,0)';BIDI;
    'DDR345_RESET_N':'(DV63,0,0,0,0,0,0,0,0,0,0,0,0,0,0,0,0,0,0,0,0,0,0,0,0,0,0,~
0,0,0)';$S;OUT;
    'DDR345_SPDSCL':'(AE18,0,0,0,0,0,0,0,0,0,0,0,0,0,0,0,0,0,0,0,0,0,0,0,0,0,0,0~
,0,0)';$S;BIDI;
    'DDR345_SPDSDA':'(AD17,0,0,0,0,0,0,0,0,0,0,0,0,0,0,0,0,0,0,0,0,0,0,0,0,0,0,0~
,0,0)';$S;BIDI;
    'DDR3_ACT_N':'(0,0,0,0,0,DW60,0,0,0,0,0,0,0,0,0,0,0,0,0,0,0,0,0,0,0,0,0,0,0,~
0)';$S;OUT;
    'DDR3_ALERT_N':'(0,0,0,0,0,ED63,0,0,0,0,0,0,0,0,0,0,0,0,0,0,0,0,0,0,0,0,0,0,~
0,0)';$S;IN;
    'DDR3_BA'<1>:'(0,0,0,0,0,EA54,0,0,0,0,0,0,0,0,0,0,0,0,0,0,0,0,0,0,0,0,0,0,0,~
0)';OUT;
    'DDR3_BA'<0>:'(0,0,0,0,0,EE52,0,0,0,0,0,0,0,0,0,0,0,0,0,0,0,0,0,0,0,0,0,0,0,~
0)';OUT;
    'DDR3_BG'<1>:'(0,0,0,0,0,DW62,0,0,0,0,0,0,0,0,0,0,0,0,0,0,0,0,0,0,0,0,0,0,0,~
0)';OUT;
    'DDR3_BG'<0>:'(0,0,0,0,0,ED61,0,0,0,0,0,0,0,0,0,0,0,0,0,0,0,0,0,0,0,0,0,0,0,~
0)';OUT;
    'DDR3_CAVREF':'(CP61,0,0,0,0,0,0,0,0,0,0,0,0,0,0,0,0,0,0,0,0,0,0,0,0,0,0,0,0~
,0)';$S;OUT;
    'DDR3_CID'<2>:'(0,0,0,0,0,DV47,0,0,0,0,0,0,0,0,0,0,0,0,0,0,0,0,0,0,0,0,0,0,0~
,0)';$S;OUT;
    'DDR3_CKE'<3>:'(0,0,0,0,0,EB63,0,0,0,0,0,0,0,0,0,0,0,0,0,0,0,0,0,0,0,0,0,0,0~
,0)';OUT;
    'DDR3_CKE'<2>:'(0,0,0,0,0,EA62,0,0,0,0,0,0,0,0,0,0,0,0,0,0,0,0,0,0,0,0,0,0,0~
,0)';OUT;
    'DDR3_CKE'<1>:'(0,0,0,0,0,EF63,0,0,0,0,0,0,0,0,0,0,0,0,0,0,0,0,0,0,0,0,0,0,0~
,0)';OUT;
    'DDR3_CKE'<0>:'(0,0,0,0,0,EE62,0,0,0,0,0,0,0,0,0,0,0,0,0,0,0,0,0,0,0,0,0,0,0~
,0)';OUT;
    'DDR3_CLK_DN'<3>:'(0,0,0,0,0,EF57,0,0,0,0,0,0,0,0,0,0,0,0,0,0,0,0,0,0,0,0,0,~
0,0,0)';OUT;
    'DDR3_CLK_DN'<2>:'(0,0,0,0,0,DW56,0,0,0,0,0,0,0,0,0,0,0,0,0,0,0,0,0,0,0,0,0,~
0,0,0)';OUT;
    'DDR3_CLK_DN'<1>:'(0,0,0,0,0,EF55,0,0,0,0,0,0,0,0,0,0,0,0,0,0,0,0,0,0,0,0,0,~
0,0,0)';OUT;
    'DDR3_CLK_DN'<0>:'(0,0,0,0,0,ED55,0,0,0,0,0,0,0,0,0,0,0,0,0,0,0,0,0,0,0,0,0,~
0,0,0)';OUT;
    'DDR3_CLK_DP'<3>:'(0,0,0,0,0,EE56,0,0,0,0,0,0,0,0,0,0,0,0,0,0,0,0,0,0,0,0,0,~
0,0,0)';OUT;
    'DDR3_CLK_DP'<2>:'(0,0,0,0,0,EA56,0,0,0,0,0,0,0,0,0,0,0,0,0,0,0,0,0,0,0,0,0,~
0,0,0)';OUT;
    'DDR3_CLK_DP'<1>:'(0,0,0,0,0,EE54,0,0,0,0,0,0,0,0,0,0,0,0,0,0,0,0,0,0,0,0,0,~
0,0,0)';OUT;
    'DDR3_CLK_DP'<0>:'(0,0,0,0,0,EB55,0,0,0,0,0,0,0,0,0,0,0,0,0,0,0,0,0,0,0,0,0,~
0,0,0)';OUT;
    'DDR3_CS_N'<7>:'(0,0,0,0,0,EB45,0,0,0,0,0,0,0,0,0,0,0,0,0,0,0,0,0,0,0,0,0,0,~
0,0)';OUT;
    'DDR3_CS_N'<6>:'(0,0,0,0,0,DV45,0,0,0,0,0,0,0,0,0,0,0,0,0,0,0,0,0,0,0,0,0,0,~
0,0)';OUT;
    'DDR3_CS_N'<5>:'(0,0,0,0,0,EB49,0,0,0,0,0,0,0,0,0,0,0,0,0,0,0,0,0,0,0,0,0,0,~
0,0)';OUT;
    'DDR3_CS_N'<4>:'(0,0,0,0,0,EB51,0,0,0,0,0,0,0,0,0,0,0,0,0,0,0,0,0,0,0,0,0,0,~
0,0)';OUT;
    'DDR3_CS_N'<3>:'(0,0,0,0,0,EB47,0,0,0,0,0,0,0,0,0,0,0,0,0,0,0,0,0,0,0,0,0,0,~
0,0)';OUT;
    'DDR3_CS_N'<2>:'(0,0,0,0,0,ED47,0,0,0,0,0,0,0,0,0,0,0,0,0,0,0,0,0,0,0,0,0,0,~
0,0)';OUT;
    'DDR3_CS_N'<1>:'(0,0,0,0,0,ED49,0,0,0,0,0,0,0,0,0,0,0,0,0,0,0,0,0,0,0,0,0,0,~
0,0)';OUT;
    'DDR3_CS_N'<0>:'(0,0,0,0,0,EF51,0,0,0,0,0,0,0,0,0,0,0,0,0,0,0,0,0,0,0,0,0,0,~
0,0)';OUT;
    'DDR3_DQ'<63>:'(0,0,0,0,0,DW22,0,0,0,0,0,0,0,0,0,0,0,0,0,0,0,0,0,0,0,0,0,0,0~
,0)';BIDI;
    'DDR3_DQ'<62>:'(0,0,0,0,0,EC22,0,0,0,0,0,0,0,0,0,0,0,0,0,0,0,0,0,0,0,0,0,0,0~
,0)';BIDI;
    'DDR3_DQ'<61>:'(0,0,0,0,0,DT25,0,0,0,0,0,0,0,0,0,0,0,0,0,0,0,0,0,0,0,0,0,0,0~
,0)';BIDI;
    'DDR3_DQ'<60>:'(0,0,0,0,0,DP25,0,0,0,0,0,0,0,0,0,0,0,0,0,0,0,0,0,0,0,0,0,0,0~
,0)';BIDI;
    'DDR3_DQ'<59>:'(0,0,0,0,0,EB21,0,0,0,0,0,0,0,0,0,0,0,0,0,0,0,0,0,0,0,0,0,0,0~
,0)';BIDI;
    'DDR3_DQ'<58>:'(0,0,0,0,0,DY21,0,0,0,0,0,0,0,0,0,0,0,0,0,0,0,0,0,0,0,0,0,0,0~
,0)';BIDI;
    'DDR3_DQ'<57>:'(0,0,0,0,0,DU24,0,0,0,0,0,0,0,0,0,0,0,0,0,0,0,0,0,0,0,0,0,0,0~
,0)';BIDI;
    'DDR3_DQ'<56>:'(0,0,0,0,0,DN24,0,0,0,0,0,0,0,0,0,0,0,0,0,0,0,0,0,0,0,0,0,0,0~
,0)';BIDI;
    'DDR3_DQ'<55>:'(0,0,0,0,0,DU28,0,0,0,0,0,0,0,0,0,0,0,0,0,0,0,0,0,0,0,0,0,0,0~
,0)';BIDI;
    'DDR3_DQ'<54>:'(0,0,0,0,0,DN28,0,0,0,0,0,0,0,0,0,0,0,0,0,0,0,0,0,0,0,0,0,0,0~
,0)';BIDI;
    'DDR3_DQ'<53>:'(0,0,0,0,0,DT31,0,0,0,0,0,0,0,0,0,0,0,0,0,0,0,0,0,0,0,0,0,0,0~
,0)';BIDI;
    'DDR3_DQ'<52>:'(0,0,0,0,0,DP31,0,0,0,0,0,0,0,0,0,0,0,0,0,0,0,0,0,0,0,0,0,0,0~
,0)';BIDI;
    'DDR3_DQ'<51>:'(0,0,0,0,0,DT27,0,0,0,0,0,0,0,0,0,0,0,0,0,0,0,0,0,0,0,0,0,0,0~
,0)';BIDI;
    'DDR3_DQ'<50>:'(0,0,0,0,0,DP27,0,0,0,0,0,0,0,0,0,0,0,0,0,0,0,0,0,0,0,0,0,0,0~
,0)';BIDI;
    'DDR3_DQ'<49>:'(0,0,0,0,0,DU30,0,0,0,0,0,0,0,0,0,0,0,0,0,0,0,0,0,0,0,0,0,0,0~
,0)';BIDI;
    'DDR3_DQ'<48>:'(0,0,0,0,0,DN30,0,0,0,0,0,0,0,0,0,0,0,0,0,0,0,0,0,0,0,0,0,0,0~
,0)';BIDI;
    'DDR3_DQ'<47>:'(0,0,0,0,0,DU34,0,0,0,0,0,0,0,0,0,0,0,0,0,0,0,0,0,0,0,0,0,0,0~
,0)';BIDI;
    'DDR3_DQ'<46>:'(0,0,0,0,0,DN34,0,0,0,0,0,0,0,0,0,0,0,0,0,0,0,0,0,0,0,0,0,0,0~
,0)';BIDI;
    'DDR3_DQ'<45>:'(0,0,0,0,0,DT37,0,0,0,0,0,0,0,0,0,0,0,0,0,0,0,0,0,0,0,0,0,0,0~
,0)';BIDI;
    'DDR3_DQ'<44>:'(0,0,0,0,0,DP37,0,0,0,0,0,0,0,0,0,0,0,0,0,0,0,0,0,0,0,0,0,0,0~
,0)';BIDI;
    'DDR3_DQ'<43>:'(0,0,0,0,0,DT33,0,0,0,0,0,0,0,0,0,0,0,0,0,0,0,0,0,0,0,0,0,0,0~
,0)';BIDI;
    'DDR3_DQ'<42>:'(0,0,0,0,0,DP33,0,0,0,0,0,0,0,0,0,0,0,0,0,0,0,0,0,0,0,0,0,0,0~
,0)';BIDI;
    'DDR3_DQ'<41>:'(0,0,0,0,0,DU36,0,0,0,0,0,0,0,0,0,0,0,0,0,0,0,0,0,0,0,0,0,0,0~
,0)';BIDI;
    'DDR3_DQ'<40>:'(0,0,0,0,0,DN36,0,0,0,0,0,0,0,0,0,0,0,0,0,0,0,0,0,0,0,0,0,0,0~
,0)';BIDI;
    'DDR3_DQ'<39>:'(0,0,0,0,0,ED37,0,0,0,0,0,0,0,0,0,0,0,0,0,0,0,0,0,0,0,0,0,0,0~
,0)';BIDI;
    'DDR3_DQ'<38>:'(0,0,0,0,0,DY37,0,0,0,0,0,0,0,0,0,0,0,0,0,0,0,0,0,0,0,0,0,0,0~
,0)';BIDI;
    'DDR3_DQ'<37>:'(0,0,0,0,0,EA40,0,0,0,0,0,0,0,0,0,0,0,0,0,0,0,0,0,0,0,0,0,0,0~
,0)';BIDI;
    'DDR3_DQ'<36>:'(0,0,0,0,0,DY39,0,0,0,0,0,0,0,0,0,0,0,0,0,0,0,0,0,0,0,0,0,0,0~
,0)';BIDI;
    'DDR3_DQ'<35>:'(0,0,0,0,0,EC36,0,0,0,0,0,0,0,0,0,0,0,0,0,0,0,0,0,0,0,0,0,0,0~
,0)';BIDI;
    'DDR3_DQ'<34>:'(0,0,0,0,0,EA36,0,0,0,0,0,0,0,0,0,0,0,0,0,0,0,0,0,0,0,0,0,0,0~
,0)';BIDI;
    'DDR3_DQ'<33>:'(0,0,0,0,0,ED39,0,0,0,0,0,0,0,0,0,0,0,0,0,0,0,0,0,0,0,0,0,0,0~
,0)';BIDI;
    'DDR3_DQ'<32>:'(0,0,0,0,0,EC40,0,0,0,0,0,0,0,0,0,0,0,0,0,0,0,0,0,0,0,0,0,0,0~
,0)';BIDI;
    'DDR3_DQ'<31>:'(0,0,0,0,0,DU74,0,0,0,0,0,0,0,0,0,0,0,0,0,0,0,0,0,0,0,0,0,0,0~
,0)';BIDI;
    'DDR3_DQ'<30>:'(0,0,0,0,0,DN74,0,0,0,0,0,0,0,0,0,0,0,0,0,0,0,0,0,0,0,0,0,0,0~
,0)';BIDI;
    'DDR3_DQ'<29>:'(0,0,0,0,0,DT77,0,0,0,0,0,0,0,0,0,0,0,0,0,0,0,0,0,0,0,0,0,0,0~
,0)';BIDI;
    'DDR3_DQ'<28>:'(0,0,0,0,0,DP77,0,0,0,0,0,0,0,0,0,0,0,0,0,0,0,0,0,0,0,0,0,0,0~
,0)';BIDI;
    'DDR3_DQ'<27>:'(0,0,0,0,0,DT73,0,0,0,0,0,0,0,0,0,0,0,0,0,0,0,0,0,0,0,0,0,0,0~
,0)';BIDI;
    'DDR3_DQ'<26>:'(0,0,0,0,0,DP73,0,0,0,0,0,0,0,0,0,0,0,0,0,0,0,0,0,0,0,0,0,0,0~
,0)';BIDI;
    'DDR3_DQ'<25>:'(0,0,0,0,0,DU76,0,0,0,0,0,0,0,0,0,0,0,0,0,0,0,0,0,0,0,0,0,0,0~
,0)';BIDI;
    'DDR3_DQ'<24>:'(0,0,0,0,0,DN76,0,0,0,0,0,0,0,0,0,0,0,0,0,0,0,0,0,0,0,0,0,0,0~
,0)';BIDI;
    'DDR3_DQ'<23>:'(0,0,0,0,0,DN82,0,0,0,0,0,0,0,0,0,0,0,0,0,0,0,0,0,0,0,0,0,0,0~
,0)';BIDI;
    'DDR3_DQ'<22>:'(0,0,0,0,0,DR80,0,0,0,0,0,0,0,0,0,0,0,0,0,0,0,0,0,0,0,0,0,0,0~
,0)';BIDI;
    'DDR3_DQ'<21>:'(0,0,0,0,0,DJ80,0,0,0,0,0,0,0,0,0,0,0,0,0,0,0,0,0,0,0,0,0,0,0~
,0)';BIDI;
    'DDR3_DQ'<20>:'(0,0,0,0,0,DK79,0,0,0,0,0,0,0,0,0,0,0,0,0,0,0,0,0,0,0,0,0,0,0~
,0)';BIDI;
    'DDR3_DQ'<19>:'(0,0,0,0,0,DR82,0,0,0,0,0,0,0,0,0,0,0,0,0,0,0,0,0,0,0,0,0,0,0~
,0)';BIDI;
    'DDR3_DQ'<18>:'(0,0,0,0,0,DT81,0,0,0,0,0,0,0,0,0,0,0,0,0,0,0,0,0,0,0,0,0,0,0~
,0)';BIDI;
    'DDR3_DQ'<17>:'(0,0,0,0,0,DK81,0,0,0,0,0,0,0,0,0,0,0,0,0,0,0,0,0,0,0,0,0,0,0~
,0)';BIDI;
    'DDR3_DQ'<16>:'(0,0,0,0,0,DM79,0,0,0,0,0,0,0,0,0,0,0,0,0,0,0,0,0,0,0,0,0,0,0~
,0)';BIDI;
    'DDR3_DQ'<15>:'(0,0,0,0,0,DV85,0,0,0,0,0,0,0,0,0,0,0,0,0,0,0,0,0,0,0,0,0,0,0~
,0)';BIDI;
    'DDR3_DQ'<14>:'(0,0,0,0,0,DR84,0,0,0,0,0,0,0,0,0,0,0,0,0,0,0,0,0,0,0,0,0,0,0~
,0)';BIDI;
    'DDR3_DQ'<13>:'(0,0,0,0,0,DE84,0,0,0,0,0,0,0,0,0,0,0,0,0,0,0,0,0,0,0,0,0,0,0~
,0)';BIDI;
    'DDR3_DQ'<12>:'(0,0,0,0,0,DD85,0,0,0,0,0,0,0,0,0,0,0,0,0,0,0,0,0,0,0,0,0,0,0~
,0)';BIDI;
    'DDR3_DQ'<11>:'(0,0,0,0,0,DY83,0,0,0,0,0,0,0,0,0,0,0,0,0,0,0,0,0,0,0,0,0,0,0~
,0)';BIDI;
    'DDR3_DQ'<10>:'(0,0,0,0,0,DV83,0,0,0,0,0,0,0,0,0,0,0,0,0,0,0,0,0,0,0,0,0,0,0~
,0)';BIDI;
    'DDR3_DQ'<9>:'(0,0,0,0,0,DH85,0,0,0,0,0,0,0,0,0,0,0,0,0,0,0,0,0,0,0,0,0,0,0,~
0)';BIDI;
    'DDR3_DQ'<8>:'(0,0,0,0,0,DG84,0,0,0,0,0,0,0,0,0,0,0,0,0,0,0,0,0,0,0,0,0,0,0,~
0)';BIDI;
    'DDR3_DQ'<7>:'(0,0,0,0,0,CW84,0,0,0,0,0,0,0,0,0,0,0,0,0,0,0,0,0,0,0,0,0,0,0,~
0)';BIDI;
    'DDR3_DQ'<6>:'(0,0,0,0,0,CW86,0,0,0,0,0,0,0,0,0,0,0,0,0,0,0,0,0,0,0,0,0,0,0,~
0)';BIDI;
    'DDR3_DQ'<5>:'(0,0,0,0,0,CL86,0,0,0,0,0,0,0,0,0,0,0,0,0,0,0,0,0,0,0,0,0,0,0,~
0)';BIDI;
    'DDR3_DQ'<4>:'(0,0,0,0,0,CL84,0,0,0,0,0,0,0,0,0,0,0,0,0,0,0,0,0,0,0,0,0,0,0,~
0)';BIDI;
    'DDR3_DQ'<3>:'(0,0,0,0,0,DA84,0,0,0,0,0,0,0,0,0,0,0,0,0,0,0,0,0,0,0,0,0,0,0,~
0)';BIDI;
    'DDR3_DQ'<2>:'(0,0,0,0,0,DA86,0,0,0,0,0,0,0,0,0,0,0,0,0,0,0,0,0,0,0,0,0,0,0,~
0)';BIDI;
    'DDR3_DQ'<1>:'(0,0,0,0,0,CN86,0,0,0,0,0,0,0,0,0,0,0,0,0,0,0,0,0,0,0,0,0,0,0,~
0)';BIDI;
    'DDR3_DQ'<0>:'(0,0,0,0,0,CN84,0,0,0,0,0,0,0,0,0,0,0,0,0,0,0,0,0,0,0,0,0,0,0,~
0)';BIDI;
    'DDR3_DQS_DN'<17>:'(0,0,0,0,0,DB67,0,0,0,0,0,0,0,0,0,0,0,0,0,0,0,0,0,0,0,0,0~
,0,0,0)';BIDI;
    'DDR3_DQS_DN'<16>:'(0,0,0,0,0,DM23,0,0,0,0,0,0,0,0,0,0,0,0,0,0,0,0,0,0,0,0,0~
,0,0,0)';BIDI;
    'DDR3_DQS_DN'<15>:'(0,0,0,0,0,DM29,0,0,0,0,0,0,0,0,0,0,0,0,0,0,0,0,0,0,0,0,0~
,0,0,0)';BIDI;
    'DDR3_DQS_DN'<14>:'(0,0,0,0,0,DP35,0,0,0,0,0,0,0,0,0,0,0,0,0,0,0,0,0,0,0,0,0~
,0,0,0)';BIDI;
    'DDR3_DQS_DN'<13>:'(0,0,0,0,0,EA38,0,0,0,0,0,0,0,0,0,0,0,0,0,0,0,0,0,0,0,0,0~
,0,0,0)';BIDI;
    'DDR3_DQS_DN'<12>:'(0,0,0,0,0,DP75,0,0,0,0,0,0,0,0,0,0,0,0,0,0,0,0,0,0,0,0,0~
,0,0,0)';BIDI;
    'DDR3_DQS_DN'<11>:'(0,0,0,0,0,DN80,0,0,0,0,0,0,0,0,0,0,0,0,0,0,0,0,0,0,0,0,0~
,0,0,0)';BIDI;
    'DDR3_DQS_DN'<10>:'(0,0,0,0,0,DM85,0,0,0,0,0,0,0,0,0,0,0,0,0,0,0,0,0,0,0,0,0~
,0,0,0)';BIDI;
    'DDR3_DQS_DN'<9>:'(0,0,0,0,0,CR84,0,0,0,0,0,0,0,0,0,0,0,0,0,0,0,0,0,0,0,0,0,~
0,0,0)';BIDI;
    'DDR3_DQS_DN'<8>:'(0,0,0,0,0,DF67,0,0,0,0,0,0,0,0,0,0,0,0,0,0,0,0,0,0,0,0,0,~
0,0,0)';BIDI;
    'DDR3_DQS_DN'<7>:'(0,0,0,0,0,DV23,0,0,0,0,0,0,0,0,0,0,0,0,0,0,0,0,0,0,0,0,0,~
0,0,0)';BIDI;
    'DDR3_DQS_DN'<6>:'(0,0,0,0,0,DV29,0,0,0,0,0,0,0,0,0,0,0,0,0,0,0,0,0,0,0,0,0,~
0,0,0)';BIDI;
    'DDR3_DQS_DN'<5>:'(0,0,0,0,0,DV35,0,0,0,0,0,0,0,0,0,0,0,0,0,0,0,0,0,0,0,0,0,~
0,0,0)';BIDI;
    'DDR3_DQS_DN'<4>:'(0,0,0,0,0,EE38,0,0,0,0,0,0,0,0,0,0,0,0,0,0,0,0,0,0,0,0,0,~
0,0,0)';BIDI;
    'DDR3_DQS_DN'<3>:'(0,0,0,0,0,DV75,0,0,0,0,0,0,0,0,0,0,0,0,0,0,0,0,0,0,0,0,0,~
0,0,0)';BIDI;
    'DDR3_DQS_DN'<2>:'(0,0,0,0,0,DL82,0,0,0,0,0,0,0,0,0,0,0,0,0,0,0,0,0,0,0,0,0,~
0,0,0)';BIDI;
    'DDR3_DQS_DN'<1>:'(0,0,0,0,0,DN84,0,0,0,0,0,0,0,0,0,0,0,0,0,0,0,0,0,0,0,0,0,~
0,0,0)';BIDI;
    'DDR3_DQS_DN'<0>:'(0,0,0,0,0,CU84,0,0,0,0,0,0,0,0,0,0,0,0,0,0,0,0,0,0,0,0,0,~
0,0,0)';BIDI;
    'DDR3_DQS_DP'<17>:'(0,0,0,0,0,CY67,0,0,0,0,0,0,0,0,0,0,0,0,0,0,0,0,0,0,0,0,0~
,0,0,0)';BIDI;
    'DDR3_DQS_DP'<16>:'(0,0,0,0,0,DP23,0,0,0,0,0,0,0,0,0,0,0,0,0,0,0,0,0,0,0,0,0~
,0,0,0)';BIDI;
    'DDR3_DQS_DP'<15>:'(0,0,0,0,0,DP29,0,0,0,0,0,0,0,0,0,0,0,0,0,0,0,0,0,0,0,0,0~
,0,0,0)';BIDI;
    'DDR3_DQS_DP'<14>:'(0,0,0,0,0,DM35,0,0,0,0,0,0,0,0,0,0,0,0,0,0,0,0,0,0,0,0,0~
,0,0,0)';BIDI;
    'DDR3_DQS_DP'<13>:'(0,0,0,0,0,DW38,0,0,0,0,0,0,0,0,0,0,0,0,0,0,0,0,0,0,0,0,0~
,0,0,0)';BIDI;
    'DDR3_DQS_DP'<12>:'(0,0,0,0,0,DM75,0,0,0,0,0,0,0,0,0,0,0,0,0,0,0,0,0,0,0,0,0~
,0,0,0)';BIDI;
    'DDR3_DQS_DP'<11>:'(0,0,0,0,0,DP79,0,0,0,0,0,0,0,0,0,0,0,0,0,0,0,0,0,0,0,0,0~
,0,0,0)';BIDI;
    'DDR3_DQS_DP'<10>:'(0,0,0,0,0,DL84,0,0,0,0,0,0,0,0,0,0,0,0,0,0,0,0,0,0,0,0,0~
,0,0,0)';BIDI;
    'DDR3_DQS_DP'<9>:'(0,0,0,0,0,CP85,0,0,0,0,0,0,0,0,0,0,0,0,0,0,0,0,0,0,0,0,0,~
0,0,0)';BIDI;
    'DDR3_DQS_DP'<8>:'(0,0,0,0,0,DD67,0,0,0,0,0,0,0,0,0,0,0,0,0,0,0,0,0,0,0,0,0,~
0,0,0)';BIDI;
    'DDR3_DQS_DP'<7>:'(0,0,0,0,0,DT23,0,0,0,0,0,0,0,0,0,0,0,0,0,0,0,0,0,0,0,0,0,~
0,0,0)';BIDI;
    'DDR3_DQS_DP'<6>:'(0,0,0,0,0,DT29,0,0,0,0,0,0,0,0,0,0,0,0,0,0,0,0,0,0,0,0,0,~
0,0,0)';BIDI;
    'DDR3_DQS_DP'<5>:'(0,0,0,0,0,DT35,0,0,0,0,0,0,0,0,0,0,0,0,0,0,0,0,0,0,0,0,0,~
0,0,0)';BIDI;
    'DDR3_DQS_DP'<4>:'(0,0,0,0,0,EC38,0,0,0,0,0,0,0,0,0,0,0,0,0,0,0,0,0,0,0,0,0,~
0,0,0)';BIDI;
    'DDR3_DQS_DP'<3>:'(0,0,0,0,0,DT75,0,0,0,0,0,0,0,0,0,0,0,0,0,0,0,0,0,0,0,0,0,~
0,0,0)';BIDI;
    'DDR3_DQS_DP'<2>:'(0,0,0,0,0,DM81,0,0,0,0,0,0,0,0,0,0,0,0,0,0,0,0,0,0,0,0,0,~
0,0,0)';BIDI;
    'DDR3_DQS_DP'<1>:'(0,0,0,0,0,DP85,0,0,0,0,0,0,0,0,0,0,0,0,0,0,0,0,0,0,0,0,0,~
0,0,0)';BIDI;
    'DDR3_DQS_DP'<0>:'(0,0,0,0,0,CV85,0,0,0,0,0,0,0,0,0,0,0,0,0,0,0,0,0,0,0,0,0,~
0,0,0)';BIDI;
    'DDR3_ECC'<7>:'(0,0,0,0,0,DE66,0,0,0,0,0,0,0,0,0,0,0,0,0,0,0,0,0,0,0,0,0,0,0~
,0)';BIDI;
    'DDR3_ECC'<6>:'(0,0,0,0,0,DA66,0,0,0,0,0,0,0,0,0,0,0,0,0,0,0,0,0,0,0,0,0,0,0~
,0)';BIDI;
    'DDR3_ECC'<5>:'(0,0,0,0,0,DD69,0,0,0,0,0,0,0,0,0,0,0,0,0,0,0,0,0,0,0,0,0,0,0~
,0)';BIDI;
    'DDR3_ECC'<4>:'(0,0,0,0,0,DB69,0,0,0,0,0,0,0,0,0,0,0,0,0,0,0,0,0,0,0,0,0,0,0~
,0)';BIDI;
    'DDR3_ECC'<3>:'(0,0,0,0,0,DD65,0,0,0,0,0,0,0,0,0,0,0,0,0,0,0,0,0,0,0,0,0,0,0~
,0)';BIDI;
    'DDR3_ECC'<2>:'(0,0,0,0,0,DB65,0,0,0,0,0,0,0,0,0,0,0,0,0,0,0,0,0,0,0,0,0,0,0~
,0)';BIDI;
    'DDR3_ECC'<1>:'(0,0,0,0,0,DE68,0,0,0,0,0,0,0,0,0,0,0,0,0,0,0,0,0,0,0,0,0,0,0~
,0)';BIDI;
    'DDR3_ECC'<0>:'(0,0,0,0,0,DA68,0,0,0,0,0,0,0,0,0,0,0,0,0,0,0,0,0,0,0,0,0,0,0~
,0)';BIDI;
    'DDR3_MA'<17>:'(0,0,0,0,0,EA46,0,0,0,0,0,0,0,0,0,0,0,0,0,0,0,0,0,0,0,0,0,0,0~
,0)';OUT;
    'DDR3_MA'<16>:'(0,0,0,0,0,EA52,0,0,0,0,0,0,0,0,0,0,0,0,0,0,0,0,0,0,0,0,0,0,0~
,0)';OUT;
    'DDR3_MA'<15>:'(0,0,0,0,0,DV49,0,0,0,0,0,0,0,0,0,0,0,0,0,0,0,0,0,0,0,0,0,0,0~
,0)';OUT;
    'DDR3_MA'<14>:'(0,0,0,0,0,ED51,0,0,0,0,0,0,0,0,0,0,0,0,0,0,0,0,0,0,0,0,0,0,0~
,0)';OUT;
    'DDR3_MA'<13>:'(0,0,0,0,0,DW48,0,0,0,0,0,0,0,0,0,0,0,0,0,0,0,0,0,0,0,0,0,0,0~
,0)';OUT;
    'DDR3_MA'<12>:'(0,0,0,0,0,DT63,0,0,0,0,0,0,0,0,0,0,0,0,0,0,0,0,0,0,0,0,0,0,0~
,0)';OUT;
    'DDR3_MA'<11>:'(0,0,0,0,0,EB61,0,0,0,0,0,0,0,0,0,0,0,0,0,0,0,0,0,0,0,0,0,0,0~
,0)';OUT;
    'DDR3_MA'<10>:'(0,0,0,0,0,DW54,0,0,0,0,0,0,0,0,0,0,0,0,0,0,0,0,0,0,0,0,0,0,0~
,0)';OUT;
    'DDR3_MA'<9>:'(0,0,0,0,0,EF61,0,0,0,0,0,0,0,0,0,0,0,0,0,0,0,0,0,0,0,0,0,0,0,~
0)';OUT;
    'DDR3_MA'<8>:'(0,0,0,0,0,EB59,0,0,0,0,0,0,0,0,0,0,0,0,0,0,0,0,0,0,0,0,0,0,0,~
0)';OUT;
    'DDR3_MA'<7>:'(0,0,0,0,0,EA60,0,0,0,0,0,0,0,0,0,0,0,0,0,0,0,0,0,0,0,0,0,0,0,~
0)';OUT;
    'DDR3_MA'<6>:'(0,0,0,0,0,EE60,0,0,0,0,0,0,0,0,0,0,0,0,0,0,0,0,0,0,0,0,0,0,0,~
0)';OUT;
    'DDR3_MA'<5>:'(0,0,0,0,0,EA58,0,0,0,0,0,0,0,0,0,0,0,0,0,0,0,0,0,0,0,0,0,0,0,~
0)';OUT;
    'DDR3_MA'<4>:'(0,0,0,0,0,ED59,0,0,0,0,0,0,0,0,0,0,0,0,0,0,0,0,0,0,0,0,0,0,0,~
0)';OUT;
    'DDR3_MA'<3>:'(0,0,0,0,0,EB57,0,0,0,0,0,0,0,0,0,0,0,0,0,0,0,0,0,0,0,0,0,0,0,~
0)';OUT;
    'DDR3_MA'<2>:'(0,0,0,0,0,EE58,0,0,0,0,0,0,0,0,0,0,0,0,0,0,0,0,0,0,0,0,0,0,0,~
0)';OUT;
    'DDR3_MA'<1>:'(0,0,0,0,0,ED57,0,0,0,0,0,0,0,0,0,0,0,0,0,0,0,0,0,0,0,0,0,0,0,~
0)';OUT;
    'DDR3_MA'<0>:'(0,0,0,0,0,EB53,0,0,0,0,0,0,0,0,0,0,0,0,0,0,0,0,0,0,0,0,0,0,0,~
0)';OUT;
    'DDR3_ODT'<3>:'(0,0,0,0,0,EA48,0,0,0,0,0,0,0,0,0,0,0,0,0,0,0,0,0,0,0,0,0,0,0~
,0)';OUT;
    'DDR3_ODT'<2>:'(0,0,0,0,0,EA50,0,0,0,0,0,0,0,0,0,0,0,0,0,0,0,0,0,0,0,0,0,0,0~
,0)';OUT;
    'DDR3_ODT'<1>:'(0,0,0,0,0,EE48,0,0,0,0,0,0,0,0,0,0,0,0,0,0,0,0,0,0,0,0,0,0,0~
,0)';OUT;
    'DDR3_ODT'<0>:'(0,0,0,0,0,EE50,0,0,0,0,0,0,0,0,0,0,0,0,0,0,0,0,0,0,0,0,0,0,0~
,0)';OUT;
    'DDR3_PAR':'(0,0,0,0,0,ED53,0,0,0,0,0,0,0,0,0,0,0,0,0,0,0,0,0,0,0,0,0,0,0,0)~
';$S;OUT;
    'DDR4_ACT_N':'(0,0,0,0,0,0,DR62,0,0,0,0,0,0,0,0,0,0,0,0,0,0,0,0,0,0,0,0,0,0,~
0)';$S;OUT;
    'DDR4_ALERT_N':'(0,0,0,0,0,0,DT61,0,0,0,0,0,0,0,0,0,0,0,0,0,0,0,0,0,0,0,0,0,~
0,0)';$S;IN;
    'DDR4_BA'<1>:'(0,0,0,0,0,0,DV55,0,0,0,0,0,0,0,0,0,0,0,0,0,0,0,0,0,0,0,0,0,0,~
0)';OUT;
    'DDR4_BA'<0>:'(0,0,0,0,0,0,DM53,0,0,0,0,0,0,0,0,0,0,0,0,0,0,0,0,0,0,0,0,0,0,~
0)';OUT;
    'DDR4_BG'<1>:'(0,0,0,0,0,0,DM61,0,0,0,0,0,0,0,0,0,0,0,0,0,0,0,0,0,0,0,0,0,0,~
0)';OUT;
    'DDR4_BG'<0>:'(0,0,0,0,0,0,DJ62,0,0,0,0,0,0,0,0,0,0,0,0,0,0,0,0,0,0,0,0,0,0,~
0)';OUT;
    'DDR4_CAVREF':'(CT61,0,0,0,0,0,0,0,0,0,0,0,0,0,0,0,0,0,0,0,0,0,0,0,0,0,0,0,0~
,0)';$S;OUT;
    'DDR4_CID'<2>:'(0,0,0,0,0,0,DT47,0,0,0,0,0,0,0,0,0,0,0,0,0,0,0,0,0,0,0,0,0,0~
,0)';$S;OUT;
    'DDR4_CKE'<3>:'(0,0,0,0,0,0,DR64,0,0,0,0,0,0,0,0,0,0,0,0,0,0,0,0,0,0,0,0,0,0~
,0)';OUT;
    'DDR4_CKE'<2>:'(0,0,0,0,0,0,DL64,0,0,0,0,0,0,0,0,0,0,0,0,0,0,0,0,0,0,0,0,0,0~
,0)';OUT;
    'DDR4_CKE'<1>:'(0,0,0,0,0,0,DN64,0,0,0,0,0,0,0,0,0,0,0,0,0,0,0,0,0,0,0,0,0,0~
,0)';OUT;
    'DDR4_CKE'<0>:'(0,0,0,0,0,0,DM63,0,0,0,0,0,0,0,0,0,0,0,0,0,0,0,0,0,0,0,0,0,0~
,0)';OUT;
    'DDR4_CLK_DN'<3>:'(0,0,0,0,0,0,DT57,0,0,0,0,0,0,0,0,0,0,0,0,0,0,0,0,0,0,0,0,~
0,0,0)';OUT;
    'DDR4_CLK_DN'<2>:'(0,0,0,0,0,0,DM57,0,0,0,0,0,0,0,0,0,0,0,0,0,0,0,0,0,0,0,0,~
0,0,0)';OUT;
    'DDR4_CLK_DN'<1>:'(0,0,0,0,0,0,DR54,0,0,0,0,0,0,0,0,0,0,0,0,0,0,0,0,0,0,0,0,~
0,0,0)';OUT;
    'DDR4_CLK_DN'<0>:'(0,0,0,0,0,0,DM55,0,0,0,0,0,0,0,0,0,0,0,0,0,0,0,0,0,0,0,0,~
0,0,0)';OUT;
    'DDR4_CLK_DP'<3>:'(0,0,0,0,0,0,DR56,0,0,0,0,0,0,0,0,0,0,0,0,0,0,0,0,0,0,0,0,~
0,0,0)';OUT;
    'DDR4_CLK_DP'<2>:'(0,0,0,0,0,0,DN56,0,0,0,0,0,0,0,0,0,0,0,0,0,0,0,0,0,0,0,0,~
0,0,0)';OUT;
    'DDR4_CLK_DP'<1>:'(0,0,0,0,0,0,DT53,0,0,0,0,0,0,0,0,0,0,0,0,0,0,0,0,0,0,0,0,~
0,0,0)';OUT;
    'DDR4_CLK_DP'<0>:'(0,0,0,0,0,0,DN54,0,0,0,0,0,0,0,0,0,0,0,0,0,0,0,0,0,0,0,0,~
0,0,0)';OUT;
    'DDR4_CS_N'<7>:'(0,0,0,0,0,0,DN46,0,0,0,0,0,0,0,0,0,0,0,0,0,0,0,0,0,0,0,0,0,~
0,0)';OUT;
    'DDR4_CS_N'<6>:'(0,0,0,0,0,0,DT45,0,0,0,0,0,0,0,0,0,0,0,0,0,0,0,0,0,0,0,0,0,~
0,0)';OUT;
    'DDR4_CS_N'<5>:'(0,0,0,0,0,0,DM49,0,0,0,0,0,0,0,0,0,0,0,0,0,0,0,0,0,0,0,0,0,~
0,0)';OUT;
    'DDR4_CS_N'<4>:'(0,0,0,0,0,0,DW50,0,0,0,0,0,0,0,0,0,0,0,0,0,0,0,0,0,0,0,0,0,~
0,0)';OUT;
    'DDR4_CS_N'<3>:'(0,0,0,0,0,0,DK47,0,0,0,0,0,0,0,0,0,0,0,0,0,0,0,0,0,0,0,0,0,~
0,0)';OUT;
    'DDR4_CS_N'<2>:'(0,0,0,0,0,0,DR46,0,0,0,0,0,0,0,0,0,0,0,0,0,0,0,0,0,0,0,0,0,~
0,0)';OUT;
    'DDR4_CS_N'<1>:'(0,0,0,0,0,0,DN50,0,0,0,0,0,0,0,0,0,0,0,0,0,0,0,0,0,0,0,0,0,~
0,0)';OUT;
    'DDR4_CS_N'<0>:'(0,0,0,0,0,0,DV51,0,0,0,0,0,0,0,0,0,0,0,0,0,0,0,0,0,0,0,0,0,~
0,0)';OUT;
    'DDR4_DQ'<63>:'(0,0,0,0,0,0,DK25,0,0,0,0,0,0,0,0,0,0,0,0,0,0,0,0,0,0,0,0,0,0~
,0)';BIDI;
    'DDR4_DQ'<62>:'(0,0,0,0,0,0,DF25,0,0,0,0,0,0,0,0,0,0,0,0,0,0,0,0,0,0,0,0,0,0~
,0)';BIDI;
    'DDR4_DQ'<61>:'(0,0,0,0,0,0,DJ28,0,0,0,0,0,0,0,0,0,0,0,0,0,0,0,0,0,0,0,0,0,0~
,0)';BIDI;
    'DDR4_DQ'<60>:'(0,0,0,0,0,0,DG28,0,0,0,0,0,0,0,0,0,0,0,0,0,0,0,0,0,0,0,0,0,0~
,0)';BIDI;
    'DDR4_DQ'<59>:'(0,0,0,0,0,0,DJ24,0,0,0,0,0,0,0,0,0,0,0,0,0,0,0,0,0,0,0,0,0,0~
,0)';BIDI;
    'DDR4_DQ'<58>:'(0,0,0,0,0,0,DD25,0,0,0,0,0,0,0,0,0,0,0,0,0,0,0,0,0,0,0,0,0,0~
,0)';BIDI;
    'DDR4_DQ'<57>:'(0,0,0,0,0,0,DK27,0,0,0,0,0,0,0,0,0,0,0,0,0,0,0,0,0,0,0,0,0,0~
,0)';BIDI;
    'DDR4_DQ'<56>:'(0,0,0,0,0,0,DF27,0,0,0,0,0,0,0,0,0,0,0,0,0,0,0,0,0,0,0,0,0,0~
,0)';BIDI;
    'DDR4_DQ'<55>:'(0,0,0,0,0,0,ED25,0,0,0,0,0,0,0,0,0,0,0,0,0,0,0,0,0,0,0,0,0,0~
,0)';BIDI;
    'DDR4_DQ'<54>:'(0,0,0,0,0,0,DY25,0,0,0,0,0,0,0,0,0,0,0,0,0,0,0,0,0,0,0,0,0,0~
,0)';BIDI;
    'DDR4_DQ'<53>:'(0,0,0,0,0,0,EA28,0,0,0,0,0,0,0,0,0,0,0,0,0,0,0,0,0,0,0,0,0,0~
,0)';BIDI;
    'DDR4_DQ'<52>:'(0,0,0,0,0,0,DY27,0,0,0,0,0,0,0,0,0,0,0,0,0,0,0,0,0,0,0,0,0,0~
,0)';BIDI;
    'DDR4_DQ'<51>:'(0,0,0,0,0,0,EC24,0,0,0,0,0,0,0,0,0,0,0,0,0,0,0,0,0,0,0,0,0,0~
,0)';BIDI;
    'DDR4_DQ'<50>:'(0,0,0,0,0,0,EA24,0,0,0,0,0,0,0,0,0,0,0,0,0,0,0,0,0,0,0,0,0,0~
,0)';BIDI;
    'DDR4_DQ'<49>:'(0,0,0,0,0,0,ED27,0,0,0,0,0,0,0,0,0,0,0,0,0,0,0,0,0,0,0,0,0,0~
,0)';BIDI;
    'DDR4_DQ'<48>:'(0,0,0,0,0,0,EC28,0,0,0,0,0,0,0,0,0,0,0,0,0,0,0,0,0,0,0,0,0,0~
,0)';BIDI;
    'DDR4_DQ'<47>:'(0,0,0,0,0,0,ED31,0,0,0,0,0,0,0,0,0,0,0,0,0,0,0,0,0,0,0,0,0,0~
,0)';BIDI;
    'DDR4_DQ'<46>:'(0,0,0,0,0,0,DY31,0,0,0,0,0,0,0,0,0,0,0,0,0,0,0,0,0,0,0,0,0,0~
,0)';BIDI;
    'DDR4_DQ'<45>:'(0,0,0,0,0,0,EA34,0,0,0,0,0,0,0,0,0,0,0,0,0,0,0,0,0,0,0,0,0,0~
,0)';BIDI;
    'DDR4_DQ'<44>:'(0,0,0,0,0,0,DY33,0,0,0,0,0,0,0,0,0,0,0,0,0,0,0,0,0,0,0,0,0,0~
,0)';BIDI;
    'DDR4_DQ'<43>:'(0,0,0,0,0,0,EC30,0,0,0,0,0,0,0,0,0,0,0,0,0,0,0,0,0,0,0,0,0,0~
,0)';BIDI;
    'DDR4_DQ'<42>:'(0,0,0,0,0,0,EA30,0,0,0,0,0,0,0,0,0,0,0,0,0,0,0,0,0,0,0,0,0,0~
,0)';BIDI;
    'DDR4_DQ'<41>:'(0,0,0,0,0,0,ED33,0,0,0,0,0,0,0,0,0,0,0,0,0,0,0,0,0,0,0,0,0,0~
,0)';BIDI;
    'DDR4_DQ'<40>:'(0,0,0,0,0,0,EC34,0,0,0,0,0,0,0,0,0,0,0,0,0,0,0,0,0,0,0,0,0,0~
,0)';BIDI;
    'DDR4_DQ'<39>:'(0,0,0,0,0,0,DU40,0,0,0,0,0,0,0,0,0,0,0,0,0,0,0,0,0,0,0,0,0,0~
,0)';BIDI;
    'DDR4_DQ'<38>:'(0,0,0,0,0,0,DN40,0,0,0,0,0,0,0,0,0,0,0,0,0,0,0,0,0,0,0,0,0,0~
,0)';BIDI;
    'DDR4_DQ'<37>:'(0,0,0,0,0,0,DN42,0,0,0,0,0,0,0,0,0,0,0,0,0,0,0,0,0,0,0,0,0,0~
,0)';BIDI;
    'DDR4_DQ'<36>:'(0,0,0,0,0,0,DL42,0,0,0,0,0,0,0,0,0,0,0,0,0,0,0,0,0,0,0,0,0,0~
,0)';BIDI;
    'DDR4_DQ'<35>:'(0,0,0,0,0,0,DT39,0,0,0,0,0,0,0,0,0,0,0,0,0,0,0,0,0,0,0,0,0,0~
,0)';BIDI;
    'DDR4_DQ'<34>:'(0,0,0,0,0,0,DP39,0,0,0,0,0,0,0,0,0,0,0,0,0,0,0,0,0,0,0,0,0,0~
,0)';BIDI;
    'DDR4_DQ'<33>:'(0,0,0,0,0,0,DW42,0,0,0,0,0,0,0,0,0,0,0,0,0,0,0,0,0,0,0,0,0,0~
,0)';BIDI;
    'DDR4_DQ'<32>:'(0,0,0,0,0,0,DU42,0,0,0,0,0,0,0,0,0,0,0,0,0,0,0,0,0,0,0,0,0,0~
,0)';BIDI;
    'DDR4_DQ'<31>:'(0,0,0,0,0,0,EE72,0,0,0,0,0,0,0,0,0,0,0,0,0,0,0,0,0,0,0,0,0,0~
,0)';BIDI;
    'DDR4_DQ'<30>:'(0,0,0,0,0,0,EA72,0,0,0,0,0,0,0,0,0,0,0,0,0,0,0,0,0,0,0,0,0,0~
,0)';BIDI;
    'DDR4_DQ'<29>:'(0,0,0,0,0,0,EB75,0,0,0,0,0,0,0,0,0,0,0,0,0,0,0,0,0,0,0,0,0,0~
,0)';BIDI;
    'DDR4_DQ'<28>:'(0,0,0,0,0,0,EA74,0,0,0,0,0,0,0,0,0,0,0,0,0,0,0,0,0,0,0,0,0,0~
,0)';BIDI;
    'DDR4_DQ'<27>:'(0,0,0,0,0,0,ED71,0,0,0,0,0,0,0,0,0,0,0,0,0,0,0,0,0,0,0,0,0,0~
,0)';BIDI;
    'DDR4_DQ'<26>:'(0,0,0,0,0,0,EB71,0,0,0,0,0,0,0,0,0,0,0,0,0,0,0,0,0,0,0,0,0,0~
,0)';BIDI;
    'DDR4_DQ'<25>:'(0,0,0,0,0,0,EE74,0,0,0,0,0,0,0,0,0,0,0,0,0,0,0,0,0,0,0,0,0,0~
,0)';BIDI;
    'DDR4_DQ'<24>:'(0,0,0,0,0,0,ED75,0,0,0,0,0,0,0,0,0,0,0,0,0,0,0,0,0,0,0,0,0,0~
,0)';BIDI;
    'DDR4_DQ'<23>:'(0,0,0,0,0,0,EC78,0,0,0,0,0,0,0,0,0,0,0,0,0,0,0,0,0,0,0,0,0,0~
,0)';BIDI;
    'DDR4_DQ'<22>:'(0,0,0,0,0,0,DW78,0,0,0,0,0,0,0,0,0,0,0,0,0,0,0,0,0,0,0,0,0,0~
,0)';BIDI;
    'DDR4_DQ'<21>:'(0,0,0,0,0,0,EB81,0,0,0,0,0,0,0,0,0,0,0,0,0,0,0,0,0,0,0,0,0,0~
,0)';BIDI;
    'DDR4_DQ'<20>:'(0,0,0,0,0,0,DY81,0,0,0,0,0,0,0,0,0,0,0,0,0,0,0,0,0,0,0,0,0,0~
,0)';BIDI;
    'DDR4_DQ'<19>:'(0,0,0,0,0,0,EB77,0,0,0,0,0,0,0,0,0,0,0,0,0,0,0,0,0,0,0,0,0,0~
,0)';BIDI;
    'DDR4_DQ'<18>:'(0,0,0,0,0,0,DY77,0,0,0,0,0,0,0,0,0,0,0,0,0,0,0,0,0,0,0,0,0,0~
,0)';BIDI;
    'DDR4_DQ'<17>:'(0,0,0,0,0,0,EC80,0,0,0,0,0,0,0,0,0,0,0,0,0,0,0,0,0,0,0,0,0,0~
,0)';BIDI;
    'DDR4_DQ'<16>:'(0,0,0,0,0,0,DW80,0,0,0,0,0,0,0,0,0,0,0,0,0,0,0,0,0,0,0,0,0,0~
,0)';BIDI;
    'DDR4_DQ'<15>:'(0,0,0,0,0,0,DE82,0,0,0,0,0,0,0,0,0,0,0,0,0,0,0,0,0,0,0,0,0,0~
,0)';BIDI;
    'DDR4_DQ'<14>:'(0,0,0,0,0,0,DC82,0,0,0,0,0,0,0,0,0,0,0,0,0,0,0,0,0,0,0,0,0,0~
,0)';BIDI;
    'DDR4_DQ'<13>:'(0,0,0,0,0,0,CW80,0,0,0,0,0,0,0,0,0,0,0,0,0,0,0,0,0,0,0,0,0,0~
,0)';BIDI;
    'DDR4_DQ'<12>:'(0,0,0,0,0,0,CY79,0,0,0,0,0,0,0,0,0,0,0,0,0,0,0,0,0,0,0,0,0,0~
,0)';BIDI;
    'DDR4_DQ'<11>:'(0,0,0,0,0,0,DF81,0,0,0,0,0,0,0,0,0,0,0,0,0,0,0,0,0,0,0,0,0,0~
,0)';BIDI;
    'DDR4_DQ'<10>:'(0,0,0,0,0,0,DE80,0,0,0,0,0,0,0,0,0,0,0,0,0,0,0,0,0,0,0,0,0,0~
,0)';BIDI;
    'DDR4_DQ'<9>:'(0,0,0,0,0,0,CY81,0,0,0,0,0,0,0,0,0,0,0,0,0,0,0,0,0,0,0,0,0,0,~
0)';BIDI;
    'DDR4_DQ'<8>:'(0,0,0,0,0,0,DB79,0,0,0,0,0,0,0,0,0,0,0,0,0,0,0,0,0,0,0,0,0,0,~
0)';BIDI;
    'DDR4_DQ'<7>:'(0,0,0,0,0,0,CN82,0,0,0,0,0,0,0,0,0,0,0,0,0,0,0,0,0,0,0,0,0,0,~
0)';BIDI;
    'DDR4_DQ'<6>:'(0,0,0,0,0,0,CR80,0,0,0,0,0,0,0,0,0,0,0,0,0,0,0,0,0,0,0,0,0,0,~
0)';BIDI;
    'DDR4_DQ'<5>:'(0,0,0,0,0,0,CJ80,0,0,0,0,0,0,0,0,0,0,0,0,0,0,0,0,0,0,0,0,0,0,~
0)';BIDI;
    'DDR4_DQ'<4>:'(0,0,0,0,0,0,CK79,0,0,0,0,0,0,0,0,0,0,0,0,0,0,0,0,0,0,0,0,0,0,~
0)';BIDI;
    'DDR4_DQ'<3>:'(0,0,0,0,0,0,CR82,0,0,0,0,0,0,0,0,0,0,0,0,0,0,0,0,0,0,0,0,0,0,~
0)';BIDI;
    'DDR4_DQ'<2>:'(0,0,0,0,0,0,CT81,0,0,0,0,0,0,0,0,0,0,0,0,0,0,0,0,0,0,0,0,0,0,~
0)';BIDI;
    'DDR4_DQ'<1>:'(0,0,0,0,0,0,CK81,0,0,0,0,0,0,0,0,0,0,0,0,0,0,0,0,0,0,0,0,0,0,~
0)';BIDI;
    'DDR4_DQ'<0>:'(0,0,0,0,0,0,CM79,0,0,0,0,0,0,0,0,0,0,0,0,0,0,0,0,0,0,0,0,0,0,~
0)';BIDI;
    'DDR4_DQS_DN'<17>:'(0,0,0,0,0,0,DV67,0,0,0,0,0,0,0,0,0,0,0,0,0,0,0,0,0,0,0,0~
,0,0,0)';BIDI;
    'DDR4_DQS_DN'<16>:'(0,0,0,0,0,0,DG26,0,0,0,0,0,0,0,0,0,0,0,0,0,0,0,0,0,0,0,0~
,0,0,0)';BIDI;
    'DDR4_DQS_DN'<15>:'(0,0,0,0,0,0,EA26,0,0,0,0,0,0,0,0,0,0,0,0,0,0,0,0,0,0,0,0~
,0,0,0)';BIDI;
    'DDR4_DQS_DN'<14>:'(0,0,0,0,0,0,EA32,0,0,0,0,0,0,0,0,0,0,0,0,0,0,0,0,0,0,0,0~
,0,0,0)';BIDI;
    'DDR4_DQS_DN'<13>:'(0,0,0,0,0,0,DP41,0,0,0,0,0,0,0,0,0,0,0,0,0,0,0,0,0,0,0,0~
,0,0,0)';BIDI;
    'DDR4_DQS_DN'<12>:'(0,0,0,0,0,0,EB73,0,0,0,0,0,0,0,0,0,0,0,0,0,0,0,0,0,0,0,0~
,0,0,0)';BIDI;
    'DDR4_DQS_DN'<11>:'(0,0,0,0,0,0,DY79,0,0,0,0,0,0,0,0,0,0,0,0,0,0,0,0,0,0,0,0~
,0,0,0)';BIDI;
    'DDR4_DQS_DN'<10>:'(0,0,0,0,0,0,DC80,0,0,0,0,0,0,0,0,0,0,0,0,0,0,0,0,0,0,0,0~
,0,0,0)';BIDI;
    'DDR4_DQS_DN'<9>:'(0,0,0,0,0,0,CN80,0,0,0,0,0,0,0,0,0,0,0,0,0,0,0,0,0,0,0,0,~
0,0,0)';BIDI;
    'DDR4_DQS_DN'<8>:'(0,0,0,0,0,0,EB67,0,0,0,0,0,0,0,0,0,0,0,0,0,0,0,0,0,0,0,0,~
0,0,0)';BIDI;
    'DDR4_DQS_DN'<7>:'(0,0,0,0,0,0,DL26,0,0,0,0,0,0,0,0,0,0,0,0,0,0,0,0,0,0,0,0,~
0,0,0)';BIDI;
    'DDR4_DQS_DN'<6>:'(0,0,0,0,0,0,EE26,0,0,0,0,0,0,0,0,0,0,0,0,0,0,0,0,0,0,0,0,~
0,0,0)';BIDI;
    'DDR4_DQS_DN'<5>:'(0,0,0,0,0,0,EE32,0,0,0,0,0,0,0,0,0,0,0,0,0,0,0,0,0,0,0,0,~
0,0,0)';BIDI;
    'DDR4_DQS_DN'<4>:'(0,0,0,0,0,0,DV41,0,0,0,0,0,0,0,0,0,0,0,0,0,0,0,0,0,0,0,0,~
0,0,0)';BIDI;
    'DDR4_DQS_DN'<3>:'(0,0,0,0,0,0,EF73,0,0,0,0,0,0,0,0,0,0,0,0,0,0,0,0,0,0,0,0,~
0,0,0)';BIDI;
    'DDR4_DQS_DN'<2>:'(0,0,0,0,0,0,ED79,0,0,0,0,0,0,0,0,0,0,0,0,0,0,0,0,0,0,0,0,~
0,0,0)';BIDI;
    'DDR4_DQS_DN'<1>:'(0,0,0,0,0,0,DA82,0,0,0,0,0,0,0,0,0,0,0,0,0,0,0,0,0,0,0,0,~
0,0,0)';BIDI;
    'DDR4_DQS_DN'<0>:'(0,0,0,0,0,0,CL82,0,0,0,0,0,0,0,0,0,0,0,0,0,0,0,0,0,0,0,0,~
0,0,0)';BIDI;
    'DDR4_DQS_DP'<17>:'(0,0,0,0,0,0,DT67,0,0,0,0,0,0,0,0,0,0,0,0,0,0,0,0,0,0,0,0~
,0,0,0)';BIDI;
    'DDR4_DQS_DP'<16>:'(0,0,0,0,0,0,DE26,0,0,0,0,0,0,0,0,0,0,0,0,0,0,0,0,0,0,0,0~
,0,0,0)';BIDI;
    'DDR4_DQS_DP'<15>:'(0,0,0,0,0,0,DW26,0,0,0,0,0,0,0,0,0,0,0,0,0,0,0,0,0,0,0,0~
,0,0,0)';BIDI;
    'DDR4_DQS_DP'<14>:'(0,0,0,0,0,0,DW32,0,0,0,0,0,0,0,0,0,0,0,0,0,0,0,0,0,0,0,0~
,0,0,0)';BIDI;
    'DDR4_DQS_DP'<13>:'(0,0,0,0,0,0,DM41,0,0,0,0,0,0,0,0,0,0,0,0,0,0,0,0,0,0,0,0~
,0,0,0)';BIDI;
    'DDR4_DQS_DP'<12>:'(0,0,0,0,0,0,DY73,0,0,0,0,0,0,0,0,0,0,0,0,0,0,0,0,0,0,0,0~
,0,0,0)';BIDI;
    'DDR4_DQS_DP'<11>:'(0,0,0,0,0,0,DV79,0,0,0,0,0,0,0,0,0,0,0,0,0,0,0,0,0,0,0,0~
,0,0,0)';BIDI;
    'DDR4_DQS_DP'<10>:'(0,0,0,0,0,0,DD79,0,0,0,0,0,0,0,0,0,0,0,0,0,0,0,0,0,0,0,0~
,0,0,0)';BIDI;
    'DDR4_DQS_DP'<9>:'(0,0,0,0,0,0,CP79,0,0,0,0,0,0,0,0,0,0,0,0,0,0,0,0,0,0,0,0,~
0,0,0)';BIDI;
    'DDR4_DQS_DP'<8>:'(0,0,0,0,0,0,DY67,0,0,0,0,0,0,0,0,0,0,0,0,0,0,0,0,0,0,0,0,~
0,0,0)';BIDI;
    'DDR4_DQS_DP'<7>:'(0,0,0,0,0,0,DJ26,0,0,0,0,0,0,0,0,0,0,0,0,0,0,0,0,0,0,0,0,~
0,0,0)';BIDI;
    'DDR4_DQS_DP'<6>:'(0,0,0,0,0,0,EC26,0,0,0,0,0,0,0,0,0,0,0,0,0,0,0,0,0,0,0,0,~
0,0,0)';BIDI;
    'DDR4_DQS_DP'<5>:'(0,0,0,0,0,0,EC32,0,0,0,0,0,0,0,0,0,0,0,0,0,0,0,0,0,0,0,0,~
0,0,0)';BIDI;
    'DDR4_DQS_DP'<4>:'(0,0,0,0,0,0,DT41,0,0,0,0,0,0,0,0,0,0,0,0,0,0,0,0,0,0,0,0,~
0,0,0)';BIDI;
    'DDR4_DQS_DP'<3>:'(0,0,0,0,0,0,ED73,0,0,0,0,0,0,0,0,0,0,0,0,0,0,0,0,0,0,0,0,~
0,0,0)';BIDI;
    'DDR4_DQS_DP'<2>:'(0,0,0,0,0,0,EB79,0,0,0,0,0,0,0,0,0,0,0,0,0,0,0,0,0,0,0,0,~
0,0,0)';BIDI;
    'DDR4_DQS_DP'<1>:'(0,0,0,0,0,0,DB81,0,0,0,0,0,0,0,0,0,0,0,0,0,0,0,0,0,0,0,0,~
0,0,0)';BIDI;
    'DDR4_DQS_DP'<0>:'(0,0,0,0,0,0,CM81,0,0,0,0,0,0,0,0,0,0,0,0,0,0,0,0,0,0,0,0,~
0,0,0)';BIDI;
    'DDR4_ECC'<7>:'(0,0,0,0,0,0,EA66,0,0,0,0,0,0,0,0,0,0,0,0,0,0,0,0,0,0,0,0,0,0~
,0)';BIDI;
    'DDR4_ECC'<6>:'(0,0,0,0,0,0,DU66,0,0,0,0,0,0,0,0,0,0,0,0,0,0,0,0,0,0,0,0,0,0~
,0)';BIDI;
    'DDR4_ECC'<5>:'(0,0,0,0,0,0,DV69,0,0,0,0,0,0,0,0,0,0,0,0,0,0,0,0,0,0,0,0,0,0~
,0)';BIDI;
    'DDR4_ECC'<4>:'(0,0,0,0,0,0,DU68,0,0,0,0,0,0,0,0,0,0,0,0,0,0,0,0,0,0,0,0,0,0~
,0)';BIDI;
    'DDR4_ECC'<3>:'(0,0,0,0,0,0,DY65,0,0,0,0,0,0,0,0,0,0,0,0,0,0,0,0,0,0,0,0,0,0~
,0)';BIDI;
    'DDR4_ECC'<2>:'(0,0,0,0,0,0,DV65,0,0,0,0,0,0,0,0,0,0,0,0,0,0,0,0,0,0,0,0,0,0~
,0)';BIDI;
    'DDR4_ECC'<1>:'(0,0,0,0,0,0,EA68,0,0,0,0,0,0,0,0,0,0,0,0,0,0,0,0,0,0,0,0,0,0~
,0)';BIDI;
    'DDR4_ECC'<0>:'(0,0,0,0,0,0,DY69,0,0,0,0,0,0,0,0,0,0,0,0,0,0,0,0,0,0,0,0,0,0~
,0)';BIDI;
    'DDR4_MA'<17>:'(0,0,0,0,0,0,DR48,0,0,0,0,0,0,0,0,0,0,0,0,0,0,0,0,0,0,0,0,0,0~
,0)';OUT;
    'DDR4_MA'<16>:'(0,0,0,0,0,0,DN52,0,0,0,0,0,0,0,0,0,0,0,0,0,0,0,0,0,0,0,0,0,0~
,0)';OUT;
    'DDR4_MA'<15>:'(0,0,0,0,0,0,DR52,0,0,0,0,0,0,0,0,0,0,0,0,0,0,0,0,0,0,0,0,0,0~
,0)';OUT;
    'DDR4_MA'<14>:'(0,0,0,0,0,0,DM51,0,0,0,0,0,0,0,0,0,0,0,0,0,0,0,0,0,0,0,0,0,0~
,0)';OUT;
    'DDR4_MA'<13>:'(0,0,0,0,0,0,DT51,0,0,0,0,0,0,0,0,0,0,0,0,0,0,0,0,0,0,0,0,0,0~
,0)';OUT;
    'DDR4_MA'<12>:'(0,0,0,0,0,0,DN60,0,0,0,0,0,0,0,0,0,0,0,0,0,0,0,0,0,0,0,0,0,0~
,0)';OUT;
    'DDR4_MA'<11>:'(0,0,0,0,0,0,DR60,0,0,0,0,0,0,0,0,0,0,0,0,0,0,0,0,0,0,0,0,0,0~
,0)';OUT;
    'DDR4_MA'<10>:'(0,0,0,0,0,0,DT55,0,0,0,0,0,0,0,0,0,0,0,0,0,0,0,0,0,0,0,0,0,0~
,0)';OUT;
    'DDR4_MA'<9>:'(0,0,0,0,0,0,DV59,0,0,0,0,0,0,0,0,0,0,0,0,0,0,0,0,0,0,0,0,0,0,~
0)';OUT;
    'DDR4_MA'<8>:'(0,0,0,0,0,0,DJ60,0,0,0,0,0,0,0,0,0,0,0,0,0,0,0,0,0,0,0,0,0,0,~
0)';OUT;
    'DDR4_MA'<7>:'(0,0,0,0,0,0,DK61,0,0,0,0,0,0,0,0,0,0,0,0,0,0,0,0,0,0,0,0,0,0,~
0)';OUT;
    'DDR4_MA'<6>:'(0,0,0,0,0,0,DM59,0,0,0,0,0,0,0,0,0,0,0,0,0,0,0,0,0,0,0,0,0,0,~
0)';OUT;
    'DDR4_MA'<5>:'(0,0,0,0,0,0,DN58,0,0,0,0,0,0,0,0,0,0,0,0,0,0,0,0,0,0,0,0,0,0,~
0)';OUT;
    'DDR4_MA'<4>:'(0,0,0,0,0,0,DT59,0,0,0,0,0,0,0,0,0,0,0,0,0,0,0,0,0,0,0,0,0,0,~
0)';OUT;
    'DDR4_MA'<3>:'(0,0,0,0,0,0,DR58,0,0,0,0,0,0,0,0,0,0,0,0,0,0,0,0,0,0,0,0,0,0,~
0)';OUT;
    'DDR4_MA'<2>:'(0,0,0,0,0,0,DV57,0,0,0,0,0,0,0,0,0,0,0,0,0,0,0,0,0,0,0,0,0,0,~
0)';OUT;
    'DDR4_MA'<1>:'(0,0,0,0,0,0,DW58,0,0,0,0,0,0,0,0,0,0,0,0,0,0,0,0,0,0,0,0,0,0,~
0)';OUT;
    'DDR4_MA'<0>:'(0,0,0,0,0,0,DW52,0,0,0,0,0,0,0,0,0,0,0,0,0,0,0,0,0,0,0,0,0,0,~
0)';OUT;
    'DDR4_ODT'<3>:'(0,0,0,0,0,0,DM47,0,0,0,0,0,0,0,0,0,0,0,0,0,0,0,0,0,0,0,0,0,0~
,0)';OUT;
    'DDR4_ODT'<2>:'(0,0,0,0,0,0,DT49,0,0,0,0,0,0,0,0,0,0,0,0,0,0,0,0,0,0,0,0,0,0~
,0)';OUT;
    'DDR4_ODT'<1>:'(0,0,0,0,0,0,DN48,0,0,0,0,0,0,0,0,0,0,0,0,0,0,0,0,0,0,0,0,0,0~
,0)';OUT;
    'DDR4_ODT'<0>:'(0,0,0,0,0,0,DR50,0,0,0,0,0,0,0,0,0,0,0,0,0,0,0,0,0,0,0,0,0,0~
,0)';OUT;
    'DDR4_PAR':'(0,0,0,0,0,0,DV53,0,0,0,0,0,0,0,0,0,0,0,0,0,0,0,0,0,0,0,0,0,0,0)~
';$S;OUT;
    'DDR5_ACT_N':'(0,0,0,0,0,0,0,DC62,0,0,0,0,0,0,0,0,0,0,0,0,0,0,0,0,0,0,0,0,0,~
0)';$S;OUT;
    'DDR5_ALERT_N':'(0,0,0,0,0,0,0,DD61,0,0,0,0,0,0,0,0,0,0,0,0,0,0,0,0,0,0,0,0,~
0,0)';$S;IN;
    'DDR5_BA'<1>:'(0,0,0,0,0,0,0,DC56,0,0,0,0,0,0,0,0,0,0,0,0,0,0,0,0,0,0,0,0,0,~
0)';OUT;
    'DDR5_BA'<0>:'(0,0,0,0,0,0,0,DJ52,0,0,0,0,0,0,0,0,0,0,0,0,0,0,0,0,0,0,0,0,0,~
0)';OUT;
    'DDR5_BG'<1>:'(0,0,0,0,0,0,0,DF61,0,0,0,0,0,0,0,0,0,0,0,0,0,0,0,0,0,0,0,0,0,~
0)';OUT;
    'DDR5_BG'<0>:'(0,0,0,0,0,0,0,DA62,0,0,0,0,0,0,0,0,0,0,0,0,0,0,0,0,0,0,0,0,0,~
0)';OUT;
    'DDR5_CAVREF':'(CV61,0,0,0,0,0,0,0,0,0,0,0,0,0,0,0,0,0,0,0,0,0,0,0,0,0,0,0,0~
,0)';$S;OUT;
    'DDR5_CID'<2>:'(0,0,0,0,0,0,0,DF45,0,0,0,0,0,0,0,0,0,0,0,0,0,0,0,0,0,0,0,0,0~
,0)';$S;OUT;
    'DDR5_CKE'<3>:'(0,0,0,0,0,0,0,DF63,0,0,0,0,0,0,0,0,0,0,0,0,0,0,0,0,0,0,0,0,0~
,0)';OUT;
    'DDR5_CKE'<2>:'(0,0,0,0,0,0,0,DK63,0,0,0,0,0,0,0,0,0,0,0,0,0,0,0,0,0,0,0,0,0~
,0)';OUT;
    'DDR5_CKE'<1>:'(0,0,0,0,0,0,0,DD63,0,0,0,0,0,0,0,0,0,0,0,0,0,0,0,0,0,0,0,0,0~
,0)';OUT;
    'DDR5_CKE'<0>:'(0,0,0,0,0,0,0,DG62,0,0,0,0,0,0,0,0,0,0,0,0,0,0,0,0,0,0,0,0,0~
,0)';OUT;
    'DDR5_CLK_DN'<3>:'(0,0,0,0,0,0,0,DF57,0,0,0,0,0,0,0,0,0,0,0,0,0,0,0,0,0,0,0,~
0,0,0)';OUT;
    'DDR5_CLK_DN'<2>:'(0,0,0,0,0,0,0,DK57,0,0,0,0,0,0,0,0,0,0,0,0,0,0,0,0,0,0,0,~
0,0,0)';OUT;
    'DDR5_CLK_DN'<1>:'(0,0,0,0,0,0,0,DF55,0,0,0,0,0,0,0,0,0,0,0,0,0,0,0,0,0,0,0,~
0,0,0)';OUT;
    'DDR5_CLK_DN'<0>:'(0,0,0,0,0,0,0,DK55,0,0,0,0,0,0,0,0,0,0,0,0,0,0,0,0,0,0,0,~
0,0,0)';OUT;
    'DDR5_CLK_DP'<3>:'(0,0,0,0,0,0,0,DG56,0,0,0,0,0,0,0,0,0,0,0,0,0,0,0,0,0,0,0,~
0,0,0)';OUT;
    'DDR5_CLK_DP'<2>:'(0,0,0,0,0,0,0,DJ56,0,0,0,0,0,0,0,0,0,0,0,0,0,0,0,0,0,0,0,~
0,0,0)';OUT;
    'DDR5_CLK_DP'<1>:'(0,0,0,0,0,0,0,DG54,0,0,0,0,0,0,0,0,0,0,0,0,0,0,0,0,0,0,0,~
0,0,0)';OUT;
    'DDR5_CLK_DP'<0>:'(0,0,0,0,0,0,0,DJ54,0,0,0,0,0,0,0,0,0,0,0,0,0,0,0,0,0,0,0,~
0,0,0)';OUT;
    'DDR5_CS_N'<7>:'(0,0,0,0,0,0,0,DK45,0,0,0,0,0,0,0,0,0,0,0,0,0,0,0,0,0,0,0,0,~
0,0)';OUT;
    'DDR5_CS_N'<6>:'(0,0,0,0,0,0,0,DM45,0,0,0,0,0,0,0,0,0,0,0,0,0,0,0,0,0,0,0,0,~
0,0)';OUT;
    'DDR5_CS_N'<5>:'(0,0,0,0,0,0,0,DJ48,0,0,0,0,0,0,0,0,0,0,0,0,0,0,0,0,0,0,0,0,~
0,0)';OUT;
    'DDR5_CS_N'<4>:'(0,0,0,0,0,0,0,DF51,0,0,0,0,0,0,0,0,0,0,0,0,0,0,0,0,0,0,0,0,~
0,0)';OUT;
    'DDR5_CS_N'<3>:'(0,0,0,0,0,0,0,DG46,0,0,0,0,0,0,0,0,0,0,0,0,0,0,0,0,0,0,0,0,~
0,0)';OUT;
    'DDR5_CS_N'<2>:'(0,0,0,0,0,0,0,DJ46,0,0,0,0,0,0,0,0,0,0,0,0,0,0,0,0,0,0,0,0,~
0,0)';OUT;
    'DDR5_CS_N'<1>:'(0,0,0,0,0,0,0,DF49,0,0,0,0,0,0,0,0,0,0,0,0,0,0,0,0,0,0,0,0,~
0,0)';OUT;
    'DDR5_CS_N'<0>:'(0,0,0,0,0,0,0,DK51,0,0,0,0,0,0,0,0,0,0,0,0,0,0,0,0,0,0,0,0,~
0,0)';OUT;
    'DDR5_DQ'<63>:'(0,0,0,0,0,0,0,DC28,0,0,0,0,0,0,0,0,0,0,0,0,0,0,0,0,0,0,0,0,0~
,0)';BIDI;
    'DDR5_DQ'<62>:'(0,0,0,0,0,0,0,CW28,0,0,0,0,0,0,0,0,0,0,0,0,0,0,0,0,0,0,0,0,0~
,0)';BIDI;
    'DDR5_DQ'<61>:'(0,0,0,0,0,0,0,DB31,0,0,0,0,0,0,0,0,0,0,0,0,0,0,0,0,0,0,0,0,0~
,0)';BIDI;
    'DDR5_DQ'<60>:'(0,0,0,0,0,0,0,CY31,0,0,0,0,0,0,0,0,0,0,0,0,0,0,0,0,0,0,0,0,0~
,0)';BIDI;
    'DDR5_DQ'<59>:'(0,0,0,0,0,0,0,DB27,0,0,0,0,0,0,0,0,0,0,0,0,0,0,0,0,0,0,0,0,0~
,0)';BIDI;
    'DDR5_DQ'<58>:'(0,0,0,0,0,0,0,CY27,0,0,0,0,0,0,0,0,0,0,0,0,0,0,0,0,0,0,0,0,0~
,0)';BIDI;
    'DDR5_DQ'<57>:'(0,0,0,0,0,0,0,DC30,0,0,0,0,0,0,0,0,0,0,0,0,0,0,0,0,0,0,0,0,0~
,0)';BIDI;
    'DDR5_DQ'<56>:'(0,0,0,0,0,0,0,CW30,0,0,0,0,0,0,0,0,0,0,0,0,0,0,0,0,0,0,0,0,0~
,0)';BIDI;
    'DDR5_DQ'<55>:'(0,0,0,0,0,0,0,DC34,0,0,0,0,0,0,0,0,0,0,0,0,0,0,0,0,0,0,0,0,0~
,0)';BIDI;
    'DDR5_DQ'<54>:'(0,0,0,0,0,0,0,CW34,0,0,0,0,0,0,0,0,0,0,0,0,0,0,0,0,0,0,0,0,0~
,0)';BIDI;
    'DDR5_DQ'<53>:'(0,0,0,0,0,0,0,DB37,0,0,0,0,0,0,0,0,0,0,0,0,0,0,0,0,0,0,0,0,0~
,0)';BIDI;
    'DDR5_DQ'<52>:'(0,0,0,0,0,0,0,CY37,0,0,0,0,0,0,0,0,0,0,0,0,0,0,0,0,0,0,0,0,0~
,0)';BIDI;
    'DDR5_DQ'<51>:'(0,0,0,0,0,0,0,DB33,0,0,0,0,0,0,0,0,0,0,0,0,0,0,0,0,0,0,0,0,0~
,0)';BIDI;
    'DDR5_DQ'<50>:'(0,0,0,0,0,0,0,CY33,0,0,0,0,0,0,0,0,0,0,0,0,0,0,0,0,0,0,0,0,0~
,0)';BIDI;
    'DDR5_DQ'<49>:'(0,0,0,0,0,0,0,DC36,0,0,0,0,0,0,0,0,0,0,0,0,0,0,0,0,0,0,0,0,0~
,0)';BIDI;
    'DDR5_DQ'<48>:'(0,0,0,0,0,0,0,CW36,0,0,0,0,0,0,0,0,0,0,0,0,0,0,0,0,0,0,0,0,0~
,0)';BIDI;
    'DDR5_DQ'<47>:'(0,0,0,0,0,0,0,DK31,0,0,0,0,0,0,0,0,0,0,0,0,0,0,0,0,0,0,0,0,0~
,0)';BIDI;
    'DDR5_DQ'<46>:'(0,0,0,0,0,0,0,DF31,0,0,0,0,0,0,0,0,0,0,0,0,0,0,0,0,0,0,0,0,0~
,0)';BIDI;
    'DDR5_DQ'<45>:'(0,0,0,0,0,0,0,DJ34,0,0,0,0,0,0,0,0,0,0,0,0,0,0,0,0,0,0,0,0,0~
,0)';BIDI;
    'DDR5_DQ'<44>:'(0,0,0,0,0,0,0,DG34,0,0,0,0,0,0,0,0,0,0,0,0,0,0,0,0,0,0,0,0,0~
,0)';BIDI;
    'DDR5_DQ'<43>:'(0,0,0,0,0,0,0,DJ30,0,0,0,0,0,0,0,0,0,0,0,0,0,0,0,0,0,0,0,0,0~
,0)';BIDI;
    'DDR5_DQ'<42>:'(0,0,0,0,0,0,0,DG30,0,0,0,0,0,0,0,0,0,0,0,0,0,0,0,0,0,0,0,0,0~
,0)';BIDI;
    'DDR5_DQ'<41>:'(0,0,0,0,0,0,0,DK33,0,0,0,0,0,0,0,0,0,0,0,0,0,0,0,0,0,0,0,0,0~
,0)';BIDI;
    'DDR5_DQ'<40>:'(0,0,0,0,0,0,0,DF33,0,0,0,0,0,0,0,0,0,0,0,0,0,0,0,0,0,0,0,0,0~
,0)';BIDI;
    'DDR5_DQ'<39>:'(0,0,0,0,0,0,0,DH39,0,0,0,0,0,0,0,0,0,0,0,0,0,0,0,0,0,0,0,0,0~
,0)';BIDI;
    'DDR5_DQ'<38>:'(0,0,0,0,0,0,0,DD39,0,0,0,0,0,0,0,0,0,0,0,0,0,0,0,0,0,0,0,0,0~
,0)';BIDI;
    'DDR5_DQ'<37>:'(0,0,0,0,0,0,0,DE42,0,0,0,0,0,0,0,0,0,0,0,0,0,0,0,0,0,0,0,0,0~
,0)';BIDI;
    'DDR5_DQ'<36>:'(0,0,0,0,0,0,0,DA42,0,0,0,0,0,0,0,0,0,0,0,0,0,0,0,0,0,0,0,0,0~
,0)';BIDI;
    'DDR5_DQ'<35>:'(0,0,0,0,0,0,0,DG38,0,0,0,0,0,0,0,0,0,0,0,0,0,0,0,0,0,0,0,0,0~
,0)';BIDI;
    'DDR5_DQ'<34>:'(0,0,0,0,0,0,0,DE38,0,0,0,0,0,0,0,0,0,0,0,0,0,0,0,0,0,0,0,0,0~
,0)';BIDI;
    'DDR5_DQ'<33>:'(0,0,0,0,0,0,0,DG42,0,0,0,0,0,0,0,0,0,0,0,0,0,0,0,0,0,0,0,0,0~
,0)';BIDI;
    'DDR5_DQ'<32>:'(0,0,0,0,0,0,0,DD41,0,0,0,0,0,0,0,0,0,0,0,0,0,0,0,0,0,0,0,0,0~
,0)';BIDI;
    'DDR5_DQ'<31>:'(0,0,0,0,0,0,0,CU64,0,0,0,0,0,0,0,0,0,0,0,0,0,0,0,0,0,0,0,0,0~
,0)';BIDI;
    'DDR5_DQ'<30>:'(0,0,0,0,0,0,0,CN64,0,0,0,0,0,0,0,0,0,0,0,0,0,0,0,0,0,0,0,0,0~
,0)';BIDI;
    'DDR5_DQ'<29>:'(0,0,0,0,0,0,0,CT67,0,0,0,0,0,0,0,0,0,0,0,0,0,0,0,0,0,0,0,0,0~
,0)';BIDI;
    'DDR5_DQ'<28>:'(0,0,0,0,0,0,0,CP67,0,0,0,0,0,0,0,0,0,0,0,0,0,0,0,0,0,0,0,0,0~
,0)';BIDI;
    'DDR5_DQ'<27>:'(0,0,0,0,0,0,0,CT63,0,0,0,0,0,0,0,0,0,0,0,0,0,0,0,0,0,0,0,0,0~
,0)';BIDI;
    'DDR5_DQ'<26>:'(0,0,0,0,0,0,0,CP63,0,0,0,0,0,0,0,0,0,0,0,0,0,0,0,0,0,0,0,0,0~
,0)';BIDI;
    'DDR5_DQ'<25>:'(0,0,0,0,0,0,0,CU66,0,0,0,0,0,0,0,0,0,0,0,0,0,0,0,0,0,0,0,0,0~
,0)';BIDI;
    'DDR5_DQ'<24>:'(0,0,0,0,0,0,0,CN66,0,0,0,0,0,0,0,0,0,0,0,0,0,0,0,0,0,0,0,0,0~
,0)';BIDI;
    'DDR5_DQ'<23>:'(0,0,0,0,0,0,0,DM71,0,0,0,0,0,0,0,0,0,0,0,0,0,0,0,0,0,0,0,0,0~
,0)';BIDI;
    'DDR5_DQ'<22>:'(0,0,0,0,0,0,0,DK69,0,0,0,0,0,0,0,0,0,0,0,0,0,0,0,0,0,0,0,0,0~
,0)';BIDI;
    'DDR5_DQ'<21>:'(0,0,0,0,0,0,0,DG72,0,0,0,0,0,0,0,0,0,0,0,0,0,0,0,0,0,0,0,0,0~
,0)';BIDI;
    'DDR5_DQ'<20>:'(0,0,0,0,0,0,0,DF71,0,0,0,0,0,0,0,0,0,0,0,0,0,0,0,0,0,0,0,0,0~
,0)';BIDI;
    'DDR5_DQ'<19>:'(0,0,0,0,0,0,0,DN70,0,0,0,0,0,0,0,0,0,0,0,0,0,0,0,0,0,0,0,0,0~
,0)';BIDI;
    'DDR5_DQ'<18>:'(0,0,0,0,0,0,0,DM69,0,0,0,0,0,0,0,0,0,0,0,0,0,0,0,0,0,0,0,0,0~
,0)';BIDI;
    'DDR5_DQ'<17>:'(0,0,0,0,0,0,0,DJ72,0,0,0,0,0,0,0,0,0,0,0,0,0,0,0,0,0,0,0,0,0~
,0)';BIDI;
    'DDR5_DQ'<16>:'(0,0,0,0,0,0,0,DG70,0,0,0,0,0,0,0,0,0,0,0,0,0,0,0,0,0,0,0,0,0~
,0)';BIDI;
    'DDR5_DQ'<15>:'(0,0,0,0,0,0,0,DH77,0,0,0,0,0,0,0,0,0,0,0,0,0,0,0,0,0,0,0,0,0~
,0)';BIDI;
    'DDR5_DQ'<14>:'(0,0,0,0,0,0,0,DF77,0,0,0,0,0,0,0,0,0,0,0,0,0,0,0,0,0,0,0,0,0~
,0)';BIDI;
    'DDR5_DQ'<13>:'(0,0,0,0,0,0,0,DB75,0,0,0,0,0,0,0,0,0,0,0,0,0,0,0,0,0,0,0,0,0~
,0)';BIDI;
    'DDR5_DQ'<12>:'(0,0,0,0,0,0,0,DC74,0,0,0,0,0,0,0,0,0,0,0,0,0,0,0,0,0,0,0,0,0~
,0)';BIDI;
    'DDR5_DQ'<11>:'(0,0,0,0,0,0,0,DJ76,0,0,0,0,0,0,0,0,0,0,0,0,0,0,0,0,0,0,0,0,0~
,0)';BIDI;
    'DDR5_DQ'<10>:'(0,0,0,0,0,0,0,DH75,0,0,0,0,0,0,0,0,0,0,0,0,0,0,0,0,0,0,0,0,0~
,0)';BIDI;
    'DDR5_DQ'<9>:'(0,0,0,0,0,0,0,DC76,0,0,0,0,0,0,0,0,0,0,0,0,0,0,0,0,0,0,0,0,0,~
0)';BIDI;
    'DDR5_DQ'<8>:'(0,0,0,0,0,0,0,DE74,0,0,0,0,0,0,0,0,0,0,0,0,0,0,0,0,0,0,0,0,0,~
0)';BIDI;
    'DDR5_DQ'<7>:'(0,0,0,0,0,0,0,CT77,0,0,0,0,0,0,0,0,0,0,0,0,0,0,0,0,0,0,0,0,0,~
0)';BIDI;
    'DDR5_DQ'<6>:'(0,0,0,0,0,0,0,CV75,0,0,0,0,0,0,0,0,0,0,0,0,0,0,0,0,0,0,0,0,0,~
0)';BIDI;
    'DDR5_DQ'<5>:'(0,0,0,0,0,0,0,CM75,0,0,0,0,0,0,0,0,0,0,0,0,0,0,0,0,0,0,0,0,0,~
0)';BIDI;
    'DDR5_DQ'<4>:'(0,0,0,0,0,0,0,CN74,0,0,0,0,0,0,0,0,0,0,0,0,0,0,0,0,0,0,0,0,0,~
0)';BIDI;
    'DDR5_DQ'<3>:'(0,0,0,0,0,0,0,CV77,0,0,0,0,0,0,0,0,0,0,0,0,0,0,0,0,0,0,0,0,0,~
0)';BIDI;
    'DDR5_DQ'<2>:'(0,0,0,0,0,0,0,CW76,0,0,0,0,0,0,0,0,0,0,0,0,0,0,0,0,0,0,0,0,0,~
0)';BIDI;
    'DDR5_DQ'<1>:'(0,0,0,0,0,0,0,CN76,0,0,0,0,0,0,0,0,0,0,0,0,0,0,0,0,0,0,0,0,0,~
0)';BIDI;
    'DDR5_DQ'<0>:'(0,0,0,0,0,0,0,CR74,0,0,0,0,0,0,0,0,0,0,0,0,0,0,0,0,0,0,0,0,0,~
0)';BIDI;
    'DDR5_DQS_DN'<17>:'(0,0,0,0,0,0,0,CJ70,0,0,0,0,0,0,0,0,0,0,0,0,0,0,0,0,0,0,0~
,0,0,0)';BIDI;
    'DDR5_DQS_DN'<16>:'(0,0,0,0,0,0,0,CY29,0,0,0,0,0,0,0,0,0,0,0,0,0,0,0,0,0,0,0~
,0,0,0)';BIDI;
    'DDR5_DQS_DN'<15>:'(0,0,0,0,0,0,0,CY35,0,0,0,0,0,0,0,0,0,0,0,0,0,0,0,0,0,0,0~
,0,0,0)';BIDI;
    'DDR5_DQS_DN'<14>:'(0,0,0,0,0,0,0,DG32,0,0,0,0,0,0,0,0,0,0,0,0,0,0,0,0,0,0,0~
,0,0,0)';BIDI;
    'DDR5_DQS_DN'<13>:'(0,0,0,0,0,0,0,DE40,0,0,0,0,0,0,0,0,0,0,0,0,0,0,0,0,0,0,0~
,0,0,0)';BIDI;
    'DDR5_DQS_DN'<12>:'(0,0,0,0,0,0,0,CP65,0,0,0,0,0,0,0,0,0,0,0,0,0,0,0,0,0,0,0~
,0,0,0)';BIDI;
    'DDR5_DQS_DN'<11>:'(0,0,0,0,0,0,0,DJ70,0,0,0,0,0,0,0,0,0,0,0,0,0,0,0,0,0,0,0~
,0,0,0)';BIDI;
    'DDR5_DQS_DN'<10>:'(0,0,0,0,0,0,0,DF75,0,0,0,0,0,0,0,0,0,0,0,0,0,0,0,0,0,0,0~
,0,0,0)';BIDI;
    'DDR5_DQS_DN'<9>:'(0,0,0,0,0,0,0,CT75,0,0,0,0,0,0,0,0,0,0,0,0,0,0,0,0,0,0,0,~
0,0,0)';BIDI;
    'DDR5_DQS_DN'<8>:'(0,0,0,0,0,0,0,CN70,0,0,0,0,0,0,0,0,0,0,0,0,0,0,0,0,0,0,0,~
0,0,0)';BIDI;
    'DDR5_DQS_DN'<7>:'(0,0,0,0,0,0,0,DD29,0,0,0,0,0,0,0,0,0,0,0,0,0,0,0,0,0,0,0,~
0,0,0)';BIDI;
    'DDR5_DQS_DN'<6>:'(0,0,0,0,0,0,0,DD35,0,0,0,0,0,0,0,0,0,0,0,0,0,0,0,0,0,0,0,~
0,0,0)';BIDI;
    'DDR5_DQS_DN'<5>:'(0,0,0,0,0,0,0,DL32,0,0,0,0,0,0,0,0,0,0,0,0,0,0,0,0,0,0,0,~
0,0,0)';BIDI;
    'DDR5_DQS_DN'<4>:'(0,0,0,0,0,0,0,DG40,0,0,0,0,0,0,0,0,0,0,0,0,0,0,0,0,0,0,0,~
0,0,0)';BIDI;
    'DDR5_DQS_DN'<3>:'(0,0,0,0,0,0,0,CV65,0,0,0,0,0,0,0,0,0,0,0,0,0,0,0,0,0,0,0,~
0,0,0)';BIDI;
    'DDR5_DQS_DN'<2>:'(0,0,0,0,0,0,0,DL72,0,0,0,0,0,0,0,0,0,0,0,0,0,0,0,0,0,0,0,~
0,0,0)';BIDI;
    'DDR5_DQS_DN'<1>:'(0,0,0,0,0,0,0,DD77,0,0,0,0,0,0,0,0,0,0,0,0,0,0,0,0,0,0,0,~
0,0,0)';BIDI;
    'DDR5_DQS_DN'<0>:'(0,0,0,0,0,0,0,CP77,0,0,0,0,0,0,0,0,0,0,0,0,0,0,0,0,0,0,0,~
0,0,0)';BIDI;
    'DDR5_DQS_DP'<17>:'(0,0,0,0,0,0,0,CG70,0,0,0,0,0,0,0,0,0,0,0,0,0,0,0,0,0,0,0~
,0,0,0)';BIDI;
    'DDR5_DQS_DP'<16>:'(0,0,0,0,0,0,0,CV29,0,0,0,0,0,0,0,0,0,0,0,0,0,0,0,0,0,0,0~
,0,0,0)';BIDI;
    'DDR5_DQS_DP'<15>:'(0,0,0,0,0,0,0,CV35,0,0,0,0,0,0,0,0,0,0,0,0,0,0,0,0,0,0,0~
,0,0,0)';BIDI;
    'DDR5_DQS_DP'<14>:'(0,0,0,0,0,0,0,DE32,0,0,0,0,0,0,0,0,0,0,0,0,0,0,0,0,0,0,0~
,0,0,0)';BIDI;
    'DDR5_DQS_DP'<13>:'(0,0,0,0,0,0,0,DC40,0,0,0,0,0,0,0,0,0,0,0,0,0,0,0,0,0,0,0~
,0,0,0)';BIDI;
    'DDR5_DQS_DP'<12>:'(0,0,0,0,0,0,0,CM65,0,0,0,0,0,0,0,0,0,0,0,0,0,0,0,0,0,0,0~
,0,0,0)';BIDI;
    'DDR5_DQS_DP'<11>:'(0,0,0,0,0,0,0,DH69,0,0,0,0,0,0,0,0,0,0,0,0,0,0,0,0,0,0,0~
,0,0,0)';BIDI;
    'DDR5_DQS_DP'<10>:'(0,0,0,0,0,0,0,DG74,0,0,0,0,0,0,0,0,0,0,0,0,0,0,0,0,0,0,0~
,0,0,0)';BIDI;
    'DDR5_DQS_DP'<9>:'(0,0,0,0,0,0,0,CU74,0,0,0,0,0,0,0,0,0,0,0,0,0,0,0,0,0,0,0,~
0,0,0)';BIDI;
    'DDR5_DQS_DP'<8>:'(0,0,0,0,0,0,0,CL70,0,0,0,0,0,0,0,0,0,0,0,0,0,0,0,0,0,0,0,~
0,0,0)';BIDI;
    'DDR5_DQS_DP'<7>:'(0,0,0,0,0,0,0,DB29,0,0,0,0,0,0,0,0,0,0,0,0,0,0,0,0,0,0,0,~
0,0,0)';BIDI;
    'DDR5_DQS_DP'<6>:'(0,0,0,0,0,0,0,DB35,0,0,0,0,0,0,0,0,0,0,0,0,0,0,0,0,0,0,0,~
0,0,0)';BIDI;
    'DDR5_DQS_DP'<5>:'(0,0,0,0,0,0,0,DJ32,0,0,0,0,0,0,0,0,0,0,0,0,0,0,0,0,0,0,0,~
0,0,0)';BIDI;
    'DDR5_DQS_DP'<4>:'(0,0,0,0,0,0,0,DJ40,0,0,0,0,0,0,0,0,0,0,0,0,0,0,0,0,0,0,0,~
0,0,0)';BIDI;
    'DDR5_DQS_DP'<3>:'(0,0,0,0,0,0,0,CT65,0,0,0,0,0,0,0,0,0,0,0,0,0,0,0,0,0,0,0,~
0,0,0)';BIDI;
    'DDR5_DQS_DP'<2>:'(0,0,0,0,0,0,0,DK71,0,0,0,0,0,0,0,0,0,0,0,0,0,0,0,0,0,0,0,~
0,0,0)';BIDI;
    'DDR5_DQS_DP'<1>:'(0,0,0,0,0,0,0,DE76,0,0,0,0,0,0,0,0,0,0,0,0,0,0,0,0,0,0,0,~
0,0,0)';BIDI;
    'DDR5_DQS_DP'<0>:'(0,0,0,0,0,0,0,CR76,0,0,0,0,0,0,0,0,0,0,0,0,0,0,0,0,0,0,0,~
0,0,0)';BIDI;
    'DDR5_ECC'<7>:'(0,0,0,0,0,0,0,CM69,0,0,0,0,0,0,0,0,0,0,0,0,0,0,0,0,0,0,0,0,0~
,0)';BIDI;
    'DDR5_ECC'<6>:'(0,0,0,0,0,0,0,CH69,0,0,0,0,0,0,0,0,0,0,0,0,0,0,0,0,0,0,0,0,0~
,0)';BIDI;
    'DDR5_ECC'<5>:'(0,0,0,0,0,0,0,CL72,0,0,0,0,0,0,0,0,0,0,0,0,0,0,0,0,0,0,0,0,0~
,0)';BIDI;
    'DDR5_ECC'<4>:'(0,0,0,0,0,0,0,CJ72,0,0,0,0,0,0,0,0,0,0,0,0,0,0,0,0,0,0,0,0,0~
,0)';BIDI;
    'DDR5_ECC'<3>:'(0,0,0,0,0,0,0,CL68,0,0,0,0,0,0,0,0,0,0,0,0,0,0,0,0,0,0,0,0,0~
,0)';BIDI;
    'DDR5_ECC'<2>:'(0,0,0,0,0,0,0,CJ68,0,0,0,0,0,0,0,0,0,0,0,0,0,0,0,0,0,0,0,0,0~
,0)';BIDI;
    'DDR5_ECC'<1>:'(0,0,0,0,0,0,0,CM71,0,0,0,0,0,0,0,0,0,0,0,0,0,0,0,0,0,0,0,0,0~
,0)';BIDI;
    'DDR5_ECC'<0>:'(0,0,0,0,0,0,0,CH71,0,0,0,0,0,0,0,0,0,0,0,0,0,0,0,0,0,0,0,0,0~
,0)';BIDI;
    'DDR5_MA'<17>:'(0,0,0,0,0,0,0,DE46,0,0,0,0,0,0,0,0,0,0,0,0,0,0,0,0,0,0,0,0,0~
,0)';OUT;
    'DDR5_MA'<16>:'(0,0,0,0,0,0,0,DG52,0,0,0,0,0,0,0,0,0,0,0,0,0,0,0,0,0,0,0,0,0~
,0)';OUT;
    'DDR5_MA'<15>:'(0,0,0,0,0,0,0,DC54,0,0,0,0,0,0,0,0,0,0,0,0,0,0,0,0,0,0,0,0,0~
,0)';OUT;
    'DDR5_MA'<14>:'(0,0,0,0,0,0,0,DJ50,0,0,0,0,0,0,0,0,0,0,0,0,0,0,0,0,0,0,0,0,0~
,0)';OUT;
    'DDR5_MA'<13>:'(0,0,0,0,0,0,0,DD53,0,0,0,0,0,0,0,0,0,0,0,0,0,0,0,0,0,0,0,0,0~
,0)';OUT;
    'DDR5_MA'<12>:'(0,0,0,0,0,0,0,DG60,0,0,0,0,0,0,0,0,0,0,0,0,0,0,0,0,0,0,0,0,0~
,0)';OUT;
    'DDR5_MA'<11>:'(0,0,0,0,0,0,0,DA60,0,0,0,0,0,0,0,0,0,0,0,0,0,0,0,0,0,0,0,0,0~
,0)';OUT;
    'DDR5_MA'<10>:'(0,0,0,0,0,0,0,DD55,0,0,0,0,0,0,0,0,0,0,0,0,0,0,0,0,0,0,0,0,0~
,0)';OUT;
    'DDR5_MA'<9>:'(0,0,0,0,0,0,0,DA58,0,0,0,0,0,0,0,0,0,0,0,0,0,0,0,0,0,0,0,0,0,~
0)';OUT;
    'DDR5_MA'<8>:'(0,0,0,0,0,0,0,DD59,0,0,0,0,0,0,0,0,0,0,0,0,0,0,0,0,0,0,0,0,0,~
0)';OUT;
    'DDR5_MA'<7>:'(0,0,0,0,0,0,0,DC60,0,0,0,0,0,0,0,0,0,0,0,0,0,0,0,0,0,0,0,0,0,~
0)';OUT;
    'DDR5_MA'<6>:'(0,0,0,0,0,0,0,DK59,0,0,0,0,0,0,0,0,0,0,0,0,0,0,0,0,0,0,0,0,0,~
0)';OUT;
    'DDR5_MA'<5>:'(0,0,0,0,0,0,0,DF59,0,0,0,0,0,0,0,0,0,0,0,0,0,0,0,0,0,0,0,0,0,~
0)';OUT;
    'DDR5_MA'<4>:'(0,0,0,0,0,0,0,DJ58,0,0,0,0,0,0,0,0,0,0,0,0,0,0,0,0,0,0,0,0,0,~
0)';OUT;
    'DDR5_MA'<3>:'(0,0,0,0,0,0,0,DG58,0,0,0,0,0,0,0,0,0,0,0,0,0,0,0,0,0,0,0,0,0,~
0)';OUT;
    'DDR5_MA'<2>:'(0,0,0,0,0,0,0,DD57,0,0,0,0,0,0,0,0,0,0,0,0,0,0,0,0,0,0,0,0,0,~
0)';OUT;
    'DDR5_MA'<1>:'(0,0,0,0,0,0,0,DC58,0,0,0,0,0,0,0,0,0,0,0,0,0,0,0,0,0,0,0,0,0,~
0)';OUT;
    'DDR5_MA'<0>:'(0,0,0,0,0,0,0,DF53,0,0,0,0,0,0,0,0,0,0,0,0,0,0,0,0,0,0,0,0,0,~
0)';OUT;
    'DDR5_ODT'<3>:'(0,0,0,0,0,0,0,DF47,0,0,0,0,0,0,0,0,0,0,0,0,0,0,0,0,0,0,0,0,0~
,0)';OUT;
    'DDR5_ODT'<2>:'(0,0,0,0,0,0,0,DK49,0,0,0,0,0,0,0,0,0,0,0,0,0,0,0,0,0,0,0,0,0~
,0)';OUT;
    'DDR5_ODT'<1>:'(0,0,0,0,0,0,0,DG48,0,0,0,0,0,0,0,0,0,0,0,0,0,0,0,0,0,0,0,0,0~
,0)';OUT;
    'DDR5_ODT'<0>:'(0,0,0,0,0,0,0,DG50,0,0,0,0,0,0,0,0,0,0,0,0,0,0,0,0,0,0,0,0,0~
,0)';OUT;
    'DDR5_PAR':'(0,0,0,0,0,0,0,DK53,0,0,0,0,0,0,0,0,0,0,0,0,0,0,0,0,0,0,0,0,0,0)~
';$S;OUT;
    'DEBUG_EN_N':'(0,AV21,0,0,0,0,0,0,0,0,0,0,0,0,0,0,0,0,0,0,0,0,0,0,0,0,0,0,0,~
0)';$S;BIDI;
    'DMIMODE_OVERRIDE':'(0,AW12,0,0,0,0,0,0,0,0,0,0,0,0,0,0,0,0,0,0,0,0,0,0,0,0,~
0,0,0,0)';$S;BIDI;
    'DMI_RX_DN'<3>:'(0,0,0,0,0,0,0,0,CT11,0,0,0,0,0,0,0,0,0,0,0,0,0,0,0,0,0,0,0,~
0,0)';IN;
    'DMI_RX_DN'<2>:'(0,0,0,0,0,0,0,0,CR12,0,0,0,0,0,0,0,0,0,0,0,0,0,0,0,0,0,0,0,~
0,0)';IN;
    'DMI_RX_DN'<1>:'(0,0,0,0,0,0,0,0,CM11,0,0,0,0,0,0,0,0,0,0,0,0,0,0,0,0,0,0,0,~
0,0)';IN;
    'DMI_RX_DN'<0>:'(0,0,0,0,0,0,0,0,CK9,0,0,0,0,0,0,0,0,0,0,0,0,0,0,0,0,0,0,0,0~
,0)';IN;
    'DMI_RX_DP'<3>:'(0,0,0,0,0,0,0,0,CV11,0,0,0,0,0,0,0,0,0,0,0,0,0,0,0,0,0,0,0,~
0,0)';IN;
    'DMI_RX_DP'<2>:'(0,0,0,0,0,0,0,0,CP11,0,0,0,0,0,0,0,0,0,0,0,0,0,0,0,0,0,0,0,~
0,0)';IN;
    'DMI_RX_DP'<1>:'(0,0,0,0,0,0,0,0,CN10,0,0,0,0,0,0,0,0,0,0,0,0,0,0,0,0,0,0,0,~
0,0)';IN;
    'DMI_RX_DP'<0>:'(0,0,0,0,0,0,0,0,CL10,0,0,0,0,0,0,0,0,0,0,0,0,0,0,0,0,0,0,0,~
0,0)';IN;
    'DMI_TX_DN'<3>:'(0,0,0,0,0,0,0,0,CP5,0,0,0,0,0,0,0,0,0,0,0,0,0,0,0,0,0,0,0,0~
,0)';OUT;
    'DMI_TX_DN'<2>:'(0,0,0,0,0,0,0,0,CN4,0,0,0,0,0,0,0,0,0,0,0,0,0,0,0,0,0,0,0,0~
,0)';OUT;
    'DMI_TX_DN'<1>:'(0,0,0,0,0,0,0,0,CJ4,0,0,0,0,0,0,0,0,0,0,0,0,0,0,0,0,0,0,0,0~
,0)';OUT;
    'DMI_TX_DN'<0>:'(0,0,0,0,0,0,0,0,CG4,0,0,0,0,0,0,0,0,0,0,0,0,0,0,0,0,0,0,0,0~
,0)';OUT;
    'DMI_TX_DP'<3>:'(0,0,0,0,0,0,0,0,CR4,0,0,0,0,0,0,0,0,0,0,0,0,0,0,0,0,0,0,0,0~
,0)';OUT;
    'DMI_TX_DP'<2>:'(0,0,0,0,0,0,0,0,CM3,0,0,0,0,0,0,0,0,0,0,0,0,0,0,0,0,0,0,0,0~
,0)';OUT;
    'DMI_TX_DP'<1>:'(0,0,0,0,0,0,0,0,CL4,0,0,0,0,0,0,0,0,0,0,0,0,0,0,0,0,0,0,0,0~
,0)';OUT;
    'DMI_TX_DP'<0>:'(0,0,0,0,0,0,0,0,CH5,0,0,0,0,0,0,0,0,0,0,0,0,0,0,0,0,0,0,0,0~
,0)';OUT;
    'EAR_N':'(AJ14,0,0,0,0,0,0,0,0,0,0,0,0,0,0,0,0,0,0,0,0,0,0,0,0,0,0,0,0,0)';$~
S;IN;
    'ERROR_N'<2>:'(AL12,0,0,0,0,0,0,0,0,0,0,0,0,0,0,0,0,0,0,0,0,0,0,0,0,0,0,0,0,~
0)';OUT;
    'ERROR_N'<1>:'(AK11,0,0,0,0,0,0,0,0,0,0,0,0,0,0,0,0,0,0,0,0,0,0,0,0,0,0,0,0,~
0)';OUT;
    'ERROR_N'<0>:'(AJ12,0,0,0,0,0,0,0,0,0,0,0,0,0,0,0,0,0,0,0,0,0,0,0,0,0,0,0,0,~
0)';OUT;
    'FIVR_FAULT':'(0,AU14,0,0,0,0,0,0,0,0,0,0,0,0,0,0,0,0,0,0,0,0,0,0,0,0,0,0,0,~
0)';$S;OUT;
    'FRMAGENT':'(AV17,0,0,0,0,0,0,0,0,0,0,0,0,0,0,0,0,0,0,0,0,0,0,0,0,0,0,0,0,0)~
';$S;IN;
    'LEGACY_SKT':'(AE20,0,0,0,0,0,0,0,0,0,0,0,0,0,0,0,0,0,0,0,0,0,0,0,0,0,0,0,0,~
0)';$S;IN;
    'MCP01_RBIAS'<1>:'(CT31,0,0,0,0,0,0,0,0,0,0,0,0,0,0,0,0,0,0,0,0,0,0,0,0,0,0,~
0,0,0)';BIDI;
    'MCP01_RBIAS'<0>:'(CU32,0,0,0,0,0,0,0,0,0,0,0,0,0,0,0,0,0,0,0,0,0,0,0,0,0,0,~
0,0,0)';BIDI;
    'MEM_HOT_C012_N':'(AH13,0,0,0,0,0,0,0,0,0,0,0,0,0,0,0,0,0,0,0,0,0,0,0,0,0,0,~
0,0,0)';$S;BIDI;
    'MEM_HOT_C345_N':'(AF13,0,0,0,0,0,0,0,0,0,0,0,0,0,0,0,0,0,0,0,0,0,0,0,0,0,0,~
0,0,0)';$S;BIDI;
    'MSMI_N':'(AN20,0,0,0,0,0,0,0,0,0,0,0,0,0,0,0,0,0,0,0,0,0,0,0,0,0,0,0,0,0)';~
$S;BIDI;
    'NMI':'(AP11,0,0,0,0,0,0,0,0,0,0,0,0,0,0,0,0,0,0,0,0,0,0,0,0,0,0,0,0,0)';$S;~
IN;
    'PE012_RBIAS'<1>:'(CL30,0,0,0,0,0,0,0,0,0,0,0,0,0,0,0,0,0,0,0,0,0,0,0,0,0,0,~
0,0,0)';BIDI;
    'PE012_RBIAS'<0>:'(CN30,0,0,0,0,0,0,0,0,0,0,0,0,0,0,0,0,0,0,0,0,0,0,0,0,0,0,~
0,0,0)';BIDI;
    'PE1_RX_DN'<15>:'(0,0,0,0,0,0,0,0,0,DU16,0,0,0,0,0,0,0,0,0,0,0,0,0,0,0,0,0,0~
,0,0)';IN;
    'PE1_RX_DN'<14>:'(0,0,0,0,0,0,0,0,0,DY15,0,0,0,0,0,0,0,0,0,0,0,0,0,0,0,0,0,0~
,0,0)';IN;
    'PE1_RX_DN'<13>:'(0,0,0,0,0,0,0,0,0,DW14,0,0,0,0,0,0,0,0,0,0,0,0,0,0,0,0,0,0~
,0,0)';IN;
    'PE1_RX_DN'<12>:'(0,0,0,0,0,0,0,0,0,DV13,0,0,0,0,0,0,0,0,0,0,0,0,0,0,0,0,0,0~
,0,0)';IN;
    'PE1_RX_DN'<11>:'(0,0,0,0,0,0,0,0,0,DT13,0,0,0,0,0,0,0,0,0,0,0,0,0,0,0,0,0,0~
,0,0)';IN;
    'PE1_RX_DN'<10>:'(0,0,0,0,0,0,0,0,0,DT11,0,0,0,0,0,0,0,0,0,0,0,0,0,0,0,0,0,0~
,0,0)';IN;
    'PE1_RX_DN'<9>:'(0,0,0,0,0,0,0,0,0,DP11,0,0,0,0,0,0,0,0,0,0,0,0,0,0,0,0,0,0,~
0,0)';IN;
    'PE1_RX_DN'<8>:'(0,0,0,0,0,0,0,0,0,DM11,0,0,0,0,0,0,0,0,0,0,0,0,0,0,0,0,0,0,~
0,0)';IN;
    'PE1_RX_DN'<7>:'(0,0,0,0,0,0,0,0,0,DM9,0,0,0,0,0,0,0,0,0,0,0,0,0,0,0,0,0,0,0~
,0)';IN;
    'PE1_RX_DN'<6>:'(0,0,0,0,0,0,0,0,0,DK9,0,0,0,0,0,0,0,0,0,0,0,0,0,0,0,0,0,0,0~
,0)';IN;
    'PE1_RX_DN'<5>:'(0,0,0,0,0,0,0,0,0,DH9,0,0,0,0,0,0,0,0,0,0,0,0,0,0,0,0,0,0,0~
,0)';IN;
    'PE1_RX_DN'<4>:'(0,0,0,0,0,0,0,0,0,DE10,0,0,0,0,0,0,0,0,0,0,0,0,0,0,0,0,0,0,~
0,0)';IN;
    'PE1_RX_DN'<3>:'(0,0,0,0,0,0,0,0,0,DC10,0,0,0,0,0,0,0,0,0,0,0,0,0,0,0,0,0,0,~
0,0)';IN;
    'PE1_RX_DN'<2>:'(0,0,0,0,0,0,0,0,0,DC8,0,0,0,0,0,0,0,0,0,0,0,0,0,0,0,0,0,0,0~
,0)';IN;
    'PE1_RX_DN'<1>:'(0,0,0,0,0,0,0,0,0,DA8,0,0,0,0,0,0,0,0,0,0,0,0,0,0,0,0,0,0,0~
,0)';IN;
    'PE1_RX_DN'<0>:'(0,0,0,0,0,0,0,0,0,CW8,0,0,0,0,0,0,0,0,0,0,0,0,0,0,0,0,0,0,0~
,0)';IN;
    'PE1_RX_DP'<15>:'(0,0,0,0,0,0,0,0,0,DT15,0,0,0,0,0,0,0,0,0,0,0,0,0,0,0,0,0,0~
,0,0)';IN;
    'PE1_RX_DP'<14>:'(0,0,0,0,0,0,0,0,0,DV15,0,0,0,0,0,0,0,0,0,0,0,0,0,0,0,0,0,0~
,0,0)';IN;
    'PE1_RX_DP'<13>:'(0,0,0,0,0,0,0,0,0,DY13,0,0,0,0,0,0,0,0,0,0,0,0,0,0,0,0,0,0~
,0,0)';IN;
    'PE1_RX_DP'<12>:'(0,0,0,0,0,0,0,0,0,DU12,0,0,0,0,0,0,0,0,0,0,0,0,0,0,0,0,0,0~
,0,0)';IN;
    'PE1_RX_DP'<11>:'(0,0,0,0,0,0,0,0,0,DP13,0,0,0,0,0,0,0,0,0,0,0,0,0,0,0,0,0,0~
,0,0)';IN;
    'PE1_RX_DP'<10>:'(0,0,0,0,0,0,0,0,0,DR12,0,0,0,0,0,0,0,0,0,0,0,0,0,0,0,0,0,0~
,0,0)';IN;
    'PE1_RX_DP'<9>:'(0,0,0,0,0,0,0,0,0,DN10,0,0,0,0,0,0,0,0,0,0,0,0,0,0,0,0,0,0,~
0,0)';IN;
    'PE1_RX_DP'<8>:'(0,0,0,0,0,0,0,0,0,DK11,0,0,0,0,0,0,0,0,0,0,0,0,0,0,0,0,0,0,~
0,0)';IN;
    'PE1_RX_DP'<7>:'(0,0,0,0,0,0,0,0,0,DL10,0,0,0,0,0,0,0,0,0,0,0,0,0,0,0,0,0,0,~
0,0)';IN;
    'PE1_RX_DP'<6>:'(0,0,0,0,0,0,0,0,0,DJ8,0,0,0,0,0,0,0,0,0,0,0,0,0,0,0,0,0,0,0~
,0)';IN;
    'PE1_RX_DP'<5>:'(0,0,0,0,0,0,0,0,0,DF9,0,0,0,0,0,0,0,0,0,0,0,0,0,0,0,0,0,0,0~
,0)';IN;
    'PE1_RX_DP'<4>:'(0,0,0,0,0,0,0,0,0,DD9,0,0,0,0,0,0,0,0,0,0,0,0,0,0,0,0,0,0,0~
,0)';IN;
    'PE1_RX_DP'<3>:'(0,0,0,0,0,0,0,0,0,DA10,0,0,0,0,0,0,0,0,0,0,0,0,0,0,0,0,0,0,~
0,0)';IN;
    'PE1_RX_DP'<2>:'(0,0,0,0,0,0,0,0,0,DB9,0,0,0,0,0,0,0,0,0,0,0,0,0,0,0,0,0,0,0~
,0)';IN;
    'PE1_RX_DP'<1>:'(0,0,0,0,0,0,0,0,0,CY7,0,0,0,0,0,0,0,0,0,0,0,0,0,0,0,0,0,0,0~
,0)';IN;
    'PE1_RX_DP'<0>:'(0,0,0,0,0,0,0,0,0,CU8,0,0,0,0,0,0,0,0,0,0,0,0,0,0,0,0,0,0,0~
,0)';IN;
    'PE1_TX_DN'<15>:'(0,0,0,0,0,0,0,0,0,ED9,0,0,0,0,0,0,0,0,0,0,0,0,0,0,0,0,0,0,~
0,0)';OUT;
    'PE1_TX_DN'<14>:'(0,0,0,0,0,0,0,0,0,EA8,0,0,0,0,0,0,0,0,0,0,0,0,0,0,0,0,0,0,~
0,0)';OUT;
    'PE1_TX_DN'<13>:'(0,0,0,0,0,0,0,0,0,DY7,0,0,0,0,0,0,0,0,0,0,0,0,0,0,0,0,0,0,~
0,0)';OUT;
    'PE1_TX_DN'<12>:'(0,0,0,0,0,0,0,0,0,DV7,0,0,0,0,0,0,0,0,0,0,0,0,0,0,0,0,0,0,~
0,0)';OUT;
    'PE1_TX_DN'<11>:'(0,0,0,0,0,0,0,0,0,DU6,0,0,0,0,0,0,0,0,0,0,0,0,0,0,0,0,0,0,~
0,0)';OUT;
    'PE1_TX_DN'<10>:'(0,0,0,0,0,0,0,0,0,DW4,0,0,0,0,0,0,0,0,0,0,0,0,0,0,0,0,0,0,~
0,0)';OUT;
    'PE1_TX_DN'<9>:'(0,0,0,0,0,0,0,0,0,DV3,0,0,0,0,0,0,0,0,0,0,0,0,0,0,0,0,0,0,0~
,0)';OUT;
    'PE1_TX_DN'<8>:'(0,0,0,0,0,0,0,0,0,DT5,0,0,0,0,0,0,0,0,0,0,0,0,0,0,0,0,0,0,0~
,0)';OUT;
    'PE1_TX_DN'<7>:'(0,0,0,0,0,0,0,0,0,DN4,0,0,0,0,0,0,0,0,0,0,0,0,0,0,0,0,0,0,0~
,0)';OUT;
    'PE1_TX_DN'<6>:'(0,0,0,0,0,0,0,0,0,DM3,0,0,0,0,0,0,0,0,0,0,0,0,0,0,0,0,0,0,0~
,0)';OUT;
    'PE1_TX_DN'<5>:'(0,0,0,0,0,0,0,0,0,DK3,0,0,0,0,0,0,0,0,0,0,0,0,0,0,0,0,0,0,0~
,0)';OUT;
    'PE1_TX_DN'<4>:'(0,0,0,0,0,0,0,0,0,DG4,0,0,0,0,0,0,0,0,0,0,0,0,0,0,0,0,0,0,0~
,0)';OUT;
    'PE1_TX_DN'<3>:'(0,0,0,0,0,0,0,0,0,DE4,0,0,0,0,0,0,0,0,0,0,0,0,0,0,0,0,0,0,0~
,0)';OUT;
    'PE1_TX_DN'<2>:'(0,0,0,0,0,0,0,0,0,DE2,0,0,0,0,0,0,0,0,0,0,0,0,0,0,0,0,0,0,0~
,0)';OUT;
    'PE1_TX_DN'<1>:'(0,0,0,0,0,0,0,0,0,DC2,0,0,0,0,0,0,0,0,0,0,0,0,0,0,0,0,0,0,0~
,0)';OUT;
    'PE1_TX_DN'<0>:'(0,0,0,0,0,0,0,0,0,DA2,0,0,0,0,0,0,0,0,0,0,0,0,0,0,0,0,0,0,0~
,0)';OUT;
    'PE1_TX_DP'<15>:'(0,0,0,0,0,0,0,0,0,EC8,0,0,0,0,0,0,0,0,0,0,0,0,0,0,0,0,0,0,~
0,0)';OUT;
    'PE1_TX_DP'<14>:'(0,0,0,0,0,0,0,0,0,EB7,0,0,0,0,0,0,0,0,0,0,0,0,0,0,0,0,0,0,~
0,0)';OUT;
    'PE1_TX_DP'<13>:'(0,0,0,0,0,0,0,0,0,DW6,0,0,0,0,0,0,0,0,0,0,0,0,0,0,0,0,0,0,~
0,0)';OUT;
    'PE1_TX_DP'<12>:'(0,0,0,0,0,0,0,0,0,DT7,0,0,0,0,0,0,0,0,0,0,0,0,0,0,0,0,0,0,~
0,0)';OUT;
    'PE1_TX_DP'<11>:'(0,0,0,0,0,0,0,0,0,DV5,0,0,0,0,0,0,0,0,0,0,0,0,0,0,0,0,0,0,~
0,0)';OUT;
    'PE1_TX_DP'<10>:'(0,0,0,0,0,0,0,0,0,DU4,0,0,0,0,0,0,0,0,0,0,0,0,0,0,0,0,0,0,~
0,0)';OUT;
    'PE1_TX_DP'<9>:'(0,0,0,0,0,0,0,0,0,DU2,0,0,0,0,0,0,0,0,0,0,0,0,0,0,0,0,0,0,0~
,0)';OUT;
    'PE1_TX_DP'<8>:'(0,0,0,0,0,0,0,0,0,DR4,0,0,0,0,0,0,0,0,0,0,0,0,0,0,0,0,0,0,0~
,0)';OUT;
    'PE1_TX_DP'<7>:'(0,0,0,0,0,0,0,0,0,DP3,0,0,0,0,0,0,0,0,0,0,0,0,0,0,0,0,0,0,0~
,0)';OUT;
    'PE1_TX_DP'<6>:'(0,0,0,0,0,0,0,0,0,DL2,0,0,0,0,0,0,0,0,0,0,0,0,0,0,0,0,0,0,0~
,0)';OUT;
    'PE1_TX_DP'<5>:'(0,0,0,0,0,0,0,0,0,DH3,0,0,0,0,0,0,0,0,0,0,0,0,0,0,0,0,0,0,0~
,0)';OUT;
    'PE1_TX_DP'<4>:'(0,0,0,0,0,0,0,0,0,DF3,0,0,0,0,0,0,0,0,0,0,0,0,0,0,0,0,0,0,0~
,0)';OUT;
    'PE1_TX_DP'<3>:'(0,0,0,0,0,0,0,0,0,DC4,0,0,0,0,0,0,0,0,0,0,0,0,0,0,0,0,0,0,0~
,0)';OUT;
    'PE1_TX_DP'<2>:'(0,0,0,0,0,0,0,0,0,DD3,0,0,0,0,0,0,0,0,0,0,0,0,0,0,0,0,0,0,0~
,0)';OUT;
    'PE1_TX_DP'<1>:'(0,0,0,0,0,0,0,0,0,DB1,0,0,0,0,0,0,0,0,0,0,0,0,0,0,0,0,0,0,0~
,0)';OUT;
    'PE1_TX_DP'<0>:'(0,0,0,0,0,0,0,0,0,CW2,0,0,0,0,0,0,0,0,0,0,0,0,0,0,0,0,0,0,0~
,0)';OUT;
    'PE2_RX_DN'<15>:'(0,0,0,0,0,0,0,0,0,0,BK9,0,0,0,0,0,0,0,0,0,0,0,0,0,0,0,0,0,~
0,0)';IN;
    'PE2_RX_DN'<14>:'(0,0,0,0,0,0,0,0,0,0,BL8,0,0,0,0,0,0,0,0,0,0,0,0,0,0,0,0,0,~
0,0)';IN;
    'PE2_RX_DN'<13>:'(0,0,0,0,0,0,0,0,0,0,BN8,0,0,0,0,0,0,0,0,0,0,0,0,0,0,0,0,0,~
0,0)';IN;
    'PE2_RX_DN'<12>:'(0,0,0,0,0,0,0,0,0,0,BR8,0,0,0,0,0,0,0,0,0,0,0,0,0,0,0,0,0,~
0,0)';IN;
    'PE2_RX_DN'<11>:'(0,0,0,0,0,0,0,0,0,0,BT7,0,0,0,0,0,0,0,0,0,0,0,0,0,0,0,0,0,~
0,0)';IN;
    'PE2_RX_DN'<10>:'(0,0,0,0,0,0,0,0,0,0,BV7,0,0,0,0,0,0,0,0,0,0,0,0,0,0,0,0,0,~
0,0)';IN;
    'PE2_RX_DN'<9>:'(0,0,0,0,0,0,0,0,0,0,BY7,0,0,0,0,0,0,0,0,0,0,0,0,0,0,0,0,0,0~
,0)';IN;
    'PE2_RX_DN'<8>:'(0,0,0,0,0,0,0,0,0,0,BY9,0,0,0,0,0,0,0,0,0,0,0,0,0,0,0,0,0,0~
,0)';IN;
    'PE2_RX_DN'<7>:'(0,0,0,0,0,0,0,0,0,0,CE8,0,0,0,0,0,0,0,0,0,0,0,0,0,0,0,0,0,0~
,0)';IN;
    'PE2_RX_DN'<6>:'(0,0,0,0,0,0,0,0,0,0,CE6,0,0,0,0,0,0,0,0,0,0,0,0,0,0,0,0,0,0~
,0)';IN;
    'PE2_RX_DN'<5>:'(0,0,0,0,0,0,0,0,0,0,CG8,0,0,0,0,0,0,0,0,0,0,0,0,0,0,0,0,0,0~
,0)';IN;
    'PE2_RX_DN'<4>:'(0,0,0,0,0,0,0,0,0,0,CK7,0,0,0,0,0,0,0,0,0,0,0,0,0,0,0,0,0,0~
,0)';IN;
    'PE2_RX_DN'<3>:'(0,0,0,0,0,0,0,0,0,0,CM7,0,0,0,0,0,0,0,0,0,0,0,0,0,0,0,0,0,0~
,0)';IN;
    'PE2_RX_DN'<2>:'(0,0,0,0,0,0,0,0,0,0,CP7,0,0,0,0,0,0,0,0,0,0,0,0,0,0,0,0,0,0~
,0)';IN;
    'PE2_RX_DN'<1>:'(0,0,0,0,0,0,0,0,0,0,CP9,0,0,0,0,0,0,0,0,0,0,0,0,0,0,0,0,0,0~
,0)';IN;
    'PE2_RX_DN'<0>:'(0,0,0,0,0,0,0,0,0,0,CT9,0,0,0,0,0,0,0,0,0,0,0,0,0,0,0,0,0,0~
,0)';IN;
    'PE2_RX_DP'<15>:'(0,0,0,0,0,0,0,0,0,0,BJ10,0,0,0,0,0,0,0,0,0,0,0,0,0,0,0,0,0~
,0,0)';IN;
    'PE2_RX_DP'<14>:'(0,0,0,0,0,0,0,0,0,0,BJ8,0,0,0,0,0,0,0,0,0,0,0,0,0,0,0,0,0,~
0,0)';IN;
    'PE2_RX_DP'<13>:'(0,0,0,0,0,0,0,0,0,0,BM7,0,0,0,0,0,0,0,0,0,0,0,0,0,0,0,0,0,~
0,0)';IN;
    'PE2_RX_DP'<12>:'(0,0,0,0,0,0,0,0,0,0,BP9,0,0,0,0,0,0,0,0,0,0,0,0,0,0,0,0,0,~
0,0)';IN;
    'PE2_RX_DP'<11>:'(0,0,0,0,0,0,0,0,0,0,BP7,0,0,0,0,0,0,0,0,0,0,0,0,0,0,0,0,0,~
0,0)';IN;
    'PE2_RX_DP'<10>:'(0,0,0,0,0,0,0,0,0,0,BU6,0,0,0,0,0,0,0,0,0,0,0,0,0,0,0,0,0,~
0,0)';IN;
    'PE2_RX_DP'<9>:'(0,0,0,0,0,0,0,0,0,0,BW8,0,0,0,0,0,0,0,0,0,0,0,0,0,0,0,0,0,0~
,0)';IN;
    'PE2_RX_DP'<8>:'(0,0,0,0,0,0,0,0,0,0,BV9,0,0,0,0,0,0,0,0,0,0,0,0,0,0,0,0,0,0~
,0)';IN;
    'PE2_RX_DP'<7>:'(0,0,0,0,0,0,0,0,0,0,CC8,0,0,0,0,0,0,0,0,0,0,0,0,0,0,0,0,0,0~
,0)';IN;
    'PE2_RX_DP'<6>:'(0,0,0,0,0,0,0,0,0,0,CD7,0,0,0,0,0,0,0,0,0,0,0,0,0,0,0,0,0,0~
,0)';IN;
    'PE2_RX_DP'<5>:'(0,0,0,0,0,0,0,0,0,0,CF7,0,0,0,0,0,0,0,0,0,0,0,0,0,0,0,0,0,0~
,0)';IN;
    'PE2_RX_DP'<4>:'(0,0,0,0,0,0,0,0,0,0,CH7,0,0,0,0,0,0,0,0,0,0,0,0,0,0,0,0,0,0~
,0)';IN;
    'PE2_RX_DP'<3>:'(0,0,0,0,0,0,0,0,0,0,CL6,0,0,0,0,0,0,0,0,0,0,0,0,0,0,0,0,0,0~
,0)';IN;
    'PE2_RX_DP'<2>:'(0,0,0,0,0,0,0,0,0,0,CN8,0,0,0,0,0,0,0,0,0,0,0,0,0,0,0,0,0,0~
,0)';IN;
    'PE2_RX_DP'<1>:'(0,0,0,0,0,0,0,0,0,0,CM9,0,0,0,0,0,0,0,0,0,0,0,0,0,0,0,0,0,0~
,0)';IN;
    'PE2_RX_DP'<0>:'(0,0,0,0,0,0,0,0,0,0,CR8,0,0,0,0,0,0,0,0,0,0,0,0,0,0,0,0,0,0~
,0)';IN;
    'PE2_TX_DN'<15>:'(0,0,0,0,0,0,0,0,0,0,BM5,0,0,0,0,0,0,0,0,0,0,0,0,0,0,0,0,0,~
0,0)';OUT;
    'PE2_TX_DN'<14>:'(0,0,0,0,0,0,0,0,0,0,BL4,0,0,0,0,0,0,0,0,0,0,0,0,0,0,0,0,0,~
0,0)';OUT;
    'PE2_TX_DN'<13>:'(0,0,0,0,0,0,0,0,0,0,BP5,0,0,0,0,0,0,0,0,0,0,0,0,0,0,0,0,0,~
0,0)';OUT;
    'PE2_TX_DN'<12>:'(0,0,0,0,0,0,0,0,0,0,BU4,0,0,0,0,0,0,0,0,0,0,0,0,0,0,0,0,0,~
0,0)';OUT;
    'PE2_TX_DN'<11>:'(0,0,0,0,0,0,0,0,0,0,BW4,0,0,0,0,0,0,0,0,0,0,0,0,0,0,0,0,0,~
0,0)';OUT;
    'PE2_TX_DN'<10>:'(0,0,0,0,0,0,0,0,0,0,CA4,0,0,0,0,0,0,0,0,0,0,0,0,0,0,0,0,0,~
0,0)';OUT;
    'PE2_TX_DN'<9>:'(0,0,0,0,0,0,0,0,0,0,CB3,0,0,0,0,0,0,0,0,0,0,0,0,0,0,0,0,0,0~
,0)';OUT;
    'PE2_TX_DN'<8>:'(0,0,0,0,0,0,0,0,0,0,CC2,0,0,0,0,0,0,0,0,0,0,0,0,0,0,0,0,0,0~
,0)';OUT;
    'PE2_TX_DN'<7>:'(0,0,0,0,0,0,0,0,0,0,CF3,0,0,0,0,0,0,0,0,0,0,0,0,0,0,0,0,0,0~
,0)';OUT;
    'PE2_TX_DN'<6>:'(0,0,0,0,0,0,0,0,0,0,CG2,0,0,0,0,0,0,0,0,0,0,0,0,0,0,0,0,0,0~
,0)';OUT;
    'PE2_TX_DN'<5>:'(0,0,0,0,0,0,0,0,0,0,CL2,0,0,0,0,0,0,0,0,0,0,0,0,0,0,0,0,0,0~
,0)';OUT;
    'PE2_TX_DN'<4>:'(0,0,0,0,0,0,0,0,0,0,CM1,0,0,0,0,0,0,0,0,0,0,0,0,0,0,0,0,0,0~
,0)';OUT;
    'PE2_TX_DN'<3>:'(0,0,0,0,0,0,0,0,0,0,CT3,0,0,0,0,0,0,0,0,0,0,0,0,0,0,0,0,0,0~
,0)';OUT;
    'PE2_TX_DN'<2>:'(0,0,0,0,0,0,0,0,0,0,CT1,0,0,0,0,0,0,0,0,0,0,0,0,0,0,0,0,0,0~
,0)';OUT;
    'PE2_TX_DN'<1>:'(0,0,0,0,0,0,0,0,0,0,CV3,0,0,0,0,0,0,0,0,0,0,0,0,0,0,0,0,0,0~
,0)';OUT;
    'PE2_TX_DN'<0>:'(0,0,0,0,0,0,0,0,0,0,CY3,0,0,0,0,0,0,0,0,0,0,0,0,0,0,0,0,0,0~
,0)';OUT;
    'PE2_TX_DP'<15>:'(0,0,0,0,0,0,0,0,0,0,BK5,0,0,0,0,0,0,0,0,0,0,0,0,0,0,0,0,0,~
0,0)';OUT;
    'PE2_TX_DP'<14>:'(0,0,0,0,0,0,0,0,0,0,BM3,0,0,0,0,0,0,0,0,0,0,0,0,0,0,0,0,0,~
0,0)';OUT;
    'PE2_TX_DP'<13>:'(0,0,0,0,0,0,0,0,0,0,BN4,0,0,0,0,0,0,0,0,0,0,0,0,0,0,0,0,0,~
0,0)';OUT;
    'PE2_TX_DP'<12>:'(0,0,0,0,0,0,0,0,0,0,BR4,0,0,0,0,0,0,0,0,0,0,0,0,0,0,0,0,0,~
0,0)';OUT;
    'PE2_TX_DP'<11>:'(0,0,0,0,0,0,0,0,0,0,BV3,0,0,0,0,0,0,0,0,0,0,0,0,0,0,0,0,0,~
0,0)';OUT;
    'PE2_TX_DP'<10>:'(0,0,0,0,0,0,0,0,0,0,BY5,0,0,0,0,0,0,0,0,0,0,0,0,0,0,0,0,0,~
0,0)';OUT;
    'PE2_TX_DP'<9>:'(0,0,0,0,0,0,0,0,0,0,BY3,0,0,0,0,0,0,0,0,0,0,0,0,0,0,0,0,0,0~
,0)';OUT;
    'PE2_TX_DP'<8>:'(0,0,0,0,0,0,0,0,0,0,CD3,0,0,0,0,0,0,0,0,0,0,0,0,0,0,0,0,0,0~
,0)';OUT;
    'PE2_TX_DP'<7>:'(0,0,0,0,0,0,0,0,0,0,CE4,0,0,0,0,0,0,0,0,0,0,0,0,0,0,0,0,0,0~
,0)';OUT;
    'PE2_TX_DP'<6>:'(0,0,0,0,0,0,0,0,0,0,CE2,0,0,0,0,0,0,0,0,0,0,0,0,0,0,0,0,0,0~
,0)';OUT;
    'PE2_TX_DP'<5>:'(0,0,0,0,0,0,0,0,0,0,CK3,0,0,0,0,0,0,0,0,0,0,0,0,0,0,0,0,0,0~
,0)';OUT;
    'PE2_TX_DP'<4>:'(0,0,0,0,0,0,0,0,0,0,CK1,0,0,0,0,0,0,0,0,0,0,0,0,0,0,0,0,0,0~
,0)';OUT;
    'PE2_TX_DP'<3>:'(0,0,0,0,0,0,0,0,0,0,CP3,0,0,0,0,0,0,0,0,0,0,0,0,0,0,0,0,0,0~
,0)';OUT;
    'PE2_TX_DP'<2>:'(0,0,0,0,0,0,0,0,0,0,CR2,0,0,0,0,0,0,0,0,0,0,0,0,0,0,0,0,0,0~
,0)';OUT;
    'PE2_TX_DP'<1>:'(0,0,0,0,0,0,0,0,0,0,CU2,0,0,0,0,0,0,0,0,0,0,0,0,0,0,0,0,0,0~
,0)';OUT;
    'PE2_TX_DP'<0>:'(0,0,0,0,0,0,0,0,0,0,CW4,0,0,0,0,0,0,0,0,0,0,0,0,0,0,0,0,0,0~
,0)';OUT;
    'PE3_RBIAS'<1>:'(CR30,0,0,0,0,0,0,0,0,0,0,0,0,0,0,0,0,0,0,0,0,0,0,0,0,0,0,0,~
0,0)';IN;
    'PE3_RBIAS'<0>:'(CP29,0,0,0,0,0,0,0,0,0,0,0,0,0,0,0,0,0,0,0,0,0,0,0,0,0,0,0,~
0,0)';IN;
    'PE3_RX_DN'<15>:'(0,0,0,0,0,0,0,0,0,0,0,CV9,0,0,0,0,0,0,0,0,0,0,0,0,0,0,0,0,~
0,0)';IN;
    'PE3_RX_DN'<14>:'(0,0,0,0,0,0,0,0,0,0,0,CY11,0,0,0,0,0,0,0,0,0,0,0,0,0,0,0,0~
,0,0)';IN;
    'PE3_RX_DN'<13>:'(0,0,0,0,0,0,0,0,0,0,0,DB11,0,0,0,0,0,0,0,0,0,0,0,0,0,0,0,0~
,0,0)';IN;
    'PE3_RX_DN'<12>:'(0,0,0,0,0,0,0,0,0,0,0,DD13,0,0,0,0,0,0,0,0,0,0,0,0,0,0,0,0~
,0,0)';IN;
    'PE3_RX_DN'<11>:'(0,0,0,0,0,0,0,0,0,0,0,DG10,0,0,0,0,0,0,0,0,0,0,0,0,0,0,0,0~
,0,0)';IN;
    'PE3_RX_DN'<10>:'(0,0,0,0,0,0,0,0,0,0,0,DG12,0,0,0,0,0,0,0,0,0,0,0,0,0,0,0,0~
,0,0)';IN;
    'PE3_RX_DN'<9>:'(0,0,0,0,0,0,0,0,0,0,0,DJ12,0,0,0,0,0,0,0,0,0,0,0,0,0,0,0,0,~
0,0)';IN;
    'PE3_RX_DN'<8>:'(0,0,0,0,0,0,0,0,0,0,0,DL12,0,0,0,0,0,0,0,0,0,0,0,0,0,0,0,0,~
0,0)';IN;
    'PE3_RX_DN'<7>:'(0,0,0,0,0,0,0,0,0,0,0,DL14,0,0,0,0,0,0,0,0,0,0,0,0,0,0,0,0,~
0,0)';IN;
    'PE3_RX_DN'<6>:'(0,0,0,0,0,0,0,0,0,0,0,DN14,0,0,0,0,0,0,0,0,0,0,0,0,0,0,0,0,~
0,0)';IN;
    'PE3_RX_DN'<5>:'(0,0,0,0,0,0,0,0,0,0,0,DR14,0,0,0,0,0,0,0,0,0,0,0,0,0,0,0,0,~
0,0)';IN;
    'PE3_RX_DN'<4>:'(0,0,0,0,0,0,0,0,0,0,0,DR16,0,0,0,0,0,0,0,0,0,0,0,0,0,0,0,0,~
0,0)';IN;
    'PE3_RX_DN'<3>:'(0,0,0,0,0,0,0,0,0,0,0,DT19,0,0,0,0,0,0,0,0,0,0,0,0,0,0,0,0,~
0,0)';IN;
    'PE3_RX_DN'<2>:'(0,0,0,0,0,0,0,0,0,0,0,DW16,0,0,0,0,0,0,0,0,0,0,0,0,0,0,0,0,~
0,0)';IN;
    'PE3_RX_DN'<1>:'(0,0,0,0,0,0,0,0,0,0,0,DW18,0,0,0,0,0,0,0,0,0,0,0,0,0,0,0,0,~
0,0)';IN;
    'PE3_RX_DN'<0>:'(0,0,0,0,0,0,0,0,0,0,0,EA18,0,0,0,0,0,0,0,0,0,0,0,0,0,0,0,0,~
0,0)';IN;
    'PE3_RX_DP'<15>:'(0,0,0,0,0,0,0,0,0,0,0,CU10,0,0,0,0,0,0,0,0,0,0,0,0,0,0,0,0~
,0,0)';IN;
    'PE3_RX_DP'<14>:'(0,0,0,0,0,0,0,0,0,0,0,CW10,0,0,0,0,0,0,0,0,0,0,0,0,0,0,0,0~
,0,0)';IN;
    'PE3_RX_DP'<13>:'(0,0,0,0,0,0,0,0,0,0,0,DA12,0,0,0,0,0,0,0,0,0,0,0,0,0,0,0,0~
,0,0)';IN;
    'PE3_RX_DP'<12>:'(0,0,0,0,0,0,0,0,0,0,0,DC12,0,0,0,0,0,0,0,0,0,0,0,0,0,0,0,0~
,0,0)';IN;
    'PE3_RX_DP'<11>:'(0,0,0,0,0,0,0,0,0,0,0,DF11,0,0,0,0,0,0,0,0,0,0,0,0,0,0,0,0~
,0,0)';IN;
    'PE3_RX_DP'<10>:'(0,0,0,0,0,0,0,0,0,0,0,DE12,0,0,0,0,0,0,0,0,0,0,0,0,0,0,0,0~
,0,0)';IN;
    'PE3_RX_DP'<9>:'(0,0,0,0,0,0,0,0,0,0,0,DH11,0,0,0,0,0,0,0,0,0,0,0,0,0,0,0,0,~
0,0)';IN;
    'PE3_RX_DP'<8>:'(0,0,0,0,0,0,0,0,0,0,0,DK13,0,0,0,0,0,0,0,0,0,0,0,0,0,0,0,0,~
0,0)';IN;
    'PE3_RX_DP'<7>:'(0,0,0,0,0,0,0,0,0,0,0,DJ14,0,0,0,0,0,0,0,0,0,0,0,0,0,0,0,0,~
0,0)';IN;
    'PE3_RX_DP'<6>:'(0,0,0,0,0,0,0,0,0,0,0,DM13,0,0,0,0,0,0,0,0,0,0,0,0,0,0,0,0,~
0,0)';IN;
    'PE3_RX_DP'<5>:'(0,0,0,0,0,0,0,0,0,0,0,DP15,0,0,0,0,0,0,0,0,0,0,0,0,0,0,0,0,~
0,0)';IN;
    'PE3_RX_DP'<4>:'(0,0,0,0,0,0,0,0,0,0,0,DN16,0,0,0,0,0,0,0,0,0,0,0,0,0,0,0,0,~
0,0)';IN;
    'PE3_RX_DP'<3>:'(0,0,0,0,0,0,0,0,0,0,0,DR18,0,0,0,0,0,0,0,0,0,0,0,0,0,0,0,0,~
0,0)';IN;
    'PE3_RX_DP'<2>:'(0,0,0,0,0,0,0,0,0,0,0,DV17,0,0,0,0,0,0,0,0,0,0,0,0,0,0,0,0,~
0,0)';IN;
    'PE3_RX_DP'<1>:'(0,0,0,0,0,0,0,0,0,0,0,DU18,0,0,0,0,0,0,0,0,0,0,0,0,0,0,0,0,~
0,0)';IN;
    'PE3_RX_DP'<0>:'(0,0,0,0,0,0,0,0,0,0,0,DY17,0,0,0,0,0,0,0,0,0,0,0,0,0,0,0,0,~
0,0)';IN;
    'PE3_TX_DN'<15>:'(0,0,0,0,0,0,0,0,0,0,0,CY5,0,0,0,0,0,0,0,0,0,0,0,0,0,0,0,0,~
0,0)';OUT;
    'PE3_TX_DN'<14>:'(0,0,0,0,0,0,0,0,0,0,0,DB5,0,0,0,0,0,0,0,0,0,0,0,0,0,0,0,0,~
0,0)';OUT;
    'PE3_TX_DN'<13>:'(0,0,0,0,0,0,0,0,0,0,0,DD5,0,0,0,0,0,0,0,0,0,0,0,0,0,0,0,0,~
0,0)';OUT;
    'PE3_TX_DN'<12>:'(0,0,0,0,0,0,0,0,0,0,0,DJ6,0,0,0,0,0,0,0,0,0,0,0,0,0,0,0,0,~
0,0)';OUT;
    'PE3_TX_DN'<11>:'(0,0,0,0,0,0,0,0,0,0,0,DJ4,0,0,0,0,0,0,0,0,0,0,0,0,0,0,0,0,~
0,0)';OUT;
    'PE3_TX_DN'<10>:'(0,0,0,0,0,0,0,0,0,0,0,DL6,0,0,0,0,0,0,0,0,0,0,0,0,0,0,0,0,~
0,0)';OUT;
    'PE3_TX_DN'<9>:'(0,0,0,0,0,0,0,0,0,0,0,DP5,0,0,0,0,0,0,0,0,0,0,0,0,0,0,0,0,0~
,0)';OUT;
    'PE3_TX_DN'<8>:'(0,0,0,0,0,0,0,0,0,0,0,DM7,0,0,0,0,0,0,0,0,0,0,0,0,0,0,0,0,0~
,0)';OUT;
    'PE3_TX_DN'<7>:'(0,0,0,0,0,0,0,0,0,0,0,DR8,0,0,0,0,0,0,0,0,0,0,0,0,0,0,0,0,0~
,0)';OUT;
    'PE3_TX_DN'<6>:'(0,0,0,0,0,0,0,0,0,0,0,DU8,0,0,0,0,0,0,0,0,0,0,0,0,0,0,0,0,0~
,0)';OUT;
    'PE3_TX_DN'<5>:'(0,0,0,0,0,0,0,0,0,0,0,DW10,0,0,0,0,0,0,0,0,0,0,0,0,0,0,0,0,~
0,0)';OUT;
    'PE3_TX_DN'<4>:'(0,0,0,0,0,0,0,0,0,0,0,EB9,0,0,0,0,0,0,0,0,0,0,0,0,0,0,0,0,0~
,0)';OUT;
    'PE3_TX_DN'<3>:'(0,0,0,0,0,0,0,0,0,0,0,DY11,0,0,0,0,0,0,0,0,0,0,0,0,0,0,0,0,~
0,0)';OUT;
    'PE3_TX_DN'<2>:'(0,0,0,0,0,0,0,0,0,0,0,EC12,0,0,0,0,0,0,0,0,0,0,0,0,0,0,0,0,~
0,0)';OUT;
    'PE3_TX_DN'<1>:'(0,0,0,0,0,0,0,0,0,0,0,EE12,0,0,0,0,0,0,0,0,0,0,0,0,0,0,0,0,~
0,0)';OUT;
    'PE3_TX_DN'<0>:'(0,0,0,0,0,0,0,0,0,0,0,EE14,0,0,0,0,0,0,0,0,0,0,0,0,0,0,0,0,~
0,0)';OUT;
    'PE3_TX_DP'<15>:'(0,0,0,0,0,0,0,0,0,0,0,CV5,0,0,0,0,0,0,0,0,0,0,0,0,0,0,0,0,~
0,0)';OUT;
    'PE3_TX_DP'<14>:'(0,0,0,0,0,0,0,0,0,0,0,DA4,0,0,0,0,0,0,0,0,0,0,0,0,0,0,0,0,~
0,0)';OUT;
    'PE3_TX_DP'<13>:'(0,0,0,0,0,0,0,0,0,0,0,DC6,0,0,0,0,0,0,0,0,0,0,0,0,0,0,0,0,~
0,0)';OUT;
    'PE3_TX_DP'<12>:'(0,0,0,0,0,0,0,0,0,0,0,DG6,0,0,0,0,0,0,0,0,0,0,0,0,0,0,0,0,~
0,0)';OUT;
    'PE3_TX_DP'<11>:'(0,0,0,0,0,0,0,0,0,0,0,DH5,0,0,0,0,0,0,0,0,0,0,0,0,0,0,0,0,~
0,0)';OUT;
    'PE3_TX_DP'<10>:'(0,0,0,0,0,0,0,0,0,0,0,DK5,0,0,0,0,0,0,0,0,0,0,0,0,0,0,0,0,~
0,0)';OUT;
    'PE3_TX_DP'<9>:'(0,0,0,0,0,0,0,0,0,0,0,DM5,0,0,0,0,0,0,0,0,0,0,0,0,0,0,0,0,0~
,0)';OUT;
    'PE3_TX_DP'<8>:'(0,0,0,0,0,0,0,0,0,0,0,DN6,0,0,0,0,0,0,0,0,0,0,0,0,0,0,0,0,0~
,0)';OUT;
    'PE3_TX_DP'<7>:'(0,0,0,0,0,0,0,0,0,0,0,DP7,0,0,0,0,0,0,0,0,0,0,0,0,0,0,0,0,0~
,0)';OUT;
    'PE3_TX_DP'<6>:'(0,0,0,0,0,0,0,0,0,0,0,DT9,0,0,0,0,0,0,0,0,0,0,0,0,0,0,0,0,0~
,0)';OUT;
    'PE3_TX_DP'<5>:'(0,0,0,0,0,0,0,0,0,0,0,DV9,0,0,0,0,0,0,0,0,0,0,0,0,0,0,0,0,0~
,0)';OUT;
    'PE3_TX_DP'<4>:'(0,0,0,0,0,0,0,0,0,0,0,DY9,0,0,0,0,0,0,0,0,0,0,0,0,0,0,0,0,0~
,0)';OUT;
    'PE3_TX_DP'<3>:'(0,0,0,0,0,0,0,0,0,0,0,EA10,0,0,0,0,0,0,0,0,0,0,0,0,0,0,0,0,~
0,0)';OUT;
    'PE3_TX_DP'<2>:'(0,0,0,0,0,0,0,0,0,0,0,EB11,0,0,0,0,0,0,0,0,0,0,0,0,0,0,0,0,~
0,0)';OUT;
    'PE3_TX_DP'<1>:'(0,0,0,0,0,0,0,0,0,0,0,ED13,0,0,0,0,0,0,0,0,0,0,0,0,0,0,0,0,~
0,0)';OUT;
    'PE3_TX_DP'<0>:'(0,0,0,0,0,0,0,0,0,0,0,EC14,0,0,0,0,0,0,0,0,0,0,0,0,0,0,0,0,~
0,0)';OUT;
    'PECI':'(AU12,0,0,0,0,0,0,0,0,0,0,0,0,0,0,0,0,0,0,0,0,0,0,0,0,0,0,0,0,0)';$S~
;BIDI;
    'PE_HP_SCL':'(AM19,0,0,0,0,0,0,0,0,0,0,0,0,0,0,0,0,0,0,0,0,0,0,0,0,0,0,0,0,0~
)';$S;BIDI;
    'PE_HP_SDA':'(AL18,0,0,0,0,0,0,0,0,0,0,0,0,0,0,0,0,0,0,0,0,0,0,0,0,0,0,0,0,0~
)';$S;BIDI;
    'PIROM_ADDR'<2>:'(CW56,0,0,0,0,0,0,0,0,0,0,0,0,0,0,0,0,0,0,0,0,0,0,0,0,0,0,0~
,0,0)';BIDI;
    'PIROM_ADDR'<1>:'(CV57,0,0,0,0,0,0,0,0,0,0,0,0,0,0,0,0,0,0,0,0,0,0,0,0,0,0,0~
,0,0)';BIDI;
    'PIROM_ADDR'<0>:'(CU58,0,0,0,0,0,0,0,0,0,0,0,0,0,0,0,0,0,0,0,0,0,0,0,0,0,0,0~
,0,0)';BIDI;
    'PKGID'<2>:'(DA72,0,0,0,0,0,0,0,0,0,0,0,0,0,0,0,0,0,0,0,0,0,0,0,0,0,0,0,0,0)~
';BIDI;
    'PKGID'<1>:'(CW72,0,0,0,0,0,0,0,0,0,0,0,0,0,0,0,0,0,0,0,0,0,0,0,0,0,0,0,0,0)~
';BIDI;
    'PKGID'<0>:'(DC72,0,0,0,0,0,0,0,0,0,0,0,0,0,0,0,0,0,0,0,0,0,0,0,0,0,0,0,0,0)~
';BIDI;
    'PMSYNC':'(AR14,0,0,0,0,0,0,0,0,0,0,0,0,0,0,0,0,0,0,0,0,0,0,0,0,0,0,0,0,0)';~
$S;IN;
    'PMSYNC_CLK':'(AT19,0,0,0,0,0,0,0,0,0,0,0,0,0,0,0,0,0,0,0,0,0,0,0,0,0,0,0,0,~
0)';$S;IN;
    'PM_FAST_WAKE_N':'(AF15,0,0,0,0,0,0,0,0,0,0,0,0,0,0,0,0,0,0,0,0,0,0,0,0,0,0,~
0,0,0)';$S;BIDI;
    'PRDY_N':'(AG16,0,0,0,0,0,0,0,0,0,0,0,0,0,0,0,0,0,0,0,0,0,0,0,0,0,0,0,0,0)';~
$S;OUT;
    'PREQ_N':'(AR12,0,0,0,0,0,0,0,0,0,0,0,0,0,0,0,0,0,0,0,0,0,0,0,0,0,0,0,0,0)';~
$S;IN;
    'PROCDIS_N':'(AB17,0,0,0,0,0,0,0,0,0,0,0,0,0,0,0,0,0,0,0,0,0,0,0,0,0,0,0,0,0~
)';$S;IN;
    'PROCHOT_N':'(AC16,0,0,0,0,0,0,0,0,0,0,0,0,0,0,0,0,0,0,0,0,0,0,0,0,0,0,0,0,0~
)';$S;BIDI;
    'PROC_ID'<1>:'(DB71,0,0,0,0,0,0,0,0,0,0,0,0,0,0,0,0,0,0,0,0,0,0,0,0,0,0,0,0,~
0)';OUT;
    'PROC_ID'<0>:'(CY71,0,0,0,0,0,0,0,0,0,0,0,0,0,0,0,0,0,0,0,0,0,0,0,0,0,0,0,0,~
0)';OUT;
    'PWRGOOD':'(BC24,0,0,0,0,0,0,0,0,0,0,0,0,0,0,0,0,0,0,0,0,0,0,0,0,0,0,0,0,0)';$S;IN;
    'PWR_DEBUG_N':'(0,AP17,0,0,0,0,0,0,0,0,0,0,0,0,0,0,0,0,0,0,0,0,0,0,0,0,0,0,0~
,0)';$S;IN;
    'RESET_N':'(AP21,0,0,0,0,0,0,0,0,0,0,0,0,0,0,0,0,0,0,0,0,0,0,0,0,0,0,0,0,0)';$S;IN;
    'RSVD'<304>:'(0,A4,0,0,0,0,0,0,0,0,0,0,0,0,0,0,0,0,0,0,0,0,0,0,0,0,0,0,0,0)';BIDI;
    'RSVD'<303>:'(0,A6,0,0,0,0,0,0,0,0,0,0,0,0,0,0,0,0,0,0,0,0,0,0,0,0,0,0,0,0)';BIDI;
    'RSVD'<302>:'(0,A14,0,0,0,0,0,0,0,0,0,0,0,0,0,0,0,0,0,0,0,0,0,0,0,0,0,0,0,0)~
';BIDI;
    'RSVD'<301>:'(0,A16,0,0,0,0,0,0,0,0,0,0,0,0,0,0,0,0,0,0,0,0,0,0,0,0,0,0,0,0)~
';BIDI;
    'RSVD'<300>:'(0,A24,0,0,0,0,0,0,0,0,0,0,0,0,0,0,0,0,0,0,0,0,0,0,0,0,0,0,0,0)~
';BIDI;
    'RSVD'<299>:'(0,B3,0,0,0,0,0,0,0,0,0,0,0,0,0,0,0,0,0,0,0,0,0,0,0,0,0,0,0,0)';BIDI;
    'RSVD'<298>:'(0,B7,0,0,0,0,0,0,0,0,0,0,0,0,0,0,0,0,0,0,0,0,0,0,0,0,0,0,0,0)';BIDI;
    'RSVD'<296>:'(0,B13,0,0,0,0,0,0,0,0,0,0,0,0,0,0,0,0,0,0,0,0,0,0,0,0,0,0,0,0)~
';BIDI;
    'RSVD'<295>:'(0,B15,0,0,0,0,0,0,0,0,0,0,0,0,0,0,0,0,0,0,0,0,0,0,0,0,0,0,0,0)~
';BIDI;
    'RSVD'<294>:'(0,B17,0,0,0,0,0,0,0,0,0,0,0,0,0,0,0,0,0,0,0,0,0,0,0,0,0,0,0,0)~
';BIDI;
    'RSVD'<293>:'(0,B77,0,0,0,0,0,0,0,0,0,0,0,0,0,0,0,0,0,0,0,0,0,0,0,0,0,0,0,0)~
';BIDI;
    'RSVD'<292>:'(0,B81,0,0,0,0,0,0,0,0,0,0,0,0,0,0,0,0,0,0,0,0,0,0,0,0,0,0,0,0)~
';BIDI;
    'RSVD'<291>:'(0,C6,0,0,0,0,0,0,0,0,0,0,0,0,0,0,0,0,0,0,0,0,0,0,0,0,0,0,0,0)';BIDI;
    'RSVD'<290>:'(0,C18,0,0,0,0,0,0,0,0,0,0,0,0,0,0,0,0,0,0,0,0,0,0,0,0,0,0,0,0)~
';BIDI;
    'RSVD'<289>:'(0,C24,0,0,0,0,0,0,0,0,0,0,0,0,0,0,0,0,0,0,0,0,0,0,0,0,0,0,0,0)~
';BIDI;
    'RSVD'<288>:'(0,C82,0,0,0,0,0,0,0,0,0,0,0,0,0,0,0,0,0,0,0,0,0,0,0,0,0,0,0,0)~
';BIDI;
    'RSVD'<287>:'(0,D5,0,0,0,0,0,0,0,0,0,0,0,0,0,0,0,0,0,0,0,0,0,0,0,0,0,0,0,0)';BIDI;
    'RSVD'<286>:'(0,D17,0,0,0,0,0,0,0,0,0,0,0,0,0,0,0,0,0,0,0,0,0,0,0,0,0,0,0,0)~
';BIDI;
    'RSVD'<285>:'(0,D65,0,0,0,0,0,0,0,0,0,0,0,0,0,0,0,0,0,0,0,0,0,0,0,0,0,0,0,0)~
';BIDI;
    'RSVD'<284>:'(0,D83,0,0,0,0,0,0,0,0,0,0,0,0,0,0,0,0,0,0,0,0,0,0,0,0,0,0,0,0)~
';BIDI;
    'RSVD'<283>:'(0,E2,0,0,0,0,0,0,0,0,0,0,0,0,0,0,0,0,0,0,0,0,0,0,0,0,0,0,0,0)';BIDI;
    'RSVD'<282>:'(0,E4,0,0,0,0,0,0,0,0,0,0,0,0,0,0,0,0,0,0,0,0,0,0,0,0,0,0,0,0)';BIDI;
    'RSVD'<281>:'(0,E24,0,0,0,0,0,0,0,0,0,0,0,0,0,0,0,0,0,0,0,0,0,0,0,0,0,0,0,0)~
';BIDI;
    'RSVD'<280>:'(0,E84,0,0,0,0,0,0,0,0,0,0,0,0,0,0,0,0,0,0,0,0,0,0,0,0,0,0,0,0)~
';BIDI;
    'RSVD'<279>:'(0,F3,0,0,0,0,0,0,0,0,0,0,0,0,0,0,0,0,0,0,0,0,0,0,0,0,0,0,0,0)';BIDI;
    'RSVD'<278>:'(0,F23,0,0,0,0,0,0,0,0,0,0,0,0,0,0,0,0,0,0,0,0,0,0,0,0,0,0,0,0)~
';BIDI;
    'RSVD'<277>:'(0,F65,0,0,0,0,0,0,0,0,0,0,0,0,0,0,0,0,0,0,0,0,0,0,0,0,0,0,0,0)~
';BIDI;
    'RSVD'<276>:'(0,F83,0,0,0,0,0,0,0,0,0,0,0,0,0,0,0,0,0,0,0,0,0,0,0,0,0,0,0,0)~
';BIDI;
    'RSVD'<275>:'(0,G2,0,0,0,0,0,0,0,0,0,0,0,0,0,0,0,0,0,0,0,0,0,0,0,0,0,0,0,0)';BIDI;
    'RSVD'<274>:'(0,G64,0,0,0,0,0,0,0,0,0,0,0,0,0,0,0,0,0,0,0,0,0,0,0,0,0,0,0,0)~
';BIDI;
    'RSVD'<273>:'(0,G84,0,0,0,0,0,0,0,0,0,0,0,0,0,0,0,0,0,0,0,0,0,0,0,0,0,0,0,0)~
';BIDI;
    'RSVD'<272>:'(0,H1,0,0,0,0,0,0,0,0,0,0,0,0,0,0,0,0,0,0,0,0,0,0,0,0,0,0,0,0)';BIDI;
    'RSVD'<271>:'(0,H83,0,0,0,0,0,0,0,0,0,0,0,0,0,0,0,0,0,0,0,0,0,0,0,0,0,0,0,0)~
';BIDI;
    'RSVD'<270>:'(0,H85,0,0,0,0,0,0,0,0,0,0,0,0,0,0,0,0,0,0,0,0,0,0,0,0,0,0,0,0)~
';BIDI;
    'RSVD'<269>:'(0,J46,0,0,0,0,0,0,0,0,0,0,0,0,0,0,0,0,0,0,0,0,0,0,0,0,0,0,0,0)~
';BIDI;
    'RSVD'<268>:'(0,J62,0,0,0,0,0,0,0,0,0,0,0,0,0,0,0,0,0,0,0,0,0,0,0,0,0,0,0,0)~
';BIDI;
    'RSVD'<267>:'(0,K61,0,0,0,0,0,0,0,0,0,0,0,0,0,0,0,0,0,0,0,0,0,0,0,0,0,0,0,0)~
';BIDI;
    'RSVD'<266>:'(0,M63,0,0,0,0,0,0,0,0,0,0,0,0,0,0,0,0,0,0,0,0,0,0,0,0,0,0,0,0)~
';BIDI;
    'RSVD'<265>:'(0,P65,0,0,0,0,0,0,0,0,0,0,0,0,0,0,0,0,0,0,0,0,0,0,0,0,0,0,0,0)~
';BIDI;
    'RSVD'<264>:'(0,R62,0,0,0,0,0,0,0,0,0,0,0,0,0,0,0,0,0,0,0,0,0,0,0,0,0,0,0,0)~
';BIDI;
    'RSVD'<263>:'(0,R66,0,0,0,0,0,0,0,0,0,0,0,0,0,0,0,0,0,0,0,0,0,0,0,0,0,0,0,0)~
';BIDI;
    'RSVD'<262>:'(0,T67,0,0,0,0,0,0,0,0,0,0,0,0,0,0,0,0,0,0,0,0,0,0,0,0,0,0,0,0)~
';BIDI;
    'RSVD'<261>:'(0,U66,0,0,0,0,0,0,0,0,0,0,0,0,0,0,0,0,0,0,0,0,0,0,0,0,0,0,0,0)~
';BIDI;
    'RSVD'<260>:'(0,V65,0,0,0,0,0,0,0,0,0,0,0,0,0,0,0,0,0,0,0,0,0,0,0,0,0,0,0,0)~
';BIDI;
    'RSVD'<259>:'(0,V67,0,0,0,0,0,0,0,0,0,0,0,0,0,0,0,0,0,0,0,0,0,0,0,0,0,0,0,0)~
';BIDI;
    'RSVD'<258>:'(0,W66,0,0,0,0,0,0,0,0,0,0,0,0,0,0,0,0,0,0,0,0,0,0,0,0,0,0,0,0)~
';BIDI;
    'RSVD'<257>:'(0,Y23,0,0,0,0,0,0,0,0,0,0,0,0,0,0,0,0,0,0,0,0,0,0,0,0,0,0,0,0)~
';BIDI;
    'RSVD'<256>:'(0,Y65,0,0,0,0,0,0,0,0,0,0,0,0,0,0,0,0,0,0,0,0,0,0,0,0,0,0,0,0)~
';BIDI;
    'RSVD'<255>:'(0,0,0,0,0,0,0,0,0,0,0,0,0,0,0,AY83,0,0,0,0,0,0,0,0,0,0,0,0,0,0~
)';BIDI;
    'RSVD'<254>:'(0,AD47,0,0,0,0,0,0,0,0,0,0,0,0,0,0,0,0,0,0,0,0,0,0,0,0,0,0,0,0~
)';BIDI;
    'RSVD'<253>:'(0,AD49,0,0,0,0,0,0,0,0,0,0,0,0,0,0,0,0,0,0,0,0,0,0,0,0,0,0,0,0~
)';BIDI;
    'RSVD'<252>:'(0,AD51,0,0,0,0,0,0,0,0,0,0,0,0,0,0,0,0,0,0,0,0,0,0,0,0,0,0,0,0~
)';BIDI;
    'RSVD'<251>:'(0,AE46,0,0,0,0,0,0,0,0,0,0,0,0,0,0,0,0,0,0,0,0,0,0,0,0,0,0,0,0~
)';BIDI;
    'RSVD'<250>:'(0,AE48,0,0,0,0,0,0,0,0,0,0,0,0,0,0,0,0,0,0,0,0,0,0,0,0,0,0,0,0~
)';BIDI;
    'RSVD'<249>:'(0,AE50,0,0,0,0,0,0,0,0,0,0,0,0,0,0,0,0,0,0,0,0,0,0,0,0,0,0,0,0~
)';BIDI;
    'RSVD'<248>:'(0,AE52,0,0,0,0,0,0,0,0,0,0,0,0,0,0,0,0,0,0,0,0,0,0,0,0,0,0,0,0~
)';BIDI;
    'RSVD'<247>:'(0,AE72,0,0,0,0,0,0,0,0,0,0,0,0,0,0,0,0,0,0,0,0,0,0,0,0,0,0,0,0~
)';BIDI;
    'RSVD'<246>:'(0,AF19,0,0,0,0,0,0,0,0,0,0,0,0,0,0,0,0,0,0,0,0,0,0,0,0,0,0,0,0~
)';BIDI;
    'RSVD'<245>:'(0,AF47,0,0,0,0,0,0,0,0,0,0,0,0,0,0,0,0,0,0,0,0,0,0,0,0,0,0,0,0~
)';BIDI;
    'RSVD'<244>:'(0,AF49,0,0,0,0,0,0,0,0,0,0,0,0,0,0,0,0,0,0,0,0,0,0,0,0,0,0,0,0~
)';BIDI;
    'RSVD'<243>:'(0,AF51,0,0,0,0,0,0,0,0,0,0,0,0,0,0,0,0,0,0,0,0,0,0,0,0,0,0,0,0~
)';BIDI;
    'RSVD'<242>:'(0,AF53,0,0,0,0,0,0,0,0,0,0,0,0,0,0,0,0,0,0,0,0,0,0,0,0,0,0,0,0~
)';BIDI;
    'RSVD'<241>:'(0,AF71,0,0,0,0,0,0,0,0,0,0,0,0,0,0,0,0,0,0,0,0,0,0,0,0,0,0,0,0~
)';BIDI;
    'RSVD'<240>:'(0,AG20,0,0,0,0,0,0,0,0,0,0,0,0,0,0,0,0,0,0,0,0,0,0,0,0,0,0,0,0~
)';BIDI;
    'RSVD'<239>:'(0,AG48,0,0,0,0,0,0,0,0,0,0,0,0,0,0,0,0,0,0,0,0,0,0,0,0,0,0,0,0~
)';BIDI;
    'RSVD'<238>:'(0,AG50,0,0,0,0,0,0,0,0,0,0,0,0,0,0,0,0,0,0,0,0,0,0,0,0,0,0,0,0~
)';BIDI;
    'RSVD'<237>:'(0,AG52,0,0,0,0,0,0,0,0,0,0,0,0,0,0,0,0,0,0,0,0,0,0,0,0,0,0,0,0~
)';BIDI;
    'RSVD'<236>:'(0,AG54,0,0,0,0,0,0,0,0,0,0,0,0,0,0,0,0,0,0,0,0,0,0,0,0,0,0,0,0~
)';BIDI;
    'RSVD'<235>:'(0,AG56,0,0,0,0,0,0,0,0,0,0,0,0,0,0,0,0,0,0,0,0,0,0,0,0,0,0,0,0~
)';BIDI;
    'RSVD'<234>:'(0,AG72,0,0,0,0,0,0,0,0,0,0,0,0,0,0,0,0,0,0,0,0,0,0,0,0,0,0,0,0~
)';BIDI;
    'RSVD'<233>:'(0,AH15,0,0,0,0,0,0,0,0,0,0,0,0,0,0,0,0,0,0,0,0,0,0,0,0,0,0,0,0~
)';BIDI;
    'RSVD'<232>:'(0,AH19,0,0,0,0,0,0,0,0,0,0,0,0,0,0,0,0,0,0,0,0,0,0,0,0,0,0,0,0~
)';BIDI;
    'RSVD'<231>:'(0,AH55,0,0,0,0,0,0,0,0,0,0,0,0,0,0,0,0,0,0,0,0,0,0,0,0,0,0,0,0~
)';BIDI;
    'RSVD'<230>:'(0,AH57,0,0,0,0,0,0,0,0,0,0,0,0,0,0,0,0,0,0,0,0,0,0,0,0,0,0,0,0~
)';BIDI;
    'RSVD'<229>:'(0,AH71,0,0,0,0,0,0,0,0,0,0,0,0,0,0,0,0,0,0,0,0,0,0,0,0,0,0,0,0~
)';BIDI;
    'RSVD'<228>:'(0,AH73,0,0,0,0,0,0,0,0,0,0,0,0,0,0,0,0,0,0,0,0,0,0,0,0,0,0,0,0~
)';BIDI;
    'RSVD'<227>:'(0,AJ20,0,0,0,0,0,0,0,0,0,0,0,0,0,0,0,0,0,0,0,0,0,0,0,0,0,0,0,0~
)';BIDI;
    'RSVD'<226>:'(0,AJ56,0,0,0,0,0,0,0,0,0,0,0,0,0,0,0,0,0,0,0,0,0,0,0,0,0,0,0,0~
)';BIDI;
    'RSVD'<225>:'(0,AJ58,0,0,0,0,0,0,0,0,0,0,0,0,0,0,0,0,0,0,0,0,0,0,0,0,0,0,0,0~
)';BIDI;
    'RSVD'<224>:'(0,AJ60,0,0,0,0,0,0,0,0,0,0,0,0,0,0,0,0,0,0,0,0,0,0,0,0,0,0,0,0~
)';BIDI;
    'RSVD'<223>:'(0,AJ62,0,0,0,0,0,0,0,0,0,0,0,0,0,0,0,0,0,0,0,0,0,0,0,0,0,0,0,0~
)';BIDI;
    'RSVD'<222>:'(0,AJ70,0,0,0,0,0,0,0,0,0,0,0,0,0,0,0,0,0,0,0,0,0,0,0,0,0,0,0,0~
)';BIDI;
    'RSVD'<221>:'(0,AK21,0,0,0,0,0,0,0,0,0,0,0,0,0,0,0,0,0,0,0,0,0,0,0,0,0,0,0,0~
)';BIDI;
    'RSVD'<220>:'(0,AK27,0,0,0,0,0,0,0,0,0,0,0,0,0,0,0,0,0,0,0,0,0,0,0,0,0,0,0,0~
)';BIDI;
    'RSVD'<219>:'(0,AK57,0,0,0,0,0,0,0,0,0,0,0,0,0,0,0,0,0,0,0,0,0,0,0,0,0,0,0,0~
)';BIDI;
    'RSVD'<218>:'(0,AK59,0,0,0,0,0,0,0,0,0,0,0,0,0,0,0,0,0,0,0,0,0,0,0,0,0,0,0,0~
)';BIDI;
    'RSVD'<217>:'(0,AK61,0,0,0,0,0,0,0,0,0,0,0,0,0,0,0,0,0,0,0,0,0,0,0,0,0,0,0,0~
)';BIDI;
    'RSVD'<216>:'(0,AK69,0,0,0,0,0,0,0,0,0,0,0,0,0,0,0,0,0,0,0,0,0,0,0,0,0,0,0,0~
)';BIDI;
    'RSVD'<215>:'(0,AL20,0,0,0,0,0,0,0,0,0,0,0,0,0,0,0,0,0,0,0,0,0,0,0,0,0,0,0,0~
)';BIDI;
    'RSVD'<214>:'(0,AL22,0,0,0,0,0,0,0,0,0,0,0,0,0,0,0,0,0,0,0,0,0,0,0,0,0,0,0,0~
)';BIDI;
    'RSVD'<213>:'(0,AL26,0,0,0,0,0,0,0,0,0,0,0,0,0,0,0,0,0,0,0,0,0,0,0,0,0,0,0,0~
)';BIDI;
    'RSVD'<212>:'(0,AL58,0,0,0,0,0,0,0,0,0,0,0,0,0,0,0,0,0,0,0,0,0,0,0,0,0,0,0,0~
)';BIDI;
    'RSVD'<211>:'(0,AL60,0,0,0,0,0,0,0,0,0,0,0,0,0,0,0,0,0,0,0,0,0,0,0,0,0,0,0,0~
)';BIDI;
    'RSVD'<210>:'(0,AL62,0,0,0,0,0,0,0,0,0,0,0,0,0,0,0,0,0,0,0,0,0,0,0,0,0,0,0,0~
)';BIDI;
    'RSVD'<209>:'(0,AM21,0,0,0,0,0,0,0,0,0,0,0,0,0,0,0,0,0,0,0,0,0,0,0,0,0,0,0,0~
)';BIDI;
    'RSVD'<208>:'(0,AM23,0,0,0,0,0,0,0,0,0,0,0,0,0,0,0,0,0,0,0,0,0,0,0,0,0,0,0,0~
)';BIDI;
    'RSVD'<207>:'(0,AM25,0,0,0,0,0,0,0,0,0,0,0,0,0,0,0,0,0,0,0,0,0,0,0,0,0,0,0,0~
)';BIDI;
    'RSVD'<206>:'(0,AM27,0,0,0,0,0,0,0,0,0,0,0,0,0,0,0,0,0,0,0,0,0,0,0,0,0,0,0,0~
)';BIDI;
    'RSVD'<205>:'(0,AM59,0,0,0,0,0,0,0,0,0,0,0,0,0,0,0,0,0,0,0,0,0,0,0,0,0,0,0,0~
)';BIDI;
    'RSVD'<204>:'(0,AM61,0,0,0,0,0,0,0,0,0,0,0,0,0,0,0,0,0,0,0,0,0,0,0,0,0,0,0,0~
)';BIDI;
    'RSVD'<203>:'(0,AN18,0,0,0,0,0,0,0,0,0,0,0,0,0,0,0,0,0,0,0,0,0,0,0,0,0,0,0,0~
)';BIDI;
    'RSVD'<202>:'(0,AN22,0,0,0,0,0,0,0,0,0,0,0,0,0,0,0,0,0,0,0,0,0,0,0,0,0,0,0,0~
)';BIDI;
    'RSVD'<201>:'(0,AN24,0,0,0,0,0,0,0,0,0,0,0,0,0,0,0,0,0,0,0,0,0,0,0,0,0,0,0,0~
)';BIDI;
    'RSVD'<200>:'(0,AN26,0,0,0,0,0,0,0,0,0,0,0,0,0,0,0,0,0,0,0,0,0,0,0,0,0,0,0,0~
)';BIDI;
    'RSVD'<199>:'(0,AN60,0,0,0,0,0,0,0,0,0,0,0,0,0,0,0,0,0,0,0,0,0,0,0,0,0,0,0,0~
)';BIDI;
    'RSVD'<198>:'(0,AN62,0,0,0,0,0,0,0,0,0,0,0,0,0,0,0,0,0,0,0,0,0,0,0,0,0,0,0,0~
)';BIDI;
    'RSVD'<197>:'(0,AP23,0,0,0,0,0,0,0,0,0,0,0,0,0,0,0,0,0,0,0,0,0,0,0,0,0,0,0,0~
)';BIDI;
    'RSVD'<196>:'(0,AP25,0,0,0,0,0,0,0,0,0,0,0,0,0,0,0,0,0,0,0,0,0,0,0,0,0,0,0,0~
)';BIDI;
    'RSVD'<195>:'(0,AP27,0,0,0,0,0,0,0,0,0,0,0,0,0,0,0,0,0,0,0,0,0,0,0,0,0,0,0,0~
)';BIDI;
    'RSVD'<194>:'(0,AP61,0,0,0,0,0,0,0,0,0,0,0,0,0,0,0,0,0,0,0,0,0,0,0,0,0,0,0,0~
)';BIDI;
    'RSVD'<193>:'(0,0,0,0,0,0,0,0,AR20,0,0,0,0,0,0,0,0,0,0,0,0,0,0,0,0,0,0,0,0,0~
)';BIDI;
    'RSVD'<192>:'(0,0,0,0,0,0,0,0,AR22,0,0,0,0,0,0,0,0,0,0,0,0,0,0,0,0,0,0,0,0,0~
)';BIDI;
    'RSVD'<191>:'(0,0,0,0,0,0,0,0,AR26,0,0,0,0,0,0,0,0,0,0,0,0,0,0,0,0,0,0,0,0,0~
)';BIDI;
    'RSVD'<190>:'(0,0,0,0,0,0,0,0,AR62,0,0,0,0,0,0,0,0,0,0,0,0,0,0,0,0,0,0,0,0,0~
)';BIDI;
    'RSVD'<189>:'(0,0,0,0,0,0,0,0,AT13,0,0,0,0,0,0,0,0,0,0,0,0,0,0,0,0,0,0,0,0,0~
)';BIDI;
    'RSVD'<188>:'(0,0,0,0,0,0,0,0,AT23,0,0,0,0,0,0,0,0,0,0,0,0,0,0,0,0,0,0,0,0,0~
)';BIDI;
    'RSVD'<187>:'(0,0,0,0,0,0,0,0,AT25,0,0,0,0,0,0,0,0,0,0,0,0,0,0,0,0,0,0,0,0,0~
)';BIDI;
    'RSVD'<186>:'(0,0,0,0,0,0,0,0,AV77,0,0,0,0,0,0,0,0,0,0,0,0,0,0,0,0,0,0,0,0,0~
)';BIDI;
    'RSVD'<184>:'(0,0,0,0,0,0,0,0,AW64,0,0,0,0,0,0,0,0,0,0,0,0,0,0,0,0,0,0,0,0,0~
)';BIDI;
    'RSVD'<183>:'(0,0,0,0,0,0,0,0,AW76,0,0,0,0,0,0,0,0,0,0,0,0,0,0,0,0,0,0,0,0,0~
)';BIDI;
    'RSVD'<182>:'(0,0,0,0,0,0,0,0,AY65,0,0,0,0,0,0,0,0,0,0,0,0,0,0,0,0,0,0,0,0,0~
)';BIDI;
    'RSVD'<181>:'(0,0,0,0,0,0,0,0,AY67,0,0,0,0,0,0,0,0,0,0,0,0,0,0,0,0,0,0,0,0,0~
)';BIDI;
    'RSVD'<180>:'(0,0,0,0,0,0,0,0,AY75,0,0,0,0,0,0,0,0,0,0,0,0,0,0,0,0,0,0,0,0,0~
)';BIDI;
    'RSVD'<179>:'(0,0,0,0,0,0,0,0,AY77,0,0,0,0,0,0,0,0,0,0,0,0,0,0,0,0,0,0,0,0,0~
)';BIDI;
    'RSVD'<178>:'(0,0,0,0,0,0,0,0,BA14,0,0,0,0,0,0,0,0,0,0,0,0,0,0,0,0,0,0,0,0,0~
)';BIDI;
    'RSVD'<177>:'(0,0,0,0,0,0,0,0,BA16,0,0,0,0,0,0,0,0,0,0,0,0,0,0,0,0,0,0,0,0,0~
)';BIDI;
    'RSVD'<176>:'(0,0,0,0,0,0,0,0,BA18,0,0,0,0,0,0,0,0,0,0,0,0,0,0,0,0,0,0,0,0,0~
)';BIDI;
    'RSVD'<175>:'(0,0,0,0,0,0,0,0,BA22,0,0,0,0,0,0,0,0,0,0,0,0,0,0,0,0,0,0,0,0,0~
)';BIDI;
    'RSVD'<174>:'(0,0,0,0,0,0,0,0,BA64,0,0,0,0,0,0,0,0,0,0,0,0,0,0,0,0,0,0,0,0,0~
)';BIDI;
    'RSVD'<173>:'(0,0,0,0,0,0,0,0,BA66,0,0,0,0,0,0,0,0,0,0,0,0,0,0,0,0,0,0,0,0,0~
)';BIDI;
    'RSVD'<172>:'(0,0,0,0,0,0,0,0,BA76,0,0,0,0,0,0,0,0,0,0,0,0,0,0,0,0,0,0,0,0,0~
)';BIDI;
    'RSVD'<171>:'(0,0,0,0,0,0,0,0,0,0,0,0,0,0,0,BA78,0,0,0,0,0,0,0,0,0,0,0,0,0,0~
)';BIDI;
    'RSVD'<170>:'(0,0,0,0,0,0,0,0,0,0,0,0,0,0,0,BA82,0,0,0,0,0,0,0,0,0,0,0,0,0,0~
)';BIDI;
    'RSVD'<169>:'(0,0,0,0,0,0,0,0,0,0,0,0,0,0,0,BB13,0,0,0,0,0,0,0,0,0,0,0,0,0,0~
)';BIDI;
    'RSVD'<168>:'(0,0,0,0,0,0,0,0,0,0,0,0,0,0,0,BB15,0,0,0,0,0,0,0,0,0,0,0,0,0,0~
)';BIDI;
    'RSVD'<167>:'(0,0,0,0,0,0,0,0,0,0,0,0,0,0,0,BB17,0,0,0,0,0,0,0,0,0,0,0,0,0,0~
)';BIDI;
    'RSVD'<166>:'(0,0,0,0,0,0,0,0,0,0,0,0,0,0,0,BB21,0,0,0,0,0,0,0,0,0,0,0,0,0,0~
)';BIDI;
    'RSVD'<165>:'(0,0,0,0,0,0,0,0,0,0,0,0,0,0,0,BB25,0,0,0,0,0,0,0,0,0,0,0,0,0,0~
)';BIDI;
    'RSVD'<164>:'(0,0,0,0,0,0,0,0,0,0,0,0,0,0,0,BB65,0,0,0,0,0,0,0,0,0,0,0,0,0,0~
)';BIDI;
    'RSVD'<163>:'(0,0,0,0,0,0,0,0,0,0,0,0,0,0,0,BB67,0,0,0,0,0,0,0,0,0,0,0,0,0,0~
)';BIDI;
    'RSVD'<162>:'(0,0,0,0,0,0,0,0,0,0,0,0,0,0,0,BC14,0,0,0,0,0,0,0,0,0,0,0,0,0,0~
)';BIDI;
    'RSVD'<161>:'(0,0,0,0,0,0,0,0,0,0,0,0,0,0,0,BC18,0,0,0,0,0,0,0,0,0,0,0,0,0,0~
)';BIDI;
    'RSVD'<160>:'(0,0,0,0,0,0,0,0,0,0,0,0,0,0,0,BC20,0,0,0,0,0,0,0,0,0,0,0,0,0,0~
)';BIDI;
    'RSVD'<159>:'(0,0,0,0,0,0,0,0,0,0,0,0,0,0,0,BC22,0,0,0,0,0,0,0,0,0,0,0,0,0,0~
)';BIDI;
    'RSVD'<158>:'(0,0,0,0,0,0,0,0,0,0,0,0,0,0,0,BC64,0,0,0,0,0,0,0,0,0,0,0,0,0,0~
)';BIDI;
    'RSVD'<157>:'(0,0,0,0,0,0,0,0,0,0,0,0,0,0,0,BC66,0,0,0,0,0,0,0,0,0,0,0,0,0,0~
)';BIDI;
    'RSVD'<156>:'(0,0,0,0,0,0,0,0,0,0,0,0,0,0,0,BC68,0,0,0,0,0,0,0,0,0,0,0,0,0,0~
)';BIDI;
    'RSVD'<155>:'(0,0,0,0,0,0,0,0,0,0,0,0,0,0,0,BD17,0,0,0,0,0,0,0,0,0,0,0,0,0,0~
)';BIDI;
    'RSVD'<154>:'(0,0,0,0,0,0,0,0,0,0,0,0,0,0,0,BD19,0,0,0,0,0,0,0,0,0,0,0,0,0,0~
)';BIDI;
    'RSVD'<153>:'(0,0,0,0,0,0,0,0,0,0,0,0,0,0,0,BD25,0,0,0,0,0,0,0,0,0,0,0,0,0,0~
)';BIDI;
    'RSVD'<152>:'(0,0,0,0,0,0,0,0,0,0,0,0,0,0,0,BD65,0,0,0,0,0,0,0,0,0,0,0,0,0,0~
)';BIDI;
    'RSVD'<151>:'(0,0,0,0,0,0,0,0,0,0,0,0,0,0,0,BD67,0,0,0,0,0,0,0,0,0,0,0,0,0,0~
)';BIDI;
    'RSVD'<150>:'(0,0,0,0,0,0,0,0,0,0,0,0,0,0,0,BD69,0,0,0,0,0,0,0,0,0,0,0,0,0,0~
)';BIDI;
    'RSVD'<149>:'(0,0,0,0,0,0,0,0,0,0,0,0,0,0,0,BE18,0,0,0,0,0,0,0,0,0,0,0,0,0,0~
)';BIDI;
    'RSVD'<148>:'(0,0,0,0,0,0,0,0,0,0,0,0,0,0,0,BE20,0,0,0,0,0,0,0,0,0,0,0,0,0,0~
)';BIDI;
    'RSVD'<147>:'(0,0,0,0,0,0,0,0,0,0,0,0,0,0,0,BE22,0,0,0,0,0,0,0,0,0,0,0,0,0,0~
)';BIDI;
    'RSVD'<146>:'(0,0,0,0,0,0,0,0,0,0,0,0,0,0,0,BF21,0,0,0,0,0,0,0,0,0,0,0,0,0,0~
)';BIDI;
    'RSVD'<145>:'(0,0,0,0,0,0,0,0,0,0,0,0,0,0,0,BG18,0,0,0,0,0,0,0,0,0,0,0,0,0,0~
)';BIDI;
    'RSVD'<144>:'(0,0,0,0,0,0,0,0,0,0,0,0,0,0,0,BG20,0,0,0,0,0,0,0,0,0,0,0,0,0,0~
)';BIDI;
    'RSVD'<143>:'(0,0,0,0,0,0,0,0,0,0,0,0,0,0,0,BH19,0,0,0,0,0,0,0,0,0,0,0,0,0,0~
)';BIDI;
    'RSVD'<142>:'(0,0,0,0,0,0,0,0,0,0,0,0,0,0,0,BJ16,0,0,0,0,0,0,0,0,0,0,0,0,0,0~
)';BIDI;
    'RSVD'<141>:'(0,0,0,0,0,0,0,0,0,0,0,0,0,0,0,BJ18,0,0,0,0,0,0,0,0,0,0,0,0,0,0~
)';BIDI;
    'RSVD'<140>:'(0,0,0,0,0,0,0,0,0,0,0,0,0,0,0,BJ20,0,0,0,0,0,0,0,0,0,0,0,0,0,0~
)';BIDI;
    'RSVD'<139>:'(0,0,0,0,0,0,0,0,0,0,0,0,0,0,0,BK17,0,0,0,0,0,0,0,0,0,0,0,0,0,0~
)';BIDI;
    'RSVD'<138>:'(0,0,0,0,0,0,0,0,0,0,0,0,0,0,0,BL18,0,0,0,0,0,0,0,0,0,0,0,0,0,0~
)';BIDI;
    'RSVD'<137>:'(0,0,0,0,0,0,0,0,0,0,0,0,0,0,0,BL20,0,0,0,0,0,0,0,0,0,0,0,0,0,0~
)';BIDI;
    'RSVD'<136>:'(0,0,0,0,0,0,0,0,0,0,0,0,0,0,0,BM17,0,0,0,0,0,0,0,0,0,0,0,0,0,0~
)';BIDI;
    'RSVD'<135>:'(0,0,0,0,0,0,0,0,0,0,0,0,0,0,0,BM19,0,0,0,0,0,0,0,0,0,0,0,0,0,0~
)';BIDI;
    'RSVD'<134>:'(0,0,0,0,0,0,0,0,0,0,0,0,0,0,0,BN18,0,0,0,0,0,0,0,0,0,0,0,0,0,0~
)';BIDI;
    'RSVD'<133>:'(0,0,0,0,0,0,0,0,0,0,0,0,0,0,0,BP17,0,0,0,0,0,0,0,0,0,0,0,0,0,0~
)';BIDI;
    'RSVD'<132>:'(0,0,0,0,0,0,0,0,0,0,0,0,0,0,0,BP21,0,0,0,0,0,0,0,0,0,0,0,0,0,0~
)';BIDI;
    'RSVD'<131>:'(0,0,0,0,0,0,0,0,0,0,0,0,0,0,0,BR22,0,0,0,0,0,0,0,0,0,0,0,0,0,0~
)';BIDI;
    'RSVD'<130>:'(0,0,0,0,0,0,0,0,0,0,0,0,0,0,0,BR24,0,0,0,0,0,0,0,0,0,0,0,0,0,0~
)';BIDI;
    'RSVD'<129>:'(0,0,0,0,0,0,0,0,0,0,0,0,0,0,0,BU18,0,0,0,0,0,0,0,0,0,0,0,0,0,0~
)';BIDI;
    'RSVD'<128>:'(0,0,0,0,0,0,0,0,0,0,0,0,0,0,0,BU20,0,0,0,0,0,0,0,0,0,0,0,0,0,0~
)';BIDI;
    'RSVD'<127>:'(0,0,0,0,0,0,0,0,0,0,0,0,0,0,0,BU22,0,0,0,0,0,0,0,0,0,0,0,0,0,0~
)';BIDI;
    'RSVD'<126>:'(0,0,0,0,0,0,0,0,0,0,0,0,0,0,0,BV19,0,0,0,0,0,0,0,0,0,0,0,0,0,0~
)';BIDI;
    'RSVD'<125>:'(0,0,0,0,0,0,0,0,0,0,0,0,0,0,0,BV21,0,0,0,0,0,0,0,0,0,0,0,0,0,0~
)';BIDI;
    'RSVD'<124>:'(0,0,0,0,0,0,0,0,0,0,0,0,0,0,0,BV23,0,0,0,0,0,0,0,0,0,0,0,0,0,0~
)';BIDI;
    'RSVD'<123>:'(0,0,0,0,0,0,0,0,0,0,0,0,0,0,0,BW10,0,0,0,0,0,0,0,0,0,0,0,0,0,0~
)';BIDI;
    'RSVD'<122>:'(0,0,0,0,0,0,0,0,0,0,0,0,0,0,0,BW20,0,0,0,0,0,0,0,0,0,0,0,0,0,0~
)';BIDI;
    'RSVD'<121>:'(0,0,0,0,0,0,0,0,0,0,0,0,0,0,0,BW22,0,0,0,0,0,0,0,0,0,0,0,0,0,0~
)';BIDI;
    'RSVD'<120>:'(0,0,0,0,0,0,0,0,0,0,0,0,0,0,0,BY19,0,0,0,0,0,0,0,0,0,0,0,0,0,0~
)';BIDI;
    'RSVD'<119>:'(0,0,0,0,0,0,0,0,0,0,0,0,0,0,0,BY25,0,0,0,0,0,0,0,0,0,0,0,0,0,0~
)';BIDI;
    'RSVD'<118>:'(0,0,0,0,0,0,0,0,0,0,0,0,0,0,0,CA22,0,0,0,0,0,0,0,0,0,0,0,0,0,0~
)';BIDI;
    'RSVD'<117>:'(0,0,0,0,0,0,0,0,0,0,0,0,0,0,0,CA24,0,0,0,0,0,0,0,0,0,0,0,0,0,0~
)';BIDI;
    'RSVD'<116>:'(0,0,0,0,0,0,0,0,0,0,0,0,0,0,0,CB19,0,0,0,0,0,0,0,0,0,0,0,0,0,0~
)';BIDI;
    'RSVD'<115>:'(0,0,0,0,0,0,0,0,0,0,0,0,0,0,0,CB21,0,0,0,0,0,0,0,0,0,0,0,0,0,0~
)';BIDI;
    'RSVD'<114>:'(0,0,0,0,0,0,0,0,0,0,0,0,0,0,0,CB25,0,0,0,0,0,0,0,0,0,0,0,0,0,0~
)';BIDI;
    'RSVD'<113>:'(0,0,0,0,0,0,0,0,0,0,0,0,0,0,0,CB5,0,0,0,0,0,0,0,0,0,0,0,0,0,0)~
';BIDI;
    'RSVD'<112>:'(0,0,0,0,0,0,0,0,0,0,0,0,0,0,0,CC20,0,0,0,0,0,0,0,0,0,0,0,0,0,0~
)';BIDI;
    'RSVD'<111>:'(0,0,0,0,0,0,0,0,0,0,0,0,0,0,0,CC6,0,0,0,0,0,0,0,0,0,0,0,0,0,0)~
';BIDI;
    'RSVD'<110>:'(0,0,0,0,0,0,0,0,0,0,0,0,0,0,0,CD19,0,0,0,0,0,0,0,0,0,0,0,0,0,0~
)';BIDI;
    'RSVD'<109>:'(0,0,0,0,0,0,0,0,0,0,0,0,0,0,0,CD21,0,0,0,0,0,0,0,0,0,0,0,0,0,0~
)';BIDI;
    'RSVD'<108>:'(0,0,0,0,0,0,0,0,0,0,0,0,0,0,0,CD25,0,0,0,0,0,0,0,0,0,0,0,0,0,0~
)';BIDI;
    'RSVD'<107>:'(0,0,0,0,0,0,0,0,0,0,0,0,0,0,0,CE22,0,0,0,0,0,0,0,0,0,0,0,0,0,0~
)';BIDI;
    'RSVD'<106>:'(0,0,0,0,0,0,0,0,0,0,0,0,0,0,0,CE78,0,0,0,0,0,0,0,0,0,0,0,0,0,0~
)';BIDI;
    'RSVD'<105>:'(0,0,0,0,0,0,0,0,0,0,0,0,0,0,0,CE80,0,0,0,0,0,0,0,0,0,0,0,0,0,0~
)';BIDI;
    'RSVD'<104>:'(0,0,0,0,0,0,0,0,0,0,0,0,0,0,0,CF19,0,0,0,0,0,0,0,0,0,0,0,0,0,0~
)';BIDI;
    'RSVD'<103>:'(0,0,0,0,0,0,0,0,0,0,0,0,0,0,0,CF21,0,0,0,0,0,0,0,0,0,0,0,0,0,0~
)';BIDI;
    'RSVD'<102>:'(0,0,0,0,0,0,0,0,0,0,0,0,0,0,0,CF23,0,0,0,0,0,0,0,0,0,0,0,0,0,0~
)';BIDI;
    'RSVD'<101>:'(0,0,0,0,0,0,0,0,0,0,0,0,0,0,0,CF79,0,0,0,0,0,0,0,0,0,0,0,0,0,0~
)';BIDI;
    'RSVD'<100>:'(0,0,0,0,0,0,0,0,0,0,0,0,0,0,0,CF81,0,0,0,0,0,0,0,0,0,0,0,0,0,0~
)';BIDI;
    'RSVD'<99>:'(0,0,0,0,0,0,0,0,0,0,0,0,0,0,0,CG10,0,0,0,0,0,0,0,0,0,0,0,0,0,0)~
';BIDI;
    'RSVD'<98>:'(0,0,0,0,0,0,0,0,0,0,0,0,0,0,0,CG20,0,0,0,0,0,0,0,0,0,0,0,0,0,0)~
';BIDI;
    'RSVD'<97>:'(0,0,0,0,0,0,0,0,0,0,0,0,0,0,0,CG24,0,0,0,0,0,0,0,0,0,0,0,0,0,0)~
';BIDI;
    'RSVD'<96>:'(0,0,0,0,0,0,0,0,0,0,0,0,0,0,0,CG26,0,0,0,0,0,0,0,0,0,0,0,0,0,0)~
';BIDI;
    'RSVD'<95>:'(0,0,0,0,0,0,0,0,0,0,0,0,0,0,0,CG78,0,0,0,0,0,0,0,0,0,0,0,0,0,0)~
';BIDI;
    'RSVD'<94>:'(0,0,0,0,0,0,0,0,0,0,0,0,0,0,0,CG82,0,0,0,0,0,0,0,0,0,0,0,0,0,0)~
';BIDI;
    'RSVD'<93>:'(0,0,0,0,0,0,0,0,0,0,0,0,0,0,0,CH21,0,0,0,0,0,0,0,0,0,0,0,0,0,0)~
';BIDI;
    'RSVD'<92>:'(0,0,0,0,0,0,0,0,0,0,0,0,0,0,0,CH23,0,0,0,0,0,0,0,0,0,0,0,0,0,0)~
';BIDI;
    'RSVD'<91>:'(0,0,0,0,0,0,0,0,0,0,0,0,0,0,0,0,CH25,0,0,0,0,0,0,0,0,0,0,0,0,0)~
';BIDI;
    'RSVD'<90>:'(0,0,0,0,0,0,0,0,0,0,0,0,0,0,0,0,CH77,0,0,0,0,0,0,0,0,0,0,0,0,0)~
';BIDI;
    'RSVD'<89>:'(0,0,0,0,0,0,0,0,0,0,0,0,0,0,0,0,CJ20,0,0,0,0,0,0,0,0,0,0,0,0,0)~
';BIDI;
    'RSVD'<88>:'(0,0,0,0,0,0,0,0,0,0,0,0,0,0,0,0,CJ22,0,0,0,0,0,0,0,0,0,0,0,0,0)~
';BIDI;
    'RSVD'<87>:'(0,0,0,0,0,0,0,0,0,0,0,0,0,0,0,0,CJ24,0,0,0,0,0,0,0,0,0,0,0,0,0)~
';BIDI;
    'RSVD'<86>:'(0,0,0,0,0,0,0,0,0,0,0,0,0,0,0,0,CJ26,0,0,0,0,0,0,0,0,0,0,0,0,0)~
';BIDI;
    'RSVD'<85>:'(0,0,0,0,0,0,0,0,0,0,0,0,0,0,0,0,CK19,0,0,0,0,0,0,0,0,0,0,0,0,0)~
';BIDI;
    'RSVD'<84>:'(0,0,0,0,0,0,0,0,0,0,0,0,0,0,0,0,CK23,0,0,0,0,0,0,0,0,0,0,0,0,0)~
';BIDI;
    'RSVD'<83>:'(0,0,0,0,0,0,0,0,0,0,0,0,0,0,0,0,CK25,0,0,0,0,0,0,0,0,0,0,0,0,0)~
';BIDI;
    'RSVD'<82>:'(0,0,0,0,0,0,0,0,0,0,0,0,0,0,0,0,CK77,0,0,0,0,0,0,0,0,0,0,0,0,0)~
';BIDI;
    'RSVD'<81>:'(0,0,0,0,0,0,0,0,0,0,0,0,0,0,0,0,CL24,0,0,0,0,0,0,0,0,0,0,0,0,0)~
';BIDI;
    'RSVD'<80>:'(0,0,0,0,0,0,0,0,0,0,0,0,0,0,0,0,0,0,0,0,0,CL26,0,0,0,0,0,0,0,0)~
';BIDI;
    'RSVD'<79>:'(0,0,0,0,0,0,0,0,0,0,0,0,0,0,0,0,0,0,0,0,0,CM23,0,0,0,0,0,0,0,0)~
';BIDI;
    'RSVD'<78>:'(0,0,0,0,0,0,0,0,0,0,0,0,0,0,0,0,0,0,0,0,0,CM25,0,0,0,0,0,0,0,0)~
';BIDI;
    'RSVD'<77>:'(0,0,0,0,0,0,0,0,0,0,0,0,0,0,0,0,0,0,0,0,0,CN22,0,0,0,0,0,0,0,0)~
';BIDI;
    'RSVD'<76>:'(0,0,0,0,0,0,0,0,0,0,0,0,0,0,0,0,0,0,0,0,0,CN24,0,0,0,0,0,0,0,0)~
';BIDI;
    'RSVD'<75>:'(0,0,0,0,0,0,0,0,0,0,0,0,0,0,0,0,0,0,0,0,0,CN28,0,0,0,0,0,0,0,0)~
';BIDI;
    'RSVD'<74>:'(0,0,0,0,0,0,0,0,0,0,0,0,0,0,0,0,0,0,0,0,0,CP23,0,0,0,0,0,0,0,0)~
';BIDI;
    'RSVD'<73>:'(0,0,0,0,0,0,0,0,0,0,0,0,0,0,0,0,0,0,0,0,0,CP31,0,0,0,0,0,0,0,0)~
';BIDI;
    'RSVD'<72>:'(0,0,0,0,0,0,0,0,0,0,0,0,0,0,0,0,0,0,0,0,0,CR60,0,0,0,0,0,0,0,0)~
';BIDI;
    'RSVD'<71>:'(0,0,0,0,0,0,0,0,0,0,0,0,0,0,0,0,0,0,0,0,0,CT23,0,0,0,0,0,0,0,0)~
';BIDI;
    'RSVD'<70>:'(0,0,0,0,0,0,0,0,0,0,0,0,0,0,0,0,0,0,0,0,0,CT5,0,0,0,0,0,0,0,0)';BIDI;
    'RSVD'<69>:'(0,0,0,0,0,0,0,0,0,0,0,0,0,0,0,0,0,0,0,0,0,CT69,0,0,0,0,0,0,0,0)~
';BIDI;
    'RSVD'<68>:'(0,0,0,0,0,0,0,0,0,0,0,0,0,0,0,0,0,0,0,0,0,CU24,0,0,0,0,0,0,0,0)~
';BIDI;
    'RSVD'<67>:'(0,0,0,0,0,0,0,0,0,0,0,0,0,0,0,0,0,0,0,0,0,CU6,0,0,0,0,0,0,0,0)';BIDI;
    'RSVD'<66>:'(0,0,0,0,0,0,0,0,0,0,0,0,0,0,0,0,0,0,0,0,0,CU60,0,0,0,0,0,0,0,0)~
';BIDI;
    'RSVD'<65>:'(0,0,0,0,0,0,0,0,0,0,0,0,0,0,0,0,0,0,0,0,0,CV23,0,0,0,0,0,0,0,0)~
';BIDI;
    'RSVD'<64>:'(0,0,0,0,0,0,0,0,0,0,0,0,0,0,0,0,0,0,0,0,0,CV69,0,0,0,0,0,0,0,0)~
';BIDI;
    'RSVD'<63>:'(0,0,0,0,0,0,0,0,0,0,0,0,0,0,0,0,0,0,0,0,0,CW22,0,0,0,0,0,0,0,0)~
';BIDI;
    'RSVD'<62>:'(0,0,0,0,0,0,0,0,0,0,0,0,0,0,0,0,0,0,0,0,0,CW24,0,0,0,0,0,0,0,0)~
';BIDI;
    'RSVD'<61>:'(0,0,0,0,0,0,0,0,0,0,0,0,0,0,0,0,0,0,0,0,0,CW60,0,0,0,0,0,0,0,0)~
';BIDI;
    'RSVD'<60>:'(0,0,0,0,0,0,0,0,0,0,0,0,0,0,0,0,0,0,0,0,0,CW62,0,0,0,0,0,0,0,0)~
';BIDI;
    'RSVD'<59>:'(0,0,0,0,0,0,0,0,0,0,0,0,0,0,0,0,0,0,0,0,0,CY23,0,0,0,0,0,0,0,0)~
';BIDI;
    'RSVD'<58>:'(0,0,0,0,0,0,0,0,0,0,0,0,0,0,0,0,0,0,0,0,0,CY25,0,0,0,0,0,0,0,0)~
';BIDI;
    'RSVD'<57>:'(0,0,0,0,0,0,0,0,0,0,0,0,0,0,0,0,0,0,0,0,0,CY39,0,0,0,0,0,0,0,0)~
';BIDI;
    'RSVD'<56>:'(0,0,0,0,0,0,0,0,0,0,0,0,0,0,0,0,0,0,0,0,0,CY53,0,0,0,0,0,0,0,0)~
';BIDI;
    'RSVD'<55>:'(0,0,0,0,0,0,0,0,0,0,0,0,0,0,0,0,0,0,0,0,0,CY57,0,0,0,0,0,0,0,0)~
';BIDI;
    'RSVD'<54>:'(0,0,0,0,0,0,0,0,0,0,0,0,0,0,0,0,0,0,0,0,0,CY63,0,0,0,0,0,0,0,0)~
';BIDI;
    'RSVD'<53>:'(0,0,0,0,0,0,0,0,0,0,0,0,0,0,0,0,0,0,0,0,0,CY73,0,0,0,0,0,0,0,0)~
';BIDI;
    'RSVD'<52>:'(0,0,0,0,0,0,0,0,0,0,0,0,0,0,0,0,0,0,0,0,0,DA24,0,0,0,0,0,0,0,0)~
';BIDI;
    'RSVD'<51>:'(0,0,0,0,0,0,0,0,0,0,0,0,0,0,0,0,0,0,0,0,0,DA40,0,0,0,0,0,0,0,0)~
';BIDI;
    'RSVD'<50>:'(0,0,0,0,0,0,0,0,0,0,0,0,0,0,0,0,0,0,0,0,0,DA52,0,0,0,0,0,0,0,0)~
';BIDI;
    'RSVD'<49>:'(0,0,0,0,0,0,0,0,0,0,0,0,0,0,0,0,0,0,0,0,0,DA54,0,0,0,0,0,0,0,0)~
';BIDI;
    'RSVD'<48>:'(0,0,0,0,0,0,0,0,0,0,0,0,0,0,0,0,0,0,0,0,0,DA56,0,0,0,0,0,0,0,0)~
';BIDI;
    'RSVD'<47>:'(0,0,0,0,0,0,0,0,0,0,0,0,0,0,0,0,0,0,0,0,0,DC46,0,0,0,0,0,0,0,0)~
';BIDI;
    'RSVD'<46>:'(0,0,0,0,0,0,0,0,0,0,0,0,0,0,0,0,0,0,0,0,0,DC52,0,0,0,0,0,0,0,0)~
';BIDI;
    'RSVD'<45>:'(0,0,0,0,0,0,0,0,0,0,0,0,0,0,0,0,0,0,0,0,0,DD51,0,0,0,0,0,0,0,0)~
';BIDI;
    'RSVD'<44>:'(0,0,0,0,0,0,0,0,0,0,0,0,0,0,0,0,0,0,0,0,0,DG36,0,0,0,0,0,0,0,0)~
';BIDI;
    'RSVD'<43>:'(0,0,0,0,0,0,0,0,0,0,0,0,0,0,0,0,0,0,0,0,0,DG64,0,0,0,0,0,0,0,0)~
';BIDI;
    'RSVD'<42>:'(0,0,0,0,0,0,0,0,0,0,0,0,0,0,0,0,0,0,0,0,0,DH65,0,0,0,0,0,0,0,0)~
';BIDI;
    'RSVD'<41>:'(0,0,0,0,0,0,0,0,0,0,0,0,0,0,0,0,0,0,0,0,0,DJ36,0,0,0,0,0,0,0,0)~
';BIDI;
    'RSVD'<40>:'(0,0,0,0,0,0,0,0,0,0,0,0,0,0,0,0,0,0,0,0,0,DJ66,0,0,0,0,0,0,0,0)~
';BIDI;
    'RSVD'<39>:'(0,0,0,0,0,0,0,0,0,0,0,0,0,0,0,0,0,0,0,0,0,DK15,0,0,0,0,0,0,0,0)~
';BIDI;
    'RSVD'<38>:'(0,0,0,0,0,0,0,0,0,0,0,0,0,0,0,0,0,0,0,0,0,DK37,0,0,0,0,0,0,0,0)~
';BIDI;
    'RSVD'<37>:'(0,0,0,0,0,0,0,0,0,0,0,0,0,0,0,0,0,0,0,0,0,DK65,0,0,0,0,0,0,0,0)~
';BIDI;
    'RSVD'<36>:'(0,0,0,0,0,0,0,0,0,0,0,0,0,0,0,0,0,0,0,0,0,DK67,0,0,0,0,0,0,0,0)~
';BIDI;
    'RSVD'<35>:'(0,0,0,0,0,0,0,0,0,0,0,0,0,0,0,0,0,0,0,0,0,DL38,0,0,0,0,0,0,0,0)~
';BIDI;
    'RSVD'<34>:'(0,0,0,0,0,0,0,0,0,0,0,0,0,0,0,0,0,0,0,0,0,DL66,0,0,0,0,0,0,0,0)~
';BIDI;
    'RSVD'<33>:'(0,0,0,0,0,0,0,0,0,0,0,0,0,0,0,0,0,0,0,0,0,DM67,0,0,0,0,0,0,0,0)~
';BIDI;
    'RSVD'<32>:'(0,0,0,0,0,0,0,0,0,0,0,0,0,0,0,0,0,0,0,0,0,DN62,0,0,0,0,0,0,0,0)~
';BIDI;
    'RSVD'<31>:'(0,0,0,0,0,0,0,0,0,0,0,0,0,0,0,0,0,0,0,0,0,DN66,0,0,0,0,0,0,0,0)~
';BIDI;
    'RSVD'<30>:'(0,0,0,0,0,0,0,0,0,0,0,0,0,0,0,0,0,0,0,0,0,DP17,0,0,0,0,0,0,0,0)~
';BIDI;
    'RSVD'<29>:'(0,0,0,0,0,0,0,0,0,0,0,0,0,0,0,0,0,0,0,0,0,DP65,0,0,0,0,0,0,0,0)~
';BIDI;
    'RSVD'<28>:'(0,0,0,0,0,0,0,0,0,0,0,0,0,0,0,0,0,0,0,0,0,DR44,0,0,0,0,0,0,0,0)~
';BIDI;
    'RSVD'<27>:'(0,0,0,0,0,0,0,0,0,0,0,0,0,0,0,0,0,0,0,0,0,DT71,0,0,0,0,0,0,0,0)~
';BIDI;
    'RSVD'<26>:'(0,0,0,0,0,0,0,0,0,0,0,0,0,0,0,0,0,0,0,0,0,DU44,0,0,0,0,0,0,0,0)~
';BIDI;
    'RSVD'<25>:'(0,0,0,0,0,0,0,0,0,0,0,0,0,0,0,0,0,0,0,0,0,DV61,0,0,0,0,0,0,0,0)~
';BIDI;
    'RSVD'<24>:'(0,0,0,0,0,0,0,0,0,0,0,0,0,0,0,0,0,0,0,0,0,DV71,0,0,0,0,0,0,0,0)~
';BIDI;
    'RSVD'<23>:'(0,0,0,0,0,0,0,0,0,0,0,0,0,0,0,0,0,0,0,0,0,DW44,0,0,0,0,0,0,0,0)~
';BIDI;
    'RSVD'<22>:'(0,0,0,0,0,0,0,0,0,0,0,0,0,0,0,0,0,0,0,0,0,DW46,0,0,0,0,0,0,0,0)~
';BIDI;
    'RSVD'<21>:'(0,0,0,0,0,0,0,0,0,0,0,0,0,0,0,0,0,0,0,0,0,DY3,0,0,0,0,0,0,0,0)';BIDI;
    'RSVD'<20>:'(0,0,0,0,0,0,0,0,0,0,0,0,0,0,0,0,0,0,0,0,0,EA4,0,0,0,0,0,0,0,0)';BIDI;
    'RSVD'<19>:'(0,0,0,0,0,0,0,0,0,0,0,0,0,0,0,0,0,0,0,0,0,EA44,0,0,0,0,0,0,0,0)~
';BIDI;
    'RSVD'<18>:'(0,0,0,0,0,0,0,0,0,0,0,0,0,0,0,0,0,0,0,0,0,EB3,0,0,0,0,0,0,0,0)';BIDI;
    'RSVD'<17>:'(0,0,0,0,0,0,0,0,0,0,0,0,0,0,0,0,0,0,0,0,0,EB5,0,0,0,0,0,0,0,0)';BIDI;
    'RSVD'<16>:'(0,0,0,0,0,0,0,0,0,0,0,0,0,0,0,0,0,0,0,0,0,EB85,0,0,0,0,0,0,0,0)~
';BIDI;
    'RSVD'<15>:'(0,0,0,0,0,0,0,0,0,0,0,0,0,0,0,0,0,0,0,0,0,EC16,0,0,0,0,0,0,0,0)~
';BIDI;
    'RSVD'<14>:'(0,0,0,0,0,0,0,0,0,0,0,0,0,0,0,0,0,0,0,0,0,EC4,0,0,0,0,0,0,0,0)';BIDI;
    'RSVD'<13>:'(0,0,0,0,0,0,0,0,0,0,0,0,0,0,0,0,0,0,0,0,0,EC44,0,0,0,0,0,0,0,0)~
';BIDI;
    'RSVD'<12>:'(0,0,0,0,0,0,0,0,0,0,0,0,0,0,0,0,0,0,0,0,0,EC84,0,0,0,0,0,0,0,0)~
';BIDI;
    'RSVD'<11>:'(0,0,0,0,0,0,0,0,0,0,0,0,0,0,0,0,0,0,0,0,0,ED45,0,0,0,0,0,0,0,0)~
';BIDI;
    'RSVD'<10>:'(0,0,0,0,0,0,0,0,0,0,0,0,0,0,0,0,0,0,0,0,0,ED5,0,0,0,0,0,0,0,0)';BIDI;
    'RSVD'<9>:'(0,0,0,0,0,0,0,0,0,0,0,0,0,0,0,0,0,0,0,0,0,ED83,0,0,0,0,0,0,0,0)';BIDI;
    'RSVD'<8>:'(0,0,0,0,0,0,0,0,0,0,0,0,0,0,0,0,0,0,0,0,0,EE16,0,0,0,0,0,0,0,0)';BIDI;
    'RSVD'<7>:'(0,0,0,0,0,0,0,0,0,0,0,0,0,0,0,0,0,0,0,0,0,EE46,0,0,0,0,0,0,0,0)';BIDI;
    'RSVD'<6>:'(0,0,0,0,0,0,0,0,0,0,0,0,0,0,0,0,0,0,0,0,0,EE6,0,0,0,0,0,0,0,0)';~
BIDI;
    'RSVD'<5>:'(0,0,0,0,0,0,0,0,0,0,0,0,0,0,0,0,0,0,0,0,0,EE82,0,0,0,0,0,0,0,0)';BIDI;
    'RSVD'<4>:'(0,0,0,0,0,0,0,0,0,0,0,0,0,0,0,0,0,0,0,0,0,EE84,0,0,0,0,0,0,0,0)';BIDI;
    'RSVD'<3>:'(0,0,0,0,0,0,0,0,0,0,0,0,0,0,0,0,0,0,0,0,0,EF47,0,0,0,0,0,0,0,0)';BIDI;
    'RSVD'<2>:'(0,0,0,0,0,0,0,0,0,0,0,0,0,0,0,0,0,0,0,0,0,EF77,0,0,0,0,0,0,0,0)';BIDI;
    'RSVD'<1>:'(0,0,0,0,0,0,0,0,0,0,0,0,0,0,0,0,0,0,0,0,0,EF81,0,0,0,0,0,0,0,0)';BIDI;
    'RSVD'<0>:'(0,0,0,0,0,0,0,0,0,0,0,0,0,0,0,0,0,0,0,0,0,EF83,0,0,0,0,0,0,0,0)';BIDI;
    'SAFE_MODE_BOOT':'(AR18,0,0,0,0,0,0,0,0,0,0,0,0,0,0,0,0,0,0,0,0,0,0,0,0,0,0,~
0,0,0)';$S;IN;
    'SKTOCC_N':'(AB13,0,0,0,0,0,0,0,0,0,0,0,0,0,0,0,0,0,0,0,0,0,0,0,0,0,0,0,0,0)~
';$S;OUT;
    'SMBCLK':'(CT59,0,0,0,0,0,0,0,0,0,0,0,0,0,0,0,0,0,0,0,0,0,0,0,0,0,0,0,0,0)';~
$S;BIDI;
    'SMBDAT':'(CW58,0,0,0,0,0,0,0,0,0,0,0,0,0,0,0,0,0,0,0,0,0,0,0,0,0,0,0,0,0)';~
$S;BIDI;
    'SM_WP':'(CV59,0,0,0,0,0,0,0,0,0,0,0,0,0,0,0,0,0,0,0,0,0,0,0,0,0,0,0,0,0)';$~
S;IN;
    'SOCKET_ID'<2>:'(AU20,0,0,0,0,0,0,0,0,0,0,0,0,0,0,0,0,0,0,0,0,0,0,0,0,0,0,0,~
0,0)';IN;
    'SOCKET_ID'<1>:'(AU16,0,0,0,0,0,0,0,0,0,0,0,0,0,0,0,0,0,0,0,0,0,0,0,0,0,0,0,~
0,0)';IN;
    'SOCKET_ID'<0>:'(AU22,0,0,0,0,0,0,0,0,0,0,0,0,0,0,0,0,0,0,0,0,0,0,0,0,0,0,0,~
0,0)';IN;
    'SVIDALERT_N'<1>:'(DL44,0,0,0,0,0,0,0,0,0,0,0,0,0,0,0,0,0,0,0,0,0,0,0,0,0,0,~
0,0,0)';IN;
    'SVIDALERT_N'<0>:'(DE44,0,0,0,0,0,0,0,0,0,0,0,0,0,0,0,0,0,0,0,0,0,0,0,0,0,0,~
0,0,0)';IN;
    'SVIDCLK'<1>:'(DG44,0,0,0,0,0,0,0,0,0,0,0,0,0,0,0,0,0,0,0,0,0,0,0,0,0,0,0,0,~
0)';OUT;
    'SVIDCLK'<0>:'(DC44,0,0,0,0,0,0,0,0,0,0,0,0,0,0,0,0,0,0,0,0,0,0,0,0,0,0,0,0,~
0)';OUT;
    'SVIDDATA'<1>:'(DJ44,0,0,0,0,0,0,0,0,0,0,0,0,0,0,0,0,0,0,0,0,0,0,0,0,0,0,0,0~
,0)';BIDI;
    'SVIDDATA'<0>:'(DB45,0,0,0,0,0,0,0,0,0,0,0,0,0,0,0,0,0,0,0,0,0,0,0,0,0,0,0,0~
,0)';BIDI;
    'TCK':'(AA14,0,0,0,0,0,0,0,0,0,0,0,0,0,0,0,0,0,0,0,0,0,0,0,0,0,0,0,0,0)';$S;~
IN;
    'TDI':'(AC14,0,0,0,0,0,0,0,0,0,0,0,0,0,0,0,0,0,0,0,0,0,0,0,0,0,0,0,0,0)';$S;~
IN;
    'TDO':'(AE14,0,0,0,0,0,0,0,0,0,0,0,0,0,0,0,0,0,0,0,0,0,0,0,0,0,0,0,0,0)';$S;~
OUT;
    'TEST_1':'(0,AF45,0,0,0,0,0,0,0,0,0,0,0,0,0,0,0,0,0,0,0,0,0,0,0,0,0,0,0,0)';~
$S;BIDI;
    'TEST_10':'(0,0,0,0,0,0,0,0,0,0,0,0,0,0,0,0,AW22,0,0,0,0,0,0,0,0,0,0,0,0,0)';$S;BIDI;
    'TEST_11':'(0,AY13,0,0,0,0,0,0,0,0,0,0,0,0,0,0,0,0,0,0,0,0,0,0,0,0,0,0,0,0)';$S;BIDI;
    'TEST_12':'(AY19,0,0,0,0,0,0,0,0,0,0,0,0,0,0,0,0,0,0,0,0,0,0,0,0,0,0,0,0,0)';$S;BIDI;
    'TEST_13':'(DB51,0,0,0,0,0,0,0,0,0,0,0,0,0,0,0,0,0,0,0,0,0,0,0,0,0,0,0,0,0)';$S;BIDI;
    'TEST_14':'(DC50,0,0,0,0,0,0,0,0,0,0,0,0,0,0,0,0,0,0,0,0,0,0,0,0,0,0,0,0,0)';$S;BIDI;
    'TEST_15':'(AW14,0,0,0,0,0,0,0,0,0,0,0,0,0,0,0,0,0,0,0,0,0,0,0,0,0,0,0,0,0)';$S;BIDI;
    'TEST_2':'(0,AG46,0,0,0,0,0,0,0,0,0,0,0,0,0,0,0,0,0,0,0,0,0,0,0,0,0,0,0,0)';~
$S;BIDI;
    'TEST_3':'(0,AM13,0,0,0,0,0,0,0,0,0,0,0,0,0,0,0,0,0,0,0,0,0,0,0,0,0,0,0,0)';~
$S;BIDI;
    'TEST_4':'(0,AN12,0,0,0,0,0,0,0,0,0,0,0,0,0,0,0,0,0,0,0,0,0,0,0,0,0,0,0,0)';~
$S;BIDI;
    'TEST_5':'(0,AN14,0,0,0,0,0,0,0,0,0,0,0,0,0,0,0,0,0,0,0,0,0,0,0,0,0,0,0,0)';~
$S;BIDI;
    'TEST_6':'(0,0,0,0,0,0,0,0,0,0,0,0,0,0,0,0,AR16,0,0,0,0,0,0,0,0,0,0,0,0,0)';~
$S;BIDI;
    'TEST_7':'(0,0,0,0,0,0,0,0,0,0,0,0,0,0,0,0,AU18,0,0,0,0,0,0,0,0,0,0,0,0,0)';~
$S;BIDI;
    'TEST_8':'(0,0,0,0,0,0,0,0,0,0,0,0,0,0,0,0,AW16,0,0,0,0,0,0,0,0,0,0,0,0,0)';~
$S;BIDI;
    'TEST_9':'(0,0,0,0,0,0,0,0,0,0,0,0,0,0,0,0,AW20,0,0,0,0,0,0,0,0,0,0,0,0,0)';~
$S;BIDI;
    'THERMTRIP_N':'(AB15,0,0,0,0,0,0,0,0,0,0,0,0,0,0,0,0,0,0,0,0,0,0,0,0,0,0,0,0~
,0)';$S;OUT;
    'TMS':'(W14,0,0,0,0,0,0,0,0,0,0,0,0,0,0,0,0,0,0,0,0,0,0,0,0,0,0,0,0,0)';$S;I~
N;
    'TRST_N':'(Y13,0,0,0,0,0,0,0,0,0,0,0,0,0,0,0,0,0,0,0,0,0,0,0,0,0,0,0,0,0)';$~
S;IN;
    'TSC_SYNC':'(AM11,0,0,0,0,0,0,0,0,0,0,0,0,0,0,0,0,0,0,0,0,0,0,0,0,0,0,0,0,0)~
';$S;BIDI;
    'TXT_AGENT':'(AW18,0,0,0,0,0,0,0,0,0,0,0,0,0,0,0,0,0,0,0,0,0,0,0,0,0,0,0,0,0~
)';$S;IN;
    'TXT_PLTEN':'(AV15,0,0,0,0,0,0,0,0,0,0,0,0,0,0,0,0,0,0,0,0,0,0,0,0,0,0,0,0,0~
)';$S;IN;
    'UPI01_RBIAS'<1>:'(AP29,0,0,0,0,0,0,0,0,0,0,0,0,0,0,0,0,0,0,0,0,0,0,0,0,0,0,~
0,0,0)';IN;
    'UPI01_RBIAS'<0>:'(AT29,0,0,0,0,0,0,0,0,0,0,0,0,0,0,0,0,0,0,0,0,0,0,0,0,0,0,~
0,0,0)';IN;
    'UPI0_RX_DN'<19>:'(0,0,0,0,0,0,0,0,0,0,0,0,BB11,0,0,0,0,0,0,0,0,0,0,0,0,0,0,~
0,0,0)';IN;
    'UPI0_RX_DN'<18>:'(0,0,0,0,0,0,0,0,0,0,0,0,BD9,0,0,0,0,0,0,0,0,0,0,0,0,0,0,0~
,0,0)';IN;
    'UPI0_RX_DN'<17>:'(0,0,0,0,0,0,0,0,0,0,0,0,AY9,0,0,0,0,0,0,0,0,0,0,0,0,0,0,0~
,0,0)';IN;
    'UPI0_RX_DN'<16>:'(0,0,0,0,0,0,0,0,0,0,0,0,AW8,0,0,0,0,0,0,0,0,0,0,0,0,0,0,0~
,0,0)';IN;
    'UPI0_RX_DN'<15>:'(0,0,0,0,0,0,0,0,0,0,0,0,BD7,0,0,0,0,0,0,0,0,0,0,0,0,0,0,0~
,0,0)';IN;
    'UPI0_RX_DN'<14>:'(0,0,0,0,0,0,0,0,0,0,0,0,BC6,0,0,0,0,0,0,0,0,0,0,0,0,0,0,0~
,0,0)';IN;
    'UPI0_RX_DN'<13>:'(0,0,0,0,0,0,0,0,0,0,0,0,BA8,0,0,0,0,0,0,0,0,0,0,0,0,0,0,0~
,0,0)';IN;
    'UPI0_RX_DN'<12>:'(0,0,0,0,0,0,0,0,0,0,0,0,AU10,0,0,0,0,0,0,0,0,0,0,0,0,0,0,~
0,0,0)';IN;
    'UPI0_RX_DN'<11>:'(0,0,0,0,0,0,0,0,0,0,0,0,AR8,0,0,0,0,0,0,0,0,0,0,0,0,0,0,0~
,0,0)';IN;
    'UPI0_RX_DN'<10>:'(0,0,0,0,0,0,0,0,0,0,0,0,AP7,0,0,0,0,0,0,0,0,0,0,0,0,0,0,0~
,0,0)';IN;
    'UPI0_RX_DN'<9>:'(0,0,0,0,0,0,0,0,0,0,0,0,AM9,0,0,0,0,0,0,0,0,0,0,0,0,0,0,0,~
0,0)';IN;
    'UPI0_RX_DN'<8>:'(0,0,0,0,0,0,0,0,0,0,0,0,AK7,0,0,0,0,0,0,0,0,0,0,0,0,0,0,0,~
0,0)';IN;
    'UPI0_RX_DN'<7>:'(0,0,0,0,0,0,0,0,0,0,0,0,AL6,0,0,0,0,0,0,0,0,0,0,0,0,0,0,0,~
0,0)';IN;
    'UPI0_RX_DN'<6>:'(0,0,0,0,0,0,0,0,0,0,0,0,AJ6,0,0,0,0,0,0,0,0,0,0,0,0,0,0,0,~
0,0)';IN;
    'UPI0_RX_DN'<5>:'(0,0,0,0,0,0,0,0,0,0,0,0,AG8,0,0,0,0,0,0,0,0,0,0,0,0,0,0,0,~
0,0)';IN;
    'UPI0_RX_DN'<4>:'(0,0,0,0,0,0,0,0,0,0,0,0,AE6,0,0,0,0,0,0,0,0,0,0,0,0,0,0,0,~
0,0)';IN;
    'UPI0_RX_DN'<3>:'(0,0,0,0,0,0,0,0,0,0,0,0,AD5,0,0,0,0,0,0,0,0,0,0,0,0,0,0,0,~
0,0)';IN;
    'UPI0_RX_DN'<2>:'(0,0,0,0,0,0,0,0,0,0,0,0,AB7,0,0,0,0,0,0,0,0,0,0,0,0,0,0,0,~
0,0)';IN;
    'UPI0_RX_DN'<1>:'(0,0,0,0,0,0,0,0,0,0,0,0,AA8,0,0,0,0,0,0,0,0,0,0,0,0,0,0,0,~
0,0)';IN;
    'UPI0_RX_DN'<0>:'(0,0,0,0,0,0,0,0,0,0,0,0,AC10,0,0,0,0,0,0,0,0,0,0,0,0,0,0,0~
,0,0)';IN;
    'UPI0_RX_DP'<19>:'(0,0,0,0,0,0,0,0,0,0,0,0,BA10,0,0,0,0,0,0,0,0,0,0,0,0,0,0,~
0,0,0)';IN;
    'UPI0_RX_DP'<18>:'(0,0,0,0,0,0,0,0,0,0,0,0,BC10,0,0,0,0,0,0,0,0,0,0,0,0,0,0,~
0,0,0)';IN;
    'UPI0_RX_DP'<17>:'(0,0,0,0,0,0,0,0,0,0,0,0,BB9,0,0,0,0,0,0,0,0,0,0,0,0,0,0,0~
,0,0)';IN;
    'UPI0_RX_DP'<16>:'(0,0,0,0,0,0,0,0,0,0,0,0,AV9,0,0,0,0,0,0,0,0,0,0,0,0,0,0,0~
,0,0)';IN;
    'UPI0_RX_DP'<15>:'(0,0,0,0,0,0,0,0,0,0,0,0,BF7,0,0,0,0,0,0,0,0,0,0,0,0,0,0,0~
,0,0)';IN;
    'UPI0_RX_DP'<14>:'(0,0,0,0,0,0,0,0,0,0,0,0,BB7,0,0,0,0,0,0,0,0,0,0,0,0,0,0,0~
,0,0)';IN;
    'UPI0_RX_DP'<13>:'(0,0,0,0,0,0,0,0,0,0,0,0,AY7,0,0,0,0,0,0,0,0,0,0,0,0,0,0,0~
,0,0)';IN;
    'UPI0_RX_DP'<12>:'(0,0,0,0,0,0,0,0,0,0,0,0,AT9,0,0,0,0,0,0,0,0,0,0,0,0,0,0,0~
,0,0)';IN;
    'UPI0_RX_DP'<11>:'(0,0,0,0,0,0,0,0,0,0,0,0,AU8,0,0,0,0,0,0,0,0,0,0,0,0,0,0,0~
,0,0)';IN;
    'UPI0_RX_DP'<10>:'(0,0,0,0,0,0,0,0,0,0,0,0,AN8,0,0,0,0,0,0,0,0,0,0,0,0,0,0,0~
,0,0)';IN;
    'UPI0_RX_DP'<9>:'(0,0,0,0,0,0,0,0,0,0,0,0,AL8,0,0,0,0,0,0,0,0,0,0,0,0,0,0,0,~
0,0)';IN;
    'UPI0_RX_DP'<8>:'(0,0,0,0,0,0,0,0,0,0,0,0,AM7,0,0,0,0,0,0,0,0,0,0,0,0,0,0,0,~
0,0)';IN;
    'UPI0_RX_DP'<7>:'(0,0,0,0,0,0,0,0,0,0,0,0,AK5,0,0,0,0,0,0,0,0,0,0,0,0,0,0,0,~
0,0)';IN;
    'UPI0_RX_DP'<6>:'(0,0,0,0,0,0,0,0,0,0,0,0,AH7,0,0,0,0,0,0,0,0,0,0,0,0,0,0,0,~
0,0)';IN;
    'UPI0_RX_DP'<5>:'(0,0,0,0,0,0,0,0,0,0,0,0,AF7,0,0,0,0,0,0,0,0,0,0,0,0,0,0,0,~
0,0)';IN;
    'UPI0_RX_DP'<4>:'(0,0,0,0,0,0,0,0,0,0,0,0,AG6,0,0,0,0,0,0,0,0,0,0,0,0,0,0,0,~
0,0)';IN;
    'UPI0_RX_DP'<3>:'(0,0,0,0,0,0,0,0,0,0,0,0,AC6,0,0,0,0,0,0,0,0,0,0,0,0,0,0,0,~
0,0)';IN;
    'UPI0_RX_DP'<2>:'(0,0,0,0,0,0,0,0,0,0,0,0,AA6,0,0,0,0,0,0,0,0,0,0,0,0,0,0,0,~
0,0)';IN;
    'UPI0_RX_DP'<1>:'(0,0,0,0,0,0,0,0,0,0,0,0,AC8,0,0,0,0,0,0,0,0,0,0,0,0,0,0,0,~
0,0)';IN;
    'UPI0_RX_DP'<0>:'(0,0,0,0,0,0,0,0,0,0,0,0,AB9,0,0,0,0,0,0,0,0,0,0,0,0,0,0,0,~
0,0)';IN;
    'UPI0_TX_DN'<19>:'(0,0,0,0,0,0,0,0,0,0,0,0,BG4,0,0,0,0,0,0,0,0,0,0,0,0,0,0,0~
,0,0)';OUT;
    'UPI0_TX_DN'<18>:'(0,0,0,0,0,0,0,0,0,0,0,0,BF3,0,0,0,0,0,0,0,0,0,0,0,0,0,0,0~
,0,0)';OUT;
    'UPI0_TX_DN'<17>:'(0,0,0,0,0,0,0,0,0,0,0,0,BB3,0,0,0,0,0,0,0,0,0,0,0,0,0,0,0~
,0,0)';OUT;
    'UPI0_TX_DN'<16>:'(0,0,0,0,0,0,0,0,0,0,0,0,BA4,0,0,0,0,0,0,0,0,0,0,0,0,0,0,0~
,0,0)';OUT;
    'UPI0_TX_DN'<15>:'(0,0,0,0,0,0,0,0,0,0,0,0,AV5,0,0,0,0,0,0,0,0,0,0,0,0,0,0,0~
,0,0)';OUT;
    'UPI0_TX_DN'<14>:'(0,0,0,0,0,0,0,0,0,0,0,0,AU4,0,0,0,0,0,0,0,0,0,0,0,0,0,0,0~
,0,0)';OUT;
    'UPI0_TX_DN'<13>:'(0,0,0,0,0,0,0,0,0,0,0,0,AT3,0,0,0,0,0,0,0,0,0,0,0,0,0,0,0~
,0,0)';OUT;
    'UPI0_TX_DN'<12>:'(0,0,0,0,0,0,0,0,0,0,0,0,AT1,0,0,0,0,0,0,0,0,0,0,0,0,0,0,0~
,0,0)';OUT;
    'UPI0_TX_DN'<11>:'(0,0,0,0,0,0,0,0,0,0,0,0,AN4,0,0,0,0,0,0,0,0,0,0,0,0,0,0,0~
,0,0)';OUT;
    'UPI0_TX_DN'<10>:'(0,0,0,0,0,0,0,0,0,0,0,0,AM3,0,0,0,0,0,0,0,0,0,0,0,0,0,0,0~
,0,0)';OUT;
    'UPI0_TX_DN'<9>:'(0,0,0,0,0,0,0,0,0,0,0,0,AL2,0,0,0,0,0,0,0,0,0,0,0,0,0,0,0,~
0,0)';OUT;
    'UPI0_TX_DN'<8>:'(0,0,0,0,0,0,0,0,0,0,0,0,AH3,0,0,0,0,0,0,0,0,0,0,0,0,0,0,0,~
0,0)';OUT;
    'UPI0_TX_DN'<7>:'(0,0,0,0,0,0,0,0,0,0,0,0,AE2,0,0,0,0,0,0,0,0,0,0,0,0,0,0,0,~
0,0)';OUT;
    'UPI0_TX_DN'<6>:'(0,0,0,0,0,0,0,0,0,0,0,0,AG4,0,0,0,0,0,0,0,0,0,0,0,0,0,0,0,~
0,0)';OUT;
    'UPI0_TX_DN'<5>:'(0,0,0,0,0,0,0,0,0,0,0,0,AC2,0,0,0,0,0,0,0,0,0,0,0,0,0,0,0,~
0,0)';OUT;
    'UPI0_TX_DN'<4>:'(0,0,0,0,0,0,0,0,0,0,0,0,AB3,0,0,0,0,0,0,0,0,0,0,0,0,0,0,0,~
0,0)';OUT;
    'UPI0_TX_DN'<3>:'(0,0,0,0,0,0,0,0,0,0,0,0,Y1,0,0,0,0,0,0,0,0,0,0,0,0,0,0,0,0~
,0)';OUT;
    'UPI0_TX_DN'<2>:'(0,0,0,0,0,0,0,0,0,0,0,0,V3,0,0,0,0,0,0,0,0,0,0,0,0,0,0,0,0~
,0)';OUT;
    'UPI0_TX_DN'<1>:'(0,0,0,0,0,0,0,0,0,0,0,0,P1,0,0,0,0,0,0,0,0,0,0,0,0,0,0,0,0~
,0)';OUT;
    'UPI0_TX_DN'<0>:'(0,0,0,0,0,0,0,0,0,0,0,0,N2,0,0,0,0,0,0,0,0,0,0,0,0,0,0,0,0~
,0)';OUT;
    'UPI0_TX_DP'<19>:'(0,0,0,0,0,0,0,0,0,0,0,0,BH3,0,0,0,0,0,0,0,0,0,0,0,0,0,0,0~
,0,0)';OUT;
    'UPI0_TX_DP'<18>:'(0,0,0,0,0,0,0,0,0,0,0,0,BD3,0,0,0,0,0,0,0,0,0,0,0,0,0,0,0~
,0,0)';OUT;
    'UPI0_TX_DP'<17>:'(0,0,0,0,0,0,0,0,0,0,0,0,BC2,0,0,0,0,0,0,0,0,0,0,0,0,0,0,0~
,0,0)';OUT;
    'UPI0_TX_DP'<16>:'(0,0,0,0,0,0,0,0,0,0,0,0,AY3,0,0,0,0,0,0,0,0,0,0,0,0,0,0,0~
,0,0)';OUT;
    'UPI0_TX_DP'<15>:'(0,0,0,0,0,0,0,0,0,0,0,0,AW4,0,0,0,0,0,0,0,0,0,0,0,0,0,0,0~
,0,0)';OUT;
    'UPI0_TX_DP'<14>:'(0,0,0,0,0,0,0,0,0,0,0,0,AR4,0,0,0,0,0,0,0,0,0,0,0,0,0,0,0~
,0,0)';OUT;
    'UPI0_TX_DP'<13>:'(0,0,0,0,0,0,0,0,0,0,0,0,AR2,0,0,0,0,0,0,0,0,0,0,0,0,0,0,0~
,0,0)';OUT;
    'UPI0_TX_DP'<12>:'(0,0,0,0,0,0,0,0,0,0,0,0,AP1,0,0,0,0,0,0,0,0,0,0,0,0,0,0,0~
,0,0)';OUT;
    'UPI0_TX_DP'<11>:'(0,0,0,0,0,0,0,0,0,0,0,0,AP3,0,0,0,0,0,0,0,0,0,0,0,0,0,0,0~
,0,0)';OUT;
    'UPI0_TX_DP'<10>:'(0,0,0,0,0,0,0,0,0,0,0,0,AK3,0,0,0,0,0,0,0,0,0,0,0,0,0,0,0~
,0,0)';OUT;
    'UPI0_TX_DP'<9>:'(0,0,0,0,0,0,0,0,0,0,0,0,AK1,0,0,0,0,0,0,0,0,0,0,0,0,0,0,0,~
0,0)';OUT;
    'UPI0_TX_DP'<8>:'(0,0,0,0,0,0,0,0,0,0,0,0,AJ2,0,0,0,0,0,0,0,0,0,0,0,0,0,0,0,~
0,0)';OUT;
    'UPI0_TX_DP'<7>:'(0,0,0,0,0,0,0,0,0,0,0,0,AG2,0,0,0,0,0,0,0,0,0,0,0,0,0,0,0,~
0,0)';OUT;
    'UPI0_TX_DP'<6>:'(0,0,0,0,0,0,0,0,0,0,0,0,AF3,0,0,0,0,0,0,0,0,0,0,0,0,0,0,0,~
0,0)';OUT;
    'UPI0_TX_DP'<5>:'(0,0,0,0,0,0,0,0,0,0,0,0,AD1,0,0,0,0,0,0,0,0,0,0,0,0,0,0,0,~
0,0)';OUT;
    'UPI0_TX_DP'<4>:'(0,0,0,0,0,0,0,0,0,0,0,0,AA2,0,0,0,0,0,0,0,0,0,0,0,0,0,0,0,~
0,0)';OUT;
    'UPI0_TX_DP'<3>:'(0,0,0,0,0,0,0,0,0,0,0,0,W2,0,0,0,0,0,0,0,0,0,0,0,0,0,0,0,0~
,0)';OUT;
    'UPI0_TX_DP'<2>:'(0,0,0,0,0,0,0,0,0,0,0,0,Y3,0,0,0,0,0,0,0,0,0,0,0,0,0,0,0,0~
,0)';OUT;
    'UPI0_TX_DP'<1>:'(0,0,0,0,0,0,0,0,0,0,0,0,T1,0,0,0,0,0,0,0,0,0,0,0,0,0,0,0,0~
,0)';OUT;
    'UPI0_TX_DP'<0>:'(0,0,0,0,0,0,0,0,0,0,0,0,M1,0,0,0,0,0,0,0,0,0,0,0,0,0,0,0,0~
,0)';OUT;
    'UPI1_RX_DN'<19>:'(0,0,0,0,0,0,0,0,0,0,0,0,0,AB19,0,0,0,0,0,0,0,0,0,0,0,0,0,~
0,0,0)';IN;
    'UPI1_RX_DN'<18>:'(0,0,0,0,0,0,0,0,0,0,0,0,0,Y21,0,0,0,0,0,0,0,0,0,0,0,0,0,0~
,0,0)';IN;
    'UPI1_RX_DN'<17>:'(0,0,0,0,0,0,0,0,0,0,0,0,0,V19,0,0,0,0,0,0,0,0,0,0,0,0,0,0~
,0,0)';IN;
    'UPI1_RX_DN'<16>:'(0,0,0,0,0,0,0,0,0,0,0,0,0,P21,0,0,0,0,0,0,0,0,0,0,0,0,0,0~
,0,0)';IN;
    'UPI1_RX_DN'<15>:'(0,0,0,0,0,0,0,0,0,0,0,0,0,U18,0,0,0,0,0,0,0,0,0,0,0,0,0,0~
,0,0)';IN;
    'UPI1_RX_DN'<14>:'(0,0,0,0,0,0,0,0,0,0,0,0,0,R20,0,0,0,0,0,0,0,0,0,0,0,0,0,0~
,0,0)';IN;
    'UPI1_RX_DN'<13>:'(0,0,0,0,0,0,0,0,0,0,0,0,0,W18,0,0,0,0,0,0,0,0,0,0,0,0,0,0~
,0,0)';IN;
    'UPI1_RX_DN'<12>:'(0,0,0,0,0,0,0,0,0,0,0,0,0,U16,0,0,0,0,0,0,0,0,0,0,0,0,0,0~
,0,0)';IN;
    'UPI1_RX_DN'<11>:'(0,0,0,0,0,0,0,0,0,0,0,0,0,P17,0,0,0,0,0,0,0,0,0,0,0,0,0,0~
,0,0)';IN;
    'UPI1_RX_DN'<10>:'(0,0,0,0,0,0,0,0,0,0,0,0,0,R16,0,0,0,0,0,0,0,0,0,0,0,0,0,0~
,0,0)';IN;
    'UPI1_RX_DN'<9>:'(0,0,0,0,0,0,0,0,0,0,0,0,0,R12,0,0,0,0,0,0,0,0,0,0,0,0,0,0,~
0,0)';IN;
    'UPI1_RX_DN'<8>:'(0,0,0,0,0,0,0,0,0,0,0,0,0,N14,0,0,0,0,0,0,0,0,0,0,0,0,0,0,~
0,0)';IN;
    'UPI1_RX_DN'<7>:'(0,0,0,0,0,0,0,0,0,0,0,0,0,L12,0,0,0,0,0,0,0,0,0,0,0,0,0,0,~
0,0)';IN;
    'UPI1_RX_DN'<6>:'(0,0,0,0,0,0,0,0,0,0,0,0,0,U12,0,0,0,0,0,0,0,0,0,0,0,0,0,0,~
0,0)';IN;
    'UPI1_RX_DN'<5>:'(0,0,0,0,0,0,0,0,0,0,0,0,0,R10,0,0,0,0,0,0,0,0,0,0,0,0,0,0,~
0,0)';IN;
    'UPI1_RX_DN'<4>:'(0,0,0,0,0,0,0,0,0,0,0,0,0,P9,0,0,0,0,0,0,0,0,0,0,0,0,0,0,0~
,0)';IN;
    'UPI1_RX_DN'<3>:'(0,0,0,0,0,0,0,0,0,0,0,0,0,T9,0,0,0,0,0,0,0,0,0,0,0,0,0,0,0~
,0)';IN;
    'UPI1_RX_DN'<2>:'(0,0,0,0,0,0,0,0,0,0,0,0,0,V7,0,0,0,0,0,0,0,0,0,0,0,0,0,0,0~
,0)';IN;
    'UPI1_RX_DN'<1>:'(0,0,0,0,0,0,0,0,0,0,0,0,0,P7,0,0,0,0,0,0,0,0,0,0,0,0,0,0,0~
,0)';IN;
    'UPI1_RX_DN'<0>:'(0,0,0,0,0,0,0,0,0,0,0,0,0,T5,0,0,0,0,0,0,0,0,0,0,0,0,0,0,0~
,0)';IN;
    'UPI1_RX_DP'<19>:'(0,0,0,0,0,0,0,0,0,0,0,0,0,AA20,0,0,0,0,0,0,0,0,0,0,0,0,0,~
0,0,0)';IN;
    'UPI1_RX_DP'<18>:'(0,0,0,0,0,0,0,0,0,0,0,0,0,W20,0,0,0,0,0,0,0,0,0,0,0,0,0,0~
,0,0)';IN;
    'UPI1_RX_DP'<17>:'(0,0,0,0,0,0,0,0,0,0,0,0,0,Y19,0,0,0,0,0,0,0,0,0,0,0,0,0,0~
,0,0)';IN;
    'UPI1_RX_DP'<16>:'(0,0,0,0,0,0,0,0,0,0,0,0,0,T21,0,0,0,0,0,0,0,0,0,0,0,0,0,0~
,0,0)';IN;
    'UPI1_RX_DP'<15>:'(0,0,0,0,0,0,0,0,0,0,0,0,0,T19,0,0,0,0,0,0,0,0,0,0,0,0,0,0~
,0,0)';IN;
    'UPI1_RX_DP'<14>:'(0,0,0,0,0,0,0,0,0,0,0,0,0,P19,0,0,0,0,0,0,0,0,0,0,0,0,0,0~
,0,0)';IN;
    'UPI1_RX_DP'<13>:'(0,0,0,0,0,0,0,0,0,0,0,0,0,V17,0,0,0,0,0,0,0,0,0,0,0,0,0,0~
,0,0)';IN;
    'UPI1_RX_DP'<12>:'(0,0,0,0,0,0,0,0,0,0,0,0,0,W16,0,0,0,0,0,0,0,0,0,0,0,0,0,0~
,0,0)';IN;
    'UPI1_RX_DP'<11>:'(0,0,0,0,0,0,0,0,0,0,0,0,0,N16,0,0,0,0,0,0,0,0,0,0,0,0,0,0~
,0,0)';IN;
    'UPI1_RX_DP'<10>:'(0,0,0,0,0,0,0,0,0,0,0,0,0,T15,0,0,0,0,0,0,0,0,0,0,0,0,0,0~
,0,0)';IN;
    'UPI1_RX_DP'<9>:'(0,0,0,0,0,0,0,0,0,0,0,0,0,P13,0,0,0,0,0,0,0,0,0,0,0,0,0,0,~
0,0)';IN;
    'UPI1_RX_DP'<8>:'(0,0,0,0,0,0,0,0,0,0,0,0,0,M13,0,0,0,0,0,0,0,0,0,0,0,0,0,0,~
0,0)';IN;
    'UPI1_RX_DP'<7>:'(0,0,0,0,0,0,0,0,0,0,0,0,0,N12,0,0,0,0,0,0,0,0,0,0,0,0,0,0,~
0,0)';IN;
    'UPI1_RX_DP'<6>:'(0,0,0,0,0,0,0,0,0,0,0,0,0,T11,0,0,0,0,0,0,0,0,0,0,0,0,0,0,~
0,0)';IN;
    'UPI1_RX_DP'<5>:'(0,0,0,0,0,0,0,0,0,0,0,0,0,U10,0,0,0,0,0,0,0,0,0,0,0,0,0,0,~
0,0)';IN;
    'UPI1_RX_DP'<4>:'(0,0,0,0,0,0,0,0,0,0,0,0,0,N10,0,0,0,0,0,0,0,0,0,0,0,0,0,0,~
0,0)';IN;
    'UPI1_RX_DP'<3>:'(0,0,0,0,0,0,0,0,0,0,0,0,0,R8,0,0,0,0,0,0,0,0,0,0,0,0,0,0,0~
,0)';IN;
    'UPI1_RX_DP'<2>:'(0,0,0,0,0,0,0,0,0,0,0,0,0,U8,0,0,0,0,0,0,0,0,0,0,0,0,0,0,0~
,0)';IN;
    'UPI1_RX_DP'<1>:'(0,0,0,0,0,0,0,0,0,0,0,0,0,T7,0,0,0,0,0,0,0,0,0,0,0,0,0,0,0~
,0)';IN;
    'UPI1_RX_DP'<0>:'(0,0,0,0,0,0,0,0,0,0,0,0,0,R6,0,0,0,0,0,0,0,0,0,0,0,0,0,0,0~
,0)';IN;
    'UPI1_TX_DN'<19>:'(0,0,0,0,0,0,0,0,0,0,0,0,0,H21,0,0,0,0,0,0,0,0,0,0,0,0,0,0~
,0,0)';OUT;
    'UPI1_TX_DN'<18>:'(0,0,0,0,0,0,0,0,0,0,0,0,0,F21,0,0,0,0,0,0,0,0,0,0,0,0,0,0~
,0,0)';OUT;
    'UPI1_TX_DN'<17>:'(0,0,0,0,0,0,0,0,0,0,0,0,0,J20,0,0,0,0,0,0,0,0,0,0,0,0,0,0~
,0,0)';OUT;
    'UPI1_TX_DN'<16>:'(0,0,0,0,0,0,0,0,0,0,0,0,0,G18,0,0,0,0,0,0,0,0,0,0,0,0,0,0~
,0,0)';OUT;
    'UPI1_TX_DN'<15>:'(0,0,0,0,0,0,0,0,0,0,0,0,0,K19,0,0,0,0,0,0,0,0,0,0,0,0,0,0~
,0,0)';OUT;
    'UPI1_TX_DN'<14>:'(0,0,0,0,0,0,0,0,0,0,0,0,0,H17,0,0,0,0,0,0,0,0,0,0,0,0,0,0~
,0,0)';OUT;
    'UPI1_TX_DN'<13>:'(0,0,0,0,0,0,0,0,0,0,0,0,0,F15,0,0,0,0,0,0,0,0,0,0,0,0,0,0~
,0,0)';OUT;
    'UPI1_TX_DN'<12>:'(0,0,0,0,0,0,0,0,0,0,0,0,0,D15,0,0,0,0,0,0,0,0,0,0,0,0,0,0~
,0,0)';OUT;
    'UPI1_TX_DN'<11>:'(0,0,0,0,0,0,0,0,0,0,0,0,0,G14,0,0,0,0,0,0,0,0,0,0,0,0,0,0~
,0,0)';OUT;
    'UPI1_TX_DN'<10>:'(0,0,0,0,0,0,0,0,0,0,0,0,0,E12,0,0,0,0,0,0,0,0,0,0,0,0,0,0~
,0,0)';OUT;
    'UPI1_TX_DN'<9>:'(0,0,0,0,0,0,0,0,0,0,0,0,0,G10,0,0,0,0,0,0,0,0,0,0,0,0,0,0,~
0,0)';OUT;
    'UPI1_TX_DN'<8>:'(0,0,0,0,0,0,0,0,0,0,0,0,0,F11,0,0,0,0,0,0,0,0,0,0,0,0,0,0,~
0,0)';OUT;
    'UPI1_TX_DN'<7>:'(0,0,0,0,0,0,0,0,0,0,0,0,0,D9,0,0,0,0,0,0,0,0,0,0,0,0,0,0,0~
,0)';OUT;
    'UPI1_TX_DN'<6>:'(0,0,0,0,0,0,0,0,0,0,0,0,0,K9,0,0,0,0,0,0,0,0,0,0,0,0,0,0,0~
,0)';OUT;
    'UPI1_TX_DN'<5>:'(0,0,0,0,0,0,0,0,0,0,0,0,0,H7,0,0,0,0,0,0,0,0,0,0,0,0,0,0,0~
,0)';OUT;
    'UPI1_TX_DN'<4>:'(0,0,0,0,0,0,0,0,0,0,0,0,0,G6,0,0,0,0,0,0,0,0,0,0,0,0,0,0,0~
,0)';OUT;
    'UPI1_TX_DN'<3>:'(0,0,0,0,0,0,0,0,0,0,0,0,0,J6,0,0,0,0,0,0,0,0,0,0,0,0,0,0,0~
,0)';OUT;
    'UPI1_TX_DN'<2>:'(0,0,0,0,0,0,0,0,0,0,0,0,0,K5,0,0,0,0,0,0,0,0,0,0,0,0,0,0,0~
,0)';OUT;
    'UPI1_TX_DN'<1>:'(0,0,0,0,0,0,0,0,0,0,0,0,0,L4,0,0,0,0,0,0,0,0,0,0,0,0,0,0,0~
,0)';OUT;
    'UPI1_TX_DN'<0>:'(0,0,0,0,0,0,0,0,0,0,0,0,0,M3,0,0,0,0,0,0,0,0,0,0,0,0,0,0,0~
,0)';OUT;
    'UPI1_TX_DP'<19>:'(0,0,0,0,0,0,0,0,0,0,0,0,0,K21,0,0,0,0,0,0,0,0,0,0,0,0,0,0~
,0,0)';OUT;
    'UPI1_TX_DP'<18>:'(0,0,0,0,0,0,0,0,0,0,0,0,0,G20,0,0,0,0,0,0,0,0,0,0,0,0,0,0~
,0,0)';OUT;
    'UPI1_TX_DP'<17>:'(0,0,0,0,0,0,0,0,0,0,0,0,0,H19,0,0,0,0,0,0,0,0,0,0,0,0,0,0~
,0,0)';OUT;
    'UPI1_TX_DP'<16>:'(0,0,0,0,0,0,0,0,0,0,0,0,0,J18,0,0,0,0,0,0,0,0,0,0,0,0,0,0~
,0,0)';OUT;
    'UPI1_TX_DP'<15>:'(0,0,0,0,0,0,0,0,0,0,0,0,0,L18,0,0,0,0,0,0,0,0,0,0,0,0,0,0~
,0,0)';OUT;
    'UPI1_TX_DP'<14>:'(0,0,0,0,0,0,0,0,0,0,0,0,0,G16,0,0,0,0,0,0,0,0,0,0,0,0,0,0~
,0,0)';OUT;
    'UPI1_TX_DP'<13>:'(0,0,0,0,0,0,0,0,0,0,0,0,0,H15,0,0,0,0,0,0,0,0,0,0,0,0,0,0~
,0,0)';OUT;
    'UPI1_TX_DP'<12>:'(0,0,0,0,0,0,0,0,0,0,0,0,0,E14,0,0,0,0,0,0,0,0,0,0,0,0,0,0~
,0,0)';OUT;
    'UPI1_TX_DP'<11>:'(0,0,0,0,0,0,0,0,0,0,0,0,0,F13,0,0,0,0,0,0,0,0,0,0,0,0,0,0~
,0,0)';OUT;
    'UPI1_TX_DP'<10>:'(0,0,0,0,0,0,0,0,0,0,0,0,0,G12,0,0,0,0,0,0,0,0,0,0,0,0,0,0~
,0,0)';OUT;
    'UPI1_TX_DP'<9>:'(0,0,0,0,0,0,0,0,0,0,0,0,0,H9,0,0,0,0,0,0,0,0,0,0,0,0,0,0,0~
,0)';OUT;
    'UPI1_TX_DP'<8>:'(0,0,0,0,0,0,0,0,0,0,0,0,0,E10,0,0,0,0,0,0,0,0,0,0,0,0,0,0,~
0,0)';OUT;
    'UPI1_TX_DP'<7>:'(0,0,0,0,0,0,0,0,0,0,0,0,0,F9,0,0,0,0,0,0,0,0,0,0,0,0,0,0,0~
,0)';OUT;
    'UPI1_TX_DP'<6>:'(0,0,0,0,0,0,0,0,0,0,0,0,0,J8,0,0,0,0,0,0,0,0,0,0,0,0,0,0,0~
,0)';OUT;
    'UPI1_TX_DP'<5>:'(0,0,0,0,0,0,0,0,0,0,0,0,0,K7,0,0,0,0,0,0,0,0,0,0,0,0,0,0,0~
,0)';OUT;
    'UPI1_TX_DP'<4>:'(0,0,0,0,0,0,0,0,0,0,0,0,0,F7,0,0,0,0,0,0,0,0,0,0,0,0,0,0,0~
,0)';OUT;
    'UPI1_TX_DP'<3>:'(0,0,0,0,0,0,0,0,0,0,0,0,0,H5,0,0,0,0,0,0,0,0,0,0,0,0,0,0,0~
,0)';OUT;
    'UPI1_TX_DP'<2>:'(0,0,0,0,0,0,0,0,0,0,0,0,0,M5,0,0,0,0,0,0,0,0,0,0,0,0,0,0,0~
,0)';OUT;
    'UPI1_TX_DP'<1>:'(0,0,0,0,0,0,0,0,0,0,0,0,0,K3,0,0,0,0,0,0,0,0,0,0,0,0,0,0,0~
,0)';OUT;
    'UPI1_TX_DP'<0>:'(0,0,0,0,0,0,0,0,0,0,0,0,0,P3,0,0,0,0,0,0,0,0,0,0,0,0,0,0,0~
,0)';OUT;
    'UPI2_RBIAS'<1>:'(CK29,0,0,0,0,0,0,0,0,0,0,0,0,0,0,0,0,0,0,0,0,0,0,0,0,0,0,0~
,0,0)';IN;
    'UPI2_RBIAS'<0>:'(CL28,0,0,0,0,0,0,0,0,0,0,0,0,0,0,0,0,0,0,0,0,0,0,0,0,0,0,0~
,0,0)';IN;
    'UPI2_RX_DN'<19>:'(0,0,0,0,0,0,0,0,0,0,0,0,0,0,BY17,0,0,0,0,0,0,0,0,0,0,0,0,~
0,0,0)';IN;
    'UPI2_RX_DN'<18>:'(0,0,0,0,0,0,0,0,0,0,0,0,0,0,CB15,0,0,0,0,0,0,0,0,0,0,0,0,~
0,0,0)';IN;
    'UPI2_RX_DN'<17>:'(0,0,0,0,0,0,0,0,0,0,0,0,0,0,CF17,0,0,0,0,0,0,0,0,0,0,0,0,~
0,0,0)';IN;
    'UPI2_RX_DN'<16>:'(0,0,0,0,0,0,0,0,0,0,0,0,0,0,CD15,0,0,0,0,0,0,0,0,0,0,0,0,~
0,0,0)';IN;
    'UPI2_RX_DN'<15>:'(0,0,0,0,0,0,0,0,0,0,0,0,0,0,CE16,0,0,0,0,0,0,0,0,0,0,0,0,~
0,0,0)';IN;
    'UPI2_RX_DN'<14>:'(0,0,0,0,0,0,0,0,0,0,0,0,0,0,CH17,0,0,0,0,0,0,0,0,0,0,0,0,~
0,0,0)';IN;
    'UPI2_RX_DN'<13>:'(0,0,0,0,0,0,0,0,0,0,0,0,0,0,CJ18,0,0,0,0,0,0,0,0,0,0,0,0,~
0,0,0)';IN;
    'UPI2_RX_DN'<12>:'(0,0,0,0,0,0,0,0,0,0,0,0,0,0,CL16,0,0,0,0,0,0,0,0,0,0,0,0,~
0,0,0)';IN;
    'UPI2_RX_DN'<11>:'(0,0,0,0,0,0,0,0,0,0,0,0,0,0,CP21,0,0,0,0,0,0,0,0,0,0,0,0,~
0,0,0)';IN;
    'UPI2_RX_DN'<10>:'(0,0,0,0,0,0,0,0,0,0,0,0,0,0,CN20,0,0,0,0,0,0,0,0,0,0,0,0,~
0,0,0)';IN;
    'UPI2_RX_DN'<9>:'(0,0,0,0,0,0,0,0,0,0,0,0,0,0,CR18,0,0,0,0,0,0,0,0,0,0,0,0,0~
,0,0)';IN;
    'UPI2_RX_DN'<8>:'(0,0,0,0,0,0,0,0,0,0,0,0,0,0,CT21,0,0,0,0,0,0,0,0,0,0,0,0,0~
,0,0)';IN;
    'UPI2_RX_DN'<7>:'(0,0,0,0,0,0,0,0,0,0,0,0,0,0,CV19,0,0,0,0,0,0,0,0,0,0,0,0,0~
,0,0)';IN;
    'UPI2_RX_DN'<6>:'(0,0,0,0,0,0,0,0,0,0,0,0,0,0,CW20,0,0,0,0,0,0,0,0,0,0,0,0,0~
,0,0)';IN;
    'UPI2_RX_DN'<5>:'(0,0,0,0,0,0,0,0,0,0,0,0,0,0,DA20,0,0,0,0,0,0,0,0,0,0,0,0,0~
,0,0)';IN;
    'UPI2_RX_DN'<4>:'(0,0,0,0,0,0,0,0,0,0,0,0,0,0,DD19,0,0,0,0,0,0,0,0,0,0,0,0,0~
,0,0)';IN;
    'UPI2_RX_DN'<3>:'(0,0,0,0,0,0,0,0,0,0,0,0,0,0,DB21,0,0,0,0,0,0,0,0,0,0,0,0,0~
,0,0)';IN;
    'UPI2_RX_DN'<2>:'(0,0,0,0,0,0,0,0,0,0,0,0,0,0,DC22,0,0,0,0,0,0,0,0,0,0,0,0,0~
,0,0)';IN;
    'UPI2_RX_DN'<1>:'(0,0,0,0,0,0,0,0,0,0,0,0,0,0,DE22,0,0,0,0,0,0,0,0,0,0,0,0,0~
,0,0)';IN;
    'UPI2_RX_DN'<0>:'(0,0,0,0,0,0,0,0,0,0,0,0,0,0,DF23,0,0,0,0,0,0,0,0,0,0,0,0,0~
,0,0)';IN;
    'UPI2_RX_DP'<19>:'(0,0,0,0,0,0,0,0,0,0,0,0,0,0,CA16,0,0,0,0,0,0,0,0,0,0,0,0,~
0,0,0)';IN;
    'UPI2_RX_DP'<18>:'(0,0,0,0,0,0,0,0,0,0,0,0,0,0,BY15,0,0,0,0,0,0,0,0,0,0,0,0,~
0,0,0)';IN;
    'UPI2_RX_DP'<17>:'(0,0,0,0,0,0,0,0,0,0,0,0,0,0,CD17,0,0,0,0,0,0,0,0,0,0,0,0,~
0,0,0)';IN;
    'UPI2_RX_DP'<16>:'(0,0,0,0,0,0,0,0,0,0,0,0,0,0,CC14,0,0,0,0,0,0,0,0,0,0,0,0,~
0,0,0)';IN;
    'UPI2_RX_DP'<15>:'(0,0,0,0,0,0,0,0,0,0,0,0,0,0,CF15,0,0,0,0,0,0,0,0,0,0,0,0,~
0,0,0)';IN;
    'UPI2_RX_DP'<14>:'(0,0,0,0,0,0,0,0,0,0,0,0,0,0,CG16,0,0,0,0,0,0,0,0,0,0,0,0,~
0,0,0)';IN;
    'UPI2_RX_DP'<13>:'(0,0,0,0,0,0,0,0,0,0,0,0,0,0,CK17,0,0,0,0,0,0,0,0,0,0,0,0,~
0,0,0)';IN;
    'UPI2_RX_DP'<12>:'(0,0,0,0,0,0,0,0,0,0,0,0,0,0,CJ16,0,0,0,0,0,0,0,0,0,0,0,0,~
0,0,0)';IN;
    'UPI2_RX_DP'<11>:'(0,0,0,0,0,0,0,0,0,0,0,0,0,0,CM21,0,0,0,0,0,0,0,0,0,0,0,0,~
0,0,0)';IN;
    'UPI2_RX_DP'<10>:'(0,0,0,0,0,0,0,0,0,0,0,0,0,0,CP19,0,0,0,0,0,0,0,0,0,0,0,0,~
0,0,0)';IN;
    'UPI2_RX_DP'<9>:'(0,0,0,0,0,0,0,0,0,0,0,0,0,0,CN18,0,0,0,0,0,0,0,0,0,0,0,0,0~
,0,0)';IN;
    'UPI2_RX_DP'<8>:'(0,0,0,0,0,0,0,0,0,0,0,0,0,0,CR20,0,0,0,0,0,0,0,0,0,0,0,0,0~
,0,0)';IN;
    'UPI2_RX_DP'<7>:'(0,0,0,0,0,0,0,0,0,0,0,0,0,0,CW18,0,0,0,0,0,0,0,0,0,0,0,0,0~
,0,0)';IN;
    'UPI2_RX_DP'<6>:'(0,0,0,0,0,0,0,0,0,0,0,0,0,0,CU20,0,0,0,0,0,0,0,0,0,0,0,0,0~
,0,0)';IN;
    'UPI2_RX_DP'<5>:'(0,0,0,0,0,0,0,0,0,0,0,0,0,0,CY19,0,0,0,0,0,0,0,0,0,0,0,0,0~
,0,0)';IN;
    'UPI2_RX_DP'<4>:'(0,0,0,0,0,0,0,0,0,0,0,0,0,0,DB19,0,0,0,0,0,0,0,0,0,0,0,0,0~
,0,0)';IN;
    'UPI2_RX_DP'<3>:'(0,0,0,0,0,0,0,0,0,0,0,0,0,0,DC20,0,0,0,0,0,0,0,0,0,0,0,0,0~
,0,0)';IN;
    'UPI2_RX_DP'<2>:'(0,0,0,0,0,0,0,0,0,0,0,0,0,0,DA22,0,0,0,0,0,0,0,0,0,0,0,0,0~
,0,0)';IN;
    'UPI2_RX_DP'<1>:'(0,0,0,0,0,0,0,0,0,0,0,0,0,0,DD21,0,0,0,0,0,0,0,0,0,0,0,0,0~
,0,0)';IN;
    'UPI2_RX_DP'<0>:'(0,0,0,0,0,0,0,0,0,0,0,0,0,0,DG22,0,0,0,0,0,0,0,0,0,0,0,0,0~
,0,0)';IN;
    'UPI2_TX_DN'<19>:'(0,0,0,0,0,0,0,0,0,0,0,0,0,0,CC12,0,0,0,0,0,0,0,0,0,0,0,0,~
0,0,0)';OUT;
    'UPI2_TX_DN'<18>:'(0,0,0,0,0,0,0,0,0,0,0,0,0,0,CC10,0,0,0,0,0,0,0,0,0,0,0,0,~
0,0,0)';OUT;
    'UPI2_TX_DN'<17>:'(0,0,0,0,0,0,0,0,0,0,0,0,0,0,CE12,0,0,0,0,0,0,0,0,0,0,0,0,~
0,0,0)';OUT;
    'UPI2_TX_DN'<16>:'(0,0,0,0,0,0,0,0,0,0,0,0,0,0,CH11,0,0,0,0,0,0,0,0,0,0,0,0,~
0,0,0)';OUT;
    'UPI2_TX_DN'<15>:'(0,0,0,0,0,0,0,0,0,0,0,0,0,0,CF13,0,0,0,0,0,0,0,0,0,0,0,0,~
0,0,0)';OUT;
    'UPI2_TX_DN'<14>:'(0,0,0,0,0,0,0,0,0,0,0,0,0,0,CJ14,0,0,0,0,0,0,0,0,0,0,0,0,~
0,0,0)';OUT;
    'UPI2_TX_DN'<13>:'(0,0,0,0,0,0,0,0,0,0,0,0,0,0,CM13,0,0,0,0,0,0,0,0,0,0,0,0,~
0,0,0)';OUT;
    'UPI2_TX_DN'<12>:'(0,0,0,0,0,0,0,0,0,0,0,0,0,0,CU14,0,0,0,0,0,0,0,0,0,0,0,0,~
0,0,0)';OUT;
    'UPI2_TX_DN'<11>:'(0,0,0,0,0,0,0,0,0,0,0,0,0,0,CW14,0,0,0,0,0,0,0,0,0,0,0,0,~
0,0,0)';OUT;
    'UPI2_TX_DN'<10>:'(0,0,0,0,0,0,0,0,0,0,0,0,0,0,DA16,0,0,0,0,0,0,0,0,0,0,0,0,~
0,0,0)';OUT;
    'UPI2_TX_DN'<9>:'(0,0,0,0,0,0,0,0,0,0,0,0,0,0,DC16,0,0,0,0,0,0,0,0,0,0,0,0,0~
,0,0)';OUT;
    'UPI2_TX_DN'<8>:'(0,0,0,0,0,0,0,0,0,0,0,0,0,0,DF15,0,0,0,0,0,0,0,0,0,0,0,0,0~
,0,0)';OUT;
    'UPI2_TX_DN'<7>:'(0,0,0,0,0,0,0,0,0,0,0,0,0,0,DD17,0,0,0,0,0,0,0,0,0,0,0,0,0~
,0,0)';OUT;
    'UPI2_TX_DN'<6>:'(0,0,0,0,0,0,0,0,0,0,0,0,0,0,DG18,0,0,0,0,0,0,0,0,0,0,0,0,0~
,0,0)';OUT;
    'UPI2_TX_DN'<5>:'(0,0,0,0,0,0,0,0,0,0,0,0,0,0,DK17,0,0,0,0,0,0,0,0,0,0,0,0,0~
,0,0)';OUT;
    'UPI2_TX_DN'<4>:'(0,0,0,0,0,0,0,0,0,0,0,0,0,0,DH19,0,0,0,0,0,0,0,0,0,0,0,0,0~
,0,0)';OUT;
    'UPI2_TX_DN'<3>:'(0,0,0,0,0,0,0,0,0,0,0,0,0,0,DG20,0,0,0,0,0,0,0,0,0,0,0,0,0~
,0,0)';OUT;
    'UPI2_TX_DN'<2>:'(0,0,0,0,0,0,0,0,0,0,0,0,0,0,DL20,0,0,0,0,0,0,0,0,0,0,0,0,0~
,0,0)';OUT;
    'UPI2_TX_DN'<1>:'(0,0,0,0,0,0,0,0,0,0,0,0,0,0,DM21,0,0,0,0,0,0,0,0,0,0,0,0,0~
,0,0)';OUT;
    'UPI2_TX_DN'<0>:'(0,0,0,0,0,0,0,0,0,0,0,0,0,0,DT21,0,0,0,0,0,0,0,0,0,0,0,0,0~
,0,0)';OUT;
    'UPI2_TX_DP'<19>:'(0,0,0,0,0,0,0,0,0,0,0,0,0,0,CA12,0,0,0,0,0,0,0,0,0,0,0,0,~
0,0,0)';OUT;
    'UPI2_TX_DP'<18>:'(0,0,0,0,0,0,0,0,0,0,0,0,0,0,CB11,0,0,0,0,0,0,0,0,0,0,0,0,~
0,0,0)';OUT;
    'UPI2_TX_DP'<17>:'(0,0,0,0,0,0,0,0,0,0,0,0,0,0,CD11,0,0,0,0,0,0,0,0,0,0,0,0,~
0,0,0)';OUT;
    'UPI2_TX_DP'<16>:'(0,0,0,0,0,0,0,0,0,0,0,0,0,0,CF11,0,0,0,0,0,0,0,0,0,0,0,0,~
0,0,0)';OUT;
    'UPI2_TX_DP'<15>:'(0,0,0,0,0,0,0,0,0,0,0,0,0,0,CG12,0,0,0,0,0,0,0,0,0,0,0,0,~
0,0,0)';OUT;
    'UPI2_TX_DP'<14>:'(0,0,0,0,0,0,0,0,0,0,0,0,0,0,CH13,0,0,0,0,0,0,0,0,0,0,0,0,~
0,0,0)';OUT;
    'UPI2_TX_DP'<13>:'(0,0,0,0,0,0,0,0,0,0,0,0,0,0,CK13,0,0,0,0,0,0,0,0,0,0,0,0,~
0,0,0)';OUT;
    'UPI2_TX_DP'<12>:'(0,0,0,0,0,0,0,0,0,0,0,0,0,0,CR14,0,0,0,0,0,0,0,0,0,0,0,0,~
0,0,0)';OUT;
    'UPI2_TX_DP'<11>:'(0,0,0,0,0,0,0,0,0,0,0,0,0,0,CV13,0,0,0,0,0,0,0,0,0,0,0,0,~
0,0,0)';OUT;
    'UPI2_TX_DP'<10>:'(0,0,0,0,0,0,0,0,0,0,0,0,0,0,CW16,0,0,0,0,0,0,0,0,0,0,0,0,~
0,0,0)';OUT;
    'UPI2_TX_DP'<9>:'(0,0,0,0,0,0,0,0,0,0,0,0,0,0,DB15,0,0,0,0,0,0,0,0,0,0,0,0,0~
,0,0)';OUT;
    'UPI2_TX_DP'<8>:'(0,0,0,0,0,0,0,0,0,0,0,0,0,0,DD15,0,0,0,0,0,0,0,0,0,0,0,0,0~
,0,0)';OUT;
    'UPI2_TX_DP'<7>:'(0,0,0,0,0,0,0,0,0,0,0,0,0,0,DE16,0,0,0,0,0,0,0,0,0,0,0,0,0~
,0,0)';OUT;
    'UPI2_TX_DP'<6>:'(0,0,0,0,0,0,0,0,0,0,0,0,0,0,DF17,0,0,0,0,0,0,0,0,0,0,0,0,0~
,0,0)';OUT;
    'UPI2_TX_DP'<5>:'(0,0,0,0,0,0,0,0,0,0,0,0,0,0,DH17,0,0,0,0,0,0,0,0,0,0,0,0,0~
,0,0)';OUT;
    'UPI2_TX_DP'<4>:'(0,0,0,0,0,0,0,0,0,0,0,0,0,0,DJ18,0,0,0,0,0,0,0,0,0,0,0,0,0~
,0,0)';OUT;
    'UPI2_TX_DP'<3>:'(0,0,0,0,0,0,0,0,0,0,0,0,0,0,DJ20,0,0,0,0,0,0,0,0,0,0,0,0,0~
,0,0)';OUT;
    'UPI2_TX_DP'<2>:'(0,0,0,0,0,0,0,0,0,0,0,0,0,0,DK19,0,0,0,0,0,0,0,0,0,0,0,0,0~
,0,0)';OUT;
    'UPI2_TX_DP'<1>:'(0,0,0,0,0,0,0,0,0,0,0,0,0,0,DN20,0,0,0,0,0,0,0,0,0,0,0,0,0~
,0,0)';OUT;
    'UPI2_TX_DP'<0>:'(0,0,0,0,0,0,0,0,0,0,0,0,0,0,DP21,0,0,0,0,0,0,0,0,0,0,0,0,0~
,0,0)';OUT;
    'VCC33':'(0,0,0,0,0,0,0,0,0,0,0,0,0,0,0,0,0,0,0,0,CY55,0,0,0,0,0,0,0,0,0)';$~
S;
    'VCCD012'<51>:'(0,0,0,0,0,0,0,0,0,0,0,0,0,0,0,0,0,0,0,B47,0,0,0,0,0,0,0,0,0,~
0)';
    'VCCD012'<50>:'(0,0,0,0,0,0,0,0,0,0,0,0,0,0,0,0,0,0,0,C46,0,0,0,0,0,0,0,0,0,~
0)';
    'VCCD012'<49>:'(0,0,0,0,0,0,0,0,0,0,0,0,0,0,0,0,0,0,0,D45,0,0,0,0,0,0,0,0,0,~
0)';
    'VCCD012'<48>:'(0,0,0,0,0,0,0,0,0,0,0,0,0,0,0,0,0,0,0,AF63,0,0,0,0,0,0,0,0,0~
,0)';
    'VCCD012'<47>:'(0,0,0,0,0,0,0,0,0,0,0,0,0,0,0,0,0,0,0,AF61,0,0,0,0,0,0,0,0,0~
,0)';
    'VCCD012'<46>:'(0,0,0,0,0,0,0,0,0,0,0,0,0,0,0,0,0,0,0,AF59,0,0,0,0,0,0,0,0,0~
,0)';
    'VCCD012'<45>:'(0,0,0,0,0,0,0,0,0,0,0,0,0,0,0,0,0,0,0,AF57,0,0,0,0,0,0,0,0,0~
,0)';
    'VCCD012'<44>:'(0,0,0,0,0,0,0,0,0,0,0,0,0,0,0,0,0,0,0,AF55,0,0,0,0,0,0,0,0,0~
,0)';
    'VCCD012'<43>:'(0,0,0,0,0,0,0,0,0,0,0,0,0,0,0,0,0,0,0,AD45,0,0,0,0,0,0,0,0,0~
,0)';
    'VCCD012'<42>:'(0,0,0,0,0,0,0,0,0,0,0,0,0,0,0,0,0,0,0,Y63,0,0,0,0,0,0,0,0,0,~
0)';
    'VCCD012'<41>:'(0,0,0,0,0,0,0,0,0,0,0,0,0,0,0,0,0,0,0,Y61,0,0,0,0,0,0,0,0,0,~
0)';
    'VCCD012'<40>:'(0,0,0,0,0,0,0,0,0,0,0,0,0,0,0,0,0,0,0,Y59,0,0,0,0,0,0,0,0,0,~
0)';
    'VCCD012'<39>:'(0,0,0,0,0,0,0,0,0,0,0,0,0,0,0,0,0,0,0,Y57,0,0,0,0,0,0,0,0,0,~
0)';
    'VCCD012'<38>:'(0,0,0,0,0,0,0,0,0,0,0,0,0,0,0,0,0,0,0,Y55,0,0,0,0,0,0,0,0,0,~
0)';
    'VCCD012'<37>:'(0,0,0,0,0,0,0,0,0,0,0,0,0,0,0,0,0,0,0,Y53,0,0,0,0,0,0,0,0,0,~
0)';
    'VCCD012'<36>:'(0,0,0,0,0,0,0,0,0,0,0,0,0,0,0,0,0,0,0,Y51,0,0,0,0,0,0,0,0,0,~
0)';
    'VCCD012'<35>:'(0,0,0,0,0,0,0,0,0,0,0,0,0,0,0,0,0,0,0,Y49,0,0,0,0,0,0,0,0,0,~
0)';
    'VCCD012'<34>:'(0,0,0,0,0,0,0,0,0,0,0,0,0,0,0,0,0,0,0,Y47,0,0,0,0,0,0,0,0,0,~
0)';
    'VCCD012'<33>:'(0,0,0,0,0,0,0,0,0,0,0,0,0,0,0,0,0,0,0,Y45,0,0,0,0,0,0,0,0,0,~
0)';
    'VCCD012'<32>:'(0,0,0,0,0,0,0,0,0,0,0,0,0,0,0,0,0,0,0,W64,0,0,0,0,0,0,0,0,0,~
0)';
    'VCCD012'<31>:'(0,0,0,0,0,0,0,0,0,0,0,0,0,0,0,0,0,0,0,U62,0,0,0,0,0,0,0,0,0,~
0)';
    'VCCD012'<30>:'(0,0,0,0,0,0,0,0,0,0,0,0,0,0,0,0,0,0,0,U60,0,0,0,0,0,0,0,0,0,~
0)';
    'VCCD012'<29>:'(0,0,0,0,0,0,0,0,0,0,0,0,0,0,0,0,0,0,0,U58,0,0,0,0,0,0,0,0,0,~
0)';
    'VCCD012'<28>:'(0,0,0,0,0,0,0,0,0,0,0,0,0,0,0,0,0,0,0,U56,0,0,0,0,0,0,0,0,0,~
0)';
    'VCCD012'<27>:'(0,0,0,0,0,0,0,0,0,0,0,0,0,0,0,0,0,0,0,U54,0,0,0,0,0,0,0,0,0,~
0)';
    'VCCD012'<26>:'(0,0,0,0,0,0,0,0,0,0,0,0,0,0,0,0,0,0,0,U52,0,0,0,0,0,0,0,0,0,~
0)';
    'VCCD012'<25>:'(0,0,0,0,0,0,0,0,0,0,0,0,0,0,0,0,0,0,0,U50,0,0,0,0,0,0,0,0,0,~
0)';
    'VCCD012'<24>:'(0,0,0,0,0,0,0,0,0,0,0,0,0,0,0,0,0,0,0,U48,0,0,0,0,0,0,0,0,0,~
0)';
    'VCCD012'<23>:'(0,0,0,0,0,0,0,0,0,0,0,0,0,0,0,0,0,0,0,U46,0,0,0,0,0,0,0,0,0,~
0)';
    'VCCD012'<22>:'(0,0,0,0,0,0,0,0,0,0,0,0,0,0,0,0,0,0,0,N64,0,0,0,0,0,0,0,0,0,~
0)';
    'VCCD012'<21>:'(0,0,0,0,0,0,0,0,0,0,0,0,0,0,0,0,0,0,0,L62,0,0,0,0,0,0,0,0,0,~
0)';
    'VCCD012'<20>:'(0,0,0,0,0,0,0,0,0,0,0,0,0,0,0,0,0,0,0,L60,0,0,0,0,0,0,0,0,0,~
0)';
    'VCCD012'<19>:'(0,0,0,0,0,0,0,0,0,0,0,0,0,0,0,0,0,0,0,L58,0,0,0,0,0,0,0,0,0,~
0)';
    'VCCD012'<18>:'(0,0,0,0,0,0,0,0,0,0,0,0,0,0,0,0,0,0,0,L56,0,0,0,0,0,0,0,0,0,~
0)';
    'VCCD012'<17>:'(0,0,0,0,0,0,0,0,0,0,0,0,0,0,0,0,0,0,0,L54,0,0,0,0,0,0,0,0,0,~
0)';
    'VCCD012'<16>:'(0,0,0,0,0,0,0,0,0,0,0,0,0,0,0,0,0,0,0,L52,0,0,0,0,0,0,0,0,0,~
0)';
    'VCCD012'<15>:'(0,0,0,0,0,0,0,0,0,0,0,0,0,0,0,0,0,0,0,L50,0,0,0,0,0,0,0,0,0,~
0)';
    'VCCD012'<14>:'(0,0,0,0,0,0,0,0,0,0,0,0,0,0,0,0,0,0,0,L48,0,0,0,0,0,0,0,0,0,~
0)';
    'VCCD012'<13>:'(0,0,0,0,0,0,0,0,0,0,0,0,0,0,0,0,0,0,0,L46,0,0,0,0,0,0,0,0,0,~
0)';
    'VCCD012'<12>:'(0,0,0,0,0,0,0,0,0,0,0,0,0,0,0,0,0,0,0,E64,0,0,0,0,0,0,0,0,0,~
0)';
    'VCCD012'<11>:'(0,0,0,0,0,0,0,0,0,0,0,0,0,0,0,0,0,0,0,E62,0,0,0,0,0,0,0,0,0,~
0)';
    'VCCD012'<10>:'(0,0,0,0,0,0,0,0,0,0,0,0,0,0,0,0,0,0,0,E60,0,0,0,0,0,0,0,0,0,~
0)';
    'VCCD012'<9>:'(0,0,0,0,0,0,0,0,0,0,0,0,0,0,0,0,0,0,0,E58,0,0,0,0,0,0,0,0,0,0~
)';
    'VCCD012'<8>:'(0,0,0,0,0,0,0,0,0,0,0,0,0,0,0,0,0,0,0,E56,0,0,0,0,0,0,0,0,0,0~
)';
    'VCCD012'<7>:'(0,0,0,0,0,0,0,0,0,0,0,0,0,0,0,0,0,0,0,E54,0,0,0,0,0,0,0,0,0,0~
)';
    'VCCD012'<6>:'(0,0,0,0,0,0,0,0,0,0,0,0,0,0,0,0,0,0,0,E52,0,0,0,0,0,0,0,0,0,0~
)';
    'VCCD012'<5>:'(0,0,0,0,0,0,0,0,0,0,0,0,0,0,0,0,0,0,0,E50,0,0,0,0,0,0,0,0,0,0~
)';
    'VCCD012'<4>:'(0,0,0,0,0,0,0,0,0,0,0,0,0,0,0,0,0,0,0,E48,0,0,0,0,0,0,0,0,0,0~
)';
    'VCCD012'<3>:'(0,0,0,0,0,0,0,0,0,0,0,0,0,0,0,0,0,0,0,E46,0,0,0,0,0,0,0,0,0,0~
)';
    'VCCD012'<2>:'(0,0,0,0,0,0,0,0,0,0,0,0,0,0,0,0,0,0,0,B59,0,0,0,0,0,0,0,0,0,0~
)';
    'VCCD012'<1>:'(0,0,0,0,0,0,0,0,0,0,0,0,0,0,0,0,0,0,0,B53,0,0,0,0,0,0,0,0,0,0~
)';
    'VCCD012'<0>:'(0,0,0,0,0,0,0,0,0,0,0,0,0,0,0,0,0,0,0,B49,0,0,0,0,0,0,0,0,0,0~
)';
    'VCCD345'<50>:'(0,0,0,0,0,0,0,0,0,0,0,0,0,0,0,0,0,0,0,EE44,0,0,0,0,0,0,0,0,0~
,0)';
    'VCCD345'<49>:'(0,0,0,0,0,0,0,0,0,0,0,0,0,0,0,0,0,0,0,EF45,0,0,0,0,0,0,0,0,0~
,0)';
    'VCCD345'<48>:'(0,0,0,0,0,0,0,0,0,0,0,0,0,0,0,0,0,0,0,DB53,0,0,0,0,0,0,0,0,0~
,0)';
    'VCCD345'<47>:'(0,0,0,0,0,0,0,0,0,0,0,0,0,0,0,0,0,0,0,DB55,0,0,0,0,0,0,0,0,0~
,0)';
    'VCCD345'<46>:'(0,0,0,0,0,0,0,0,0,0,0,0,0,0,0,0,0,0,0,DB57,0,0,0,0,0,0,0,0,0~
,0)';
    'VCCD345'<45>:'(0,0,0,0,0,0,0,0,0,0,0,0,0,0,0,0,0,0,0,DB59,0,0,0,0,0,0,0,0,0~
,0)';
    'VCCD345'<44>:'(0,0,0,0,0,0,0,0,0,0,0,0,0,0,0,0,0,0,0,DB61,0,0,0,0,0,0,0,0,0~
,0)';
    'VCCD345'<43>:'(0,0,0,0,0,0,0,0,0,0,0,0,0,0,0,0,0,0,0,DB63,0,0,0,0,0,0,0,0,0~
,0)';
    'VCCD345'<42>:'(0,0,0,0,0,0,0,0,0,0,0,0,0,0,0,0,0,0,0,DD45,0,0,0,0,0,0,0,0,0~
,0)';
    'VCCD345'<41>:'(0,0,0,0,0,0,0,0,0,0,0,0,0,0,0,0,0,0,0,DH45,0,0,0,0,0,0,0,0,0~
,0)';
    'VCCD345'<40>:'(0,0,0,0,0,0,0,0,0,0,0,0,0,0,0,0,0,0,0,DH47,0,0,0,0,0,0,0,0,0~
,0)';
    'VCCD345'<39>:'(0,0,0,0,0,0,0,0,0,0,0,0,0,0,0,0,0,0,0,DH49,0,0,0,0,0,0,0,0,0~
,0)';
    'VCCD345'<38>:'(0,0,0,0,0,0,0,0,0,0,0,0,0,0,0,0,0,0,0,DH51,0,0,0,0,0,0,0,0,0~
,0)';
    'VCCD345'<37>:'(0,0,0,0,0,0,0,0,0,0,0,0,0,0,0,0,0,0,0,DH53,0,0,0,0,0,0,0,0,0~
,0)';
    'VCCD345'<36>:'(0,0,0,0,0,0,0,0,0,0,0,0,0,0,0,0,0,0,0,DH55,0,0,0,0,0,0,0,0,0~
,0)';
    'VCCD345'<35>:'(0,0,0,0,0,0,0,0,0,0,0,0,0,0,0,0,0,0,0,DH57,0,0,0,0,0,0,0,0,0~
,0)';
    'VCCD345'<34>:'(0,0,0,0,0,0,0,0,0,0,0,0,0,0,0,0,0,0,0,DH59,0,0,0,0,0,0,0,0,0~
,0)';
    'VCCD345'<33>:'(0,0,0,0,0,0,0,0,0,0,0,0,0,0,0,0,0,0,0,DH61,0,0,0,0,0,0,0,0,0~
,0)';
    'VCCD345'<32>:'(0,0,0,0,0,0,0,0,0,0,0,0,0,0,0,0,0,0,0,DH63,0,0,0,0,0,0,0,0,0~
,0)';
    'VCCD345'<31>:'(0,0,0,0,0,0,0,0,0,0,0,0,0,0,0,0,0,0,0,DJ64,0,0,0,0,0,0,0,0,0~
,0)';
    'VCCD345'<30>:'(0,0,0,0,0,0,0,0,0,0,0,0,0,0,0,0,0,0,0,DL46,0,0,0,0,0,0,0,0,0~
,0)';
    'VCCD345'<29>:'(0,0,0,0,0,0,0,0,0,0,0,0,0,0,0,0,0,0,0,DL48,0,0,0,0,0,0,0,0,0~
,0)';
    'VCCD345'<28>:'(0,0,0,0,0,0,0,0,0,0,0,0,0,0,0,0,0,0,0,DL50,0,0,0,0,0,0,0,0,0~
,0)';
    'VCCD345'<27>:'(0,0,0,0,0,0,0,0,0,0,0,0,0,0,0,0,0,0,0,DL52,0,0,0,0,0,0,0,0,0~
,0)';
    'VCCD345'<26>:'(0,0,0,0,0,0,0,0,0,0,0,0,0,0,0,0,0,0,0,DL54,0,0,0,0,0,0,0,0,0~
,0)';
    'VCCD345'<25>:'(0,0,0,0,0,0,0,0,0,0,0,0,0,0,0,0,0,0,0,DL56,0,0,0,0,0,0,0,0,0~
,0)';
    'VCCD345'<24>:'(0,0,0,0,0,0,0,0,0,0,0,0,0,0,0,0,0,0,0,DL58,0,0,0,0,0,0,0,0,0~
,0)';
    'VCCD345'<23>:'(0,0,0,0,0,0,0,0,0,0,0,0,0,0,0,0,0,0,0,DL60,0,0,0,0,0,0,0,0,0~
,0)';
    'VCCD345'<22>:'(0,0,0,0,0,0,0,0,0,0,0,0,0,0,0,0,0,0,0,DL62,0,0,0,0,0,0,0,0,0~
,0)';
    'VCCD345'<21>:'(0,0,0,0,0,0,0,0,0,0,0,0,0,0,0,0,0,0,0,DU46,0,0,0,0,0,0,0,0,0~
,0)';
    'VCCD345'<20>:'(0,0,0,0,0,0,0,0,0,0,0,0,0,0,0,0,0,0,0,DU48,0,0,0,0,0,0,0,0,0~
,0)';
    'VCCD345'<19>:'(0,0,0,0,0,0,0,0,0,0,0,0,0,0,0,0,0,0,0,DU50,0,0,0,0,0,0,0,0,0~
,0)';
    'VCCD345'<18>:'(0,0,0,0,0,0,0,0,0,0,0,0,0,0,0,0,0,0,0,DU52,0,0,0,0,0,0,0,0,0~
,0)';
    'VCCD345'<17>:'(0,0,0,0,0,0,0,0,0,0,0,0,0,0,0,0,0,0,0,DU54,0,0,0,0,0,0,0,0,0~
,0)';
    'VCCD345'<16>:'(0,0,0,0,0,0,0,0,0,0,0,0,0,0,0,0,0,0,0,DU56,0,0,0,0,0,0,0,0,0~
,0)';
    'VCCD345'<15>:'(0,0,0,0,0,0,0,0,0,0,0,0,0,0,0,0,0,0,0,DU58,0,0,0,0,0,0,0,0,0~
,0)';
    'VCCD345'<14>:'(0,0,0,0,0,0,0,0,0,0,0,0,0,0,0,0,0,0,0,DU60,0,0,0,0,0,0,0,0,0~
,0)';
    'VCCD345'<13>:'(0,0,0,0,0,0,0,0,0,0,0,0,0,0,0,0,0,0,0,DU62,0,0,0,0,0,0,0,0,0~
,0)';
    'VCCD345'<12>:'(0,0,0,0,0,0,0,0,0,0,0,0,0,0,0,0,0,0,0,DU64,0,0,0,0,0,0,0,0,0~
,0)';
    'VCCD345'<11>:'(0,0,0,0,0,0,0,0,0,0,0,0,0,0,0,0,0,0,0,EC46,0,0,0,0,0,0,0,0,0~
,0)';
    'VCCD345'<10>:'(0,0,0,0,0,0,0,0,0,0,0,0,0,0,0,0,0,0,0,EC48,0,0,0,0,0,0,0,0,0~
,0)';
    'VCCD345'<9>:'(0,0,0,0,0,0,0,0,0,0,0,0,0,0,0,0,0,0,0,EC50,0,0,0,0,0,0,0,0,0,~
0)';
    'VCCD345'<8>:'(0,0,0,0,0,0,0,0,0,0,0,0,0,0,0,0,0,0,0,EC52,0,0,0,0,0,0,0,0,0,~
0)';
    'VCCD345'<7>:'(0,0,0,0,0,0,0,0,0,0,0,0,0,0,0,0,0,0,0,EC54,0,0,0,0,0,0,0,0,0,~
0)';
    'VCCD345'<6>:'(0,0,0,0,0,0,0,0,0,0,0,0,0,0,0,0,0,0,0,EC56,0,0,0,0,0,0,0,0,0,~
0)';
    'VCCD345'<5>:'(0,0,0,0,0,0,0,0,0,0,0,0,0,0,0,0,0,0,0,EC58,0,0,0,0,0,0,0,0,0,~
0)';
    'VCCD345'<4>:'(0,0,0,0,0,0,0,0,0,0,0,0,0,0,0,0,0,0,0,EC60,0,0,0,0,0,0,0,0,0,~
0)';
    'VCCD345'<3>:'(0,0,0,0,0,0,0,0,0,0,0,0,0,0,0,0,0,0,0,EC62,0,0,0,0,0,0,0,0,0,~
0)';
    'VCCD345'<2>:'(0,0,0,0,0,0,0,0,0,0,0,0,0,0,0,0,0,0,0,EF49,0,0,0,0,0,0,0,0,0,~
0)';
    'VCCD345'<1>:'(0,0,0,0,0,0,0,0,0,0,0,0,0,0,0,0,0,0,0,EF53,0,0,0,0,0,0,0,0,0,~
0)';
    'VCCD345'<0>:'(0,0,0,0,0,0,0,0,0,0,0,0,0,0,0,0,0,0,0,EF59,0,0,0,0,0,0,0,0,0,~
0)';
    'VCCIN'<267>:'(0,0,0,0,0,0,0,0,0,0,0,0,0,0,0,0,0,AF43,0,0,0,0,0,0,0,0,0,0,0,~
0)';
    'VCCIN'<266>:'(0,0,0,0,0,0,0,0,0,0,0,0,0,0,0,0,0,AG38,0,0,0,0,0,0,0,0,0,0,0,~
0)';
    'VCCIN'<265>:'(0,0,0,0,0,0,0,0,0,0,0,0,0,0,0,0,0,AG40,0,0,0,0,0,0,0,0,0,0,0,~
0)';
    'VCCIN'<264>:'(0,0,0,0,0,0,0,0,0,0,0,0,0,0,0,0,0,AG42,0,0,0,0,0,0,0,0,0,0,0,~
0)';
    'VCCIN'<263>:'(0,0,0,0,0,0,0,0,0,0,0,0,0,0,0,0,0,AH37,0,0,0,0,0,0,0,0,0,0,0,~
0)';
    'VCCIN'<262>:'(0,0,0,0,0,0,0,0,0,0,0,0,0,0,0,0,0,AH39,0,0,0,0,0,0,0,0,0,0,0,~
0)';
    'VCCIN'<261>:'(0,0,0,0,0,0,0,0,0,0,0,0,0,0,0,0,0,AH41,0,0,0,0,0,0,0,0,0,0,0,~
0)';
    'VCCIN'<260>:'(0,0,0,0,0,0,0,0,0,0,0,0,0,0,0,0,0,AJ36,0,0,0,0,0,0,0,0,0,0,0,~
0)';
    'VCCIN'<259>:'(0,0,0,0,0,0,0,0,0,0,0,0,0,0,0,0,0,AK35,0,0,0,0,0,0,0,0,0,0,0,~
0)';
    'VCCIN'<258>:'(0,0,0,0,0,0,0,0,0,0,0,0,0,0,0,0,0,AK45,0,0,0,0,0,0,0,0,0,0,0,~
0)';
    'VCCIN'<257>:'(0,0,0,0,0,0,0,0,0,0,0,0,0,0,0,0,0,AK47,0,0,0,0,0,0,0,0,0,0,0,~
0)';
    'VCCIN'<256>:'(0,0,0,0,0,0,0,0,0,0,0,0,0,0,0,0,0,AK49,0,0,0,0,0,0,0,0,0,0,0,~
0)';
    'VCCIN'<255>:'(0,0,0,0,0,0,0,0,0,0,0,0,0,0,0,0,0,AK51,0,0,0,0,0,0,0,0,0,0,0,~
0)';
    'VCCIN'<254>:'(0,0,0,0,0,0,0,0,0,0,0,0,0,0,0,0,0,AK53,0,0,0,0,0,0,0,0,0,0,0,~
0)';
    'VCCIN'<253>:'(0,0,0,0,0,0,0,0,0,0,0,0,0,0,0,0,0,AL34,0,0,0,0,0,0,0,0,0,0,0,~
0)';
    'VCCIN'<252>:'(0,0,0,0,0,0,0,0,0,0,0,0,0,0,0,0,0,AL46,0,0,0,0,0,0,0,0,0,0,0,~
0)';
    'VCCIN'<251>:'(0,0,0,0,0,0,0,0,0,0,0,0,0,0,0,0,0,AL48,0,0,0,0,0,0,0,0,0,0,0,~
0)';
    'VCCIN'<250>:'(0,0,0,0,0,0,0,0,0,0,0,0,0,0,0,0,0,AL50,0,0,0,0,0,0,0,0,0,0,0,~
0)';
    'VCCIN'<249>:'(0,0,0,0,0,0,0,0,0,0,0,0,0,0,0,0,0,AL52,0,0,0,0,0,0,0,0,0,0,0,~
0)';
    'VCCIN'<248>:'(0,0,0,0,0,0,0,0,0,0,0,0,0,0,0,0,0,AL54,0,0,0,0,0,0,0,0,0,0,0,~
0)';
    'VCCIN'<247>:'(0,0,0,0,0,0,0,0,0,0,0,0,0,0,0,0,0,AM33,0,0,0,0,0,0,0,0,0,0,0,~
0)';
    'VCCIN'<246>:'(0,0,0,0,0,0,0,0,0,0,0,0,0,0,0,0,0,AM53,0,0,0,0,0,0,0,0,0,0,0,~
0)';
    'VCCIN'<245>:'(0,0,0,0,0,0,0,0,0,0,0,0,0,0,0,0,0,AM55,0,0,0,0,0,0,0,0,0,0,0,~
0)';
    'VCCIN'<244>:'(0,0,0,0,0,0,0,0,0,0,0,0,0,0,0,0,0,AN32,0,0,0,0,0,0,0,0,0,0,0,~
0)';
    'VCCIN'<243>:'(0,0,0,0,0,0,0,0,0,0,0,0,0,0,0,0,0,AN54,0,0,0,0,0,0,0,0,0,0,0,~
0)';
    'VCCIN'<242>:'(0,0,0,0,0,0,0,0,0,0,0,0,0,0,0,0,0,AN56,0,0,0,0,0,0,0,0,0,0,0,~
0)';
    'VCCIN'<241>:'(0,0,0,0,0,0,0,0,0,0,0,0,0,0,0,0,0,AP55,0,0,0,0,0,0,0,0,0,0,0,~
0)';
    'VCCIN'<240>:'(0,0,0,0,0,0,0,0,0,0,0,0,0,0,0,0,0,AP57,0,0,0,0,0,0,0,0,0,0,0,~
0)';
    'VCCIN'<239>:'(0,0,0,0,0,0,0,0,0,0,0,0,0,0,0,0,0,AR56,0,0,0,0,0,0,0,0,0,0,0,~
0)';
    'VCCIN'<238>:'(0,0,0,0,0,0,0,0,0,0,0,0,0,0,0,0,0,AR58,0,0,0,0,0,0,0,0,0,0,0,~
0)';
    'VCCIN'<237>:'(0,0,0,0,0,0,0,0,0,0,0,0,0,0,0,0,0,AT57,0,0,0,0,0,0,0,0,0,0,0,~
0)';
    'VCCIN'<236>:'(0,0,0,0,0,0,0,0,0,0,0,0,0,0,0,0,0,AT59,0,0,0,0,0,0,0,0,0,0,0,~
0)';
    'VCCIN'<235>:'(0,0,0,0,0,0,0,0,0,0,0,0,0,0,0,0,0,AU58,0,0,0,0,0,0,0,0,0,0,0,~
0)';
    'VCCIN'<234>:'(0,0,0,0,0,0,0,0,0,0,0,0,0,0,0,0,0,AU60,0,0,0,0,0,0,0,0,0,0,0,~
0)';
    'VCCIN'<233>:'(0,0,0,0,0,0,0,0,0,0,0,0,0,0,0,0,0,AV59,0,0,0,0,0,0,0,0,0,0,0,~
0)';
    'VCCIN'<232>:'(0,0,0,0,0,0,0,0,0,0,0,0,0,0,0,0,0,AV61,0,0,0,0,0,0,0,0,0,0,0,~
0)';
    'VCCIN'<231>:'(0,0,0,0,0,0,0,0,0,0,0,0,0,0,0,0,0,AW60,0,0,0,0,0,0,0,0,0,0,0,~
0)';
    'VCCIN'<230>:'(0,0,0,0,0,0,0,0,0,0,0,0,0,0,0,0,0,AY61,0,0,0,0,0,0,0,0,0,0,0,~
0)';
    'VCCIN'<229>:'(0,0,0,0,0,0,0,0,0,0,0,0,0,0,0,0,0,BA60,0,0,0,0,0,0,0,0,0,0,0,~
0)';
    'VCCIN'<228>:'(0,0,0,0,0,0,0,0,0,0,0,0,0,0,0,0,0,BB61,0,0,0,0,0,0,0,0,0,0,0,~
0)';
    'VCCIN'<227>:'(0,0,0,0,0,0,0,0,0,0,0,0,0,0,0,0,0,BB85,0,0,0,0,0,0,0,0,0,0,0,~
0)';
    'VCCIN'<226>:'(0,0,0,0,0,0,0,0,0,0,0,0,0,0,0,0,0,BC60,0,0,0,0,0,0,0,0,0,0,0,~
0)';
    'VCCIN'<225>:'(0,0,0,0,0,0,0,0,0,0,0,0,0,0,0,0,0,BC62,0,0,0,0,0,0,0,0,0,0,0,~
0)';
    'VCCIN'<224>:'(0,0,0,0,0,0,0,0,0,0,0,0,0,0,0,0,0,BC84,0,0,0,0,0,0,0,0,0,0,0,~
0)';
    'VCCIN'<223>:'(0,0,0,0,0,0,0,0,0,0,0,0,0,0,0,0,0,BD61,0,0,0,0,0,0,0,0,0,0,0,~
0)';
    'VCCIN'<222>:'(0,0,0,0,0,0,0,0,0,0,0,0,0,0,0,0,0,BD73,0,0,0,0,0,0,0,0,0,0,0,~
0)';
    'VCCIN'<221>:'(0,0,0,0,0,0,0,0,0,0,0,0,0,0,0,0,0,BD75,0,0,0,0,0,0,0,0,0,0,0,~
0)';
    'VCCIN'<220>:'(0,0,0,0,0,0,0,0,0,0,0,0,0,0,0,0,0,BD77,0,0,0,0,0,0,0,0,0,0,0,~
0)';
    'VCCIN'<219>:'(0,0,0,0,0,0,0,0,0,0,0,0,0,0,0,0,0,BD79,0,0,0,0,0,0,0,0,0,0,0,~
0)';
    'VCCIN'<218>:'(0,0,0,0,0,0,0,0,0,0,0,0,0,0,0,0,0,BD81,0,0,0,0,0,0,0,0,0,0,0,~
0)';
    'VCCIN'<217>:'(0,0,0,0,0,0,0,0,0,0,0,0,0,0,0,0,0,BD83,0,0,0,0,0,0,0,0,0,0,0,~
0)';
    'VCCIN'<216>:'(0,0,0,0,0,0,0,0,0,0,0,0,0,0,0,0,0,BD85,0,0,0,0,0,0,0,0,0,0,0,~
0)';
    'VCCIN'<215>:'(0,0,0,0,0,0,0,0,0,0,0,0,0,0,0,0,0,BE60,0,0,0,0,0,0,0,0,0,0,0,~
0)';
    'VCCIN'<214>:'(0,0,0,0,0,0,0,0,0,0,0,0,0,0,0,0,0,BE62,0,0,0,0,0,0,0,0,0,0,0,~
0)';
    'VCCIN'<213>:'(0,0,0,0,0,0,0,0,0,0,0,0,0,0,0,0,0,BE72,0,0,0,0,0,0,0,0,0,0,0,~
0)';
    'VCCIN'<212>:'(0,0,0,0,0,0,0,0,0,0,0,0,0,0,0,0,0,BE74,0,0,0,0,0,0,0,0,0,0,0,~
0)';
    'VCCIN'<211>:'(0,0,0,0,0,0,0,0,0,0,0,0,0,0,0,0,0,BE76,0,0,0,0,0,0,0,0,0,0,0,~
0)';
    'VCCIN'<210>:'(0,0,0,0,0,0,0,0,0,0,0,0,0,0,0,0,0,BE78,0,0,0,0,0,0,0,0,0,0,0,~
0)';
    'VCCIN'<209>:'(0,0,0,0,0,0,0,0,0,0,0,0,0,0,0,0,0,BE80,0,0,0,0,0,0,0,0,0,0,0,~
0)';
    'VCCIN'<208>:'(0,0,0,0,0,0,0,0,0,0,0,0,0,0,0,0,0,BE82,0,0,0,0,0,0,0,0,0,0,0,~
0)';
    'VCCIN'<207>:'(0,0,0,0,0,0,0,0,0,0,0,0,0,0,0,0,0,BE84,0,0,0,0,0,0,0,0,0,0,0,~
0)';
    'VCCIN'<206>:'(0,0,0,0,0,0,0,0,0,0,0,0,0,0,0,0,0,BF61,0,0,0,0,0,0,0,0,0,0,0,~
0)';
    'VCCIN'<205>:'(0,0,0,0,0,0,0,0,0,0,0,0,0,0,0,0,0,BF73,0,0,0,0,0,0,0,0,0,0,0,~
0)';
    'VCCIN'<204>:'(0,0,0,0,0,0,0,0,0,0,0,0,0,0,0,0,0,BF75,0,0,0,0,0,0,0,0,0,0,0,~
0)';
    'VCCIN'<203>:'(0,0,0,0,0,0,0,0,0,0,0,0,0,0,0,0,0,BF77,0,0,0,0,0,0,0,0,0,0,0,~
0)';
    'VCCIN'<202>:'(0,0,0,0,0,0,0,0,0,0,0,0,0,0,0,0,0,BF79,0,0,0,0,0,0,0,0,0,0,0,~
0)';
    'VCCIN'<201>:'(0,0,0,0,0,0,0,0,0,0,0,0,0,0,0,0,0,BF81,0,0,0,0,0,0,0,0,0,0,0,~
0)';
    'VCCIN'<200>:'(0,0,0,0,0,0,0,0,0,0,0,0,0,0,0,0,0,BF83,0,0,0,0,0,0,0,0,0,0,0,~
0)';
    'VCCIN'<199>:'(0,0,0,0,0,0,0,0,0,0,0,0,0,0,0,0,0,BF85,0,0,0,0,0,0,0,0,0,0,0,~
0)';
    'VCCIN'<198>:'(0,0,0,0,0,0,0,0,0,0,0,0,0,0,0,0,0,BG60,0,0,0,0,0,0,0,0,0,0,0,~
0)';
    'VCCIN'<197>:'(0,0,0,0,0,0,0,0,0,0,0,0,0,0,0,0,0,BG62,0,0,0,0,0,0,0,0,0,0,0,~
0)';
    'VCCIN'<196>:'(0,0,0,0,0,0,0,0,0,0,0,0,0,0,0,0,0,BG64,0,0,0,0,0,0,0,0,0,0,0,~
0)';
    'VCCIN'<195>:'(0,0,0,0,0,0,0,0,0,0,0,0,0,0,0,0,0,BG66,0,0,0,0,0,0,0,0,0,0,0,~
0)';
    'VCCIN'<194>:'(0,0,0,0,0,0,0,0,0,0,0,0,0,0,0,0,0,BG68,0,0,0,0,0,0,0,0,0,0,0,~
0)';
    'VCCIN'<193>:'(0,0,0,0,0,0,0,0,0,0,0,0,0,0,0,0,0,BG70,0,0,0,0,0,0,0,0,0,0,0,~
0)';
    'VCCIN'<192>:'(0,0,0,0,0,0,0,0,0,0,0,0,0,0,0,0,0,BG84,0,0,0,0,0,0,0,0,0,0,0,~
0)';
    'VCCIN'<191>:'(0,0,0,0,0,0,0,0,0,0,0,0,0,0,0,0,0,BH61,0,0,0,0,0,0,0,0,0,0,0,~
0)';
    'VCCIN'<190>:'(0,0,0,0,0,0,0,0,0,0,0,0,0,0,0,0,0,BH63,0,0,0,0,0,0,0,0,0,0,0,~
0)';
    'VCCIN'<189>:'(0,0,0,0,0,0,0,0,0,0,0,0,0,0,0,0,0,BH65,0,0,0,0,0,0,0,0,0,0,0,~
0)';
    'VCCIN'<188>:'(0,0,0,0,0,0,0,0,0,0,0,0,0,0,0,0,0,BH67,0,0,0,0,0,0,0,0,0,0,0,~
0)';
    'VCCIN'<187>:'(0,0,0,0,0,0,0,0,0,0,0,0,0,0,0,0,0,BH69,0,0,0,0,0,0,0,0,0,0,0,~
0)';
    'VCCIN'<186>:'(0,0,0,0,0,0,0,0,0,0,0,0,0,0,0,0,0,BH71,0,0,0,0,0,0,0,0,0,0,0,~
0)';
    'VCCIN'<185>:'(0,0,0,0,0,0,0,0,0,0,0,0,0,0,0,0,0,BH73,0,0,0,0,0,0,0,0,0,0,0,~
0)';
    'VCCIN'<184>:'(0,0,0,0,0,0,0,0,0,0,0,0,0,0,0,0,0,BH75,0,0,0,0,0,0,0,0,0,0,0,~
0)';
    'VCCIN'<183>:'(0,0,0,0,0,0,0,0,0,0,0,0,0,0,0,0,0,BH77,0,0,0,0,0,0,0,0,0,0,0,~
0)';
    'VCCIN'<182>:'(0,0,0,0,0,0,0,0,0,0,0,0,0,0,0,0,0,BH79,0,0,0,0,0,0,0,0,0,0,0,~
0)';
    'VCCIN'<181>:'(0,0,0,0,0,0,0,0,0,0,0,0,0,0,0,0,0,BH81,0,0,0,0,0,0,0,0,0,0,0,~
0)';
    'VCCIN'<180>:'(0,0,0,0,0,0,0,0,0,0,0,0,0,0,0,0,0,BH83,0,0,0,0,0,0,0,0,0,0,0,~
0)';
    'VCCIN'<179>:'(0,0,0,0,0,0,0,0,0,0,0,0,0,0,0,0,0,BJ60,0,0,0,0,0,0,0,0,0,0,0,~
0)';
    'VCCIN'<178>:'(0,0,0,0,0,0,0,0,0,0,0,0,0,0,0,0,0,BJ62,0,0,0,0,0,0,0,0,0,0,0,~
0)';
    'VCCIN'<177>:'(0,0,0,0,0,0,0,0,0,0,0,0,0,0,0,0,0,BJ64,0,0,0,0,0,0,0,0,0,0,0,~
0)';
    'VCCIN'<176>:'(0,0,0,0,0,0,0,0,0,0,0,0,0,0,0,0,0,BJ66,0,0,0,0,0,0,0,0,0,0,0,~
0)';
    'VCCIN'<175>:'(0,0,0,0,0,0,0,0,0,0,0,0,0,0,0,0,0,BJ68,0,0,0,0,0,0,0,0,0,0,0,~
0)';
    'VCCIN'<174>:'(0,0,0,0,0,0,0,0,0,0,0,0,0,0,0,0,0,BJ70,0,0,0,0,0,0,0,0,0,0,0,~
0)';
    'VCCIN'<173>:'(0,0,0,0,0,0,0,0,0,0,0,0,0,0,0,0,0,BJ72,0,0,0,0,0,0,0,0,0,0,0,~
0)';
    'VCCIN'<172>:'(0,0,0,0,0,0,0,0,0,0,0,0,0,0,0,0,0,BJ74,0,0,0,0,0,0,0,0,0,0,0,~
0)';
    'VCCIN'<171>:'(0,0,0,0,0,0,0,0,0,0,0,0,0,0,0,0,0,BJ76,0,0,0,0,0,0,0,0,0,0,0,~
0)';
    'VCCIN'<170>:'(0,0,0,0,0,0,0,0,0,0,0,0,0,0,0,0,0,BJ78,0,0,0,0,0,0,0,0,0,0,0,~
0)';
    'VCCIN'<169>:'(0,0,0,0,0,0,0,0,0,0,0,0,0,0,0,0,0,BJ80,0,0,0,0,0,0,0,0,0,0,0,~
0)';
    'VCCIN'<168>:'(0,0,0,0,0,0,0,0,0,0,0,0,0,0,0,0,0,BJ82,0,0,0,0,0,0,0,0,0,0,0,~
0)';
    'VCCIN'<167>:'(0,0,0,0,0,0,0,0,0,0,0,0,0,0,0,0,0,BJ84,0,0,0,0,0,0,0,0,0,0,0,~
0)';
    'VCCIN'<166>:'(0,0,0,0,0,0,0,0,0,0,0,0,0,0,0,0,0,BK61,0,0,0,0,0,0,0,0,0,0,0,~
0)';
    'VCCIN'<165>:'(0,0,0,0,0,0,0,0,0,0,0,0,0,0,0,0,0,BK63,0,0,0,0,0,0,0,0,0,0,0,~
0)';
    'VCCIN'<164>:'(0,0,0,0,0,0,0,0,0,0,0,0,0,0,0,0,0,BK65,0,0,0,0,0,0,0,0,0,0,0,~
0)';
    'VCCIN'<163>:'(0,0,0,0,0,0,0,0,0,0,0,0,0,0,0,0,0,BK67,0,0,0,0,0,0,0,0,0,0,0,~
0)';
    'VCCIN'<162>:'(0,0,0,0,0,0,0,0,0,0,0,0,0,0,0,0,0,BK69,0,0,0,0,0,0,0,0,0,0,0,~
0)';
    'VCCIN'<161>:'(0,0,0,0,0,0,0,0,0,0,0,0,0,0,0,0,0,BK71,0,0,0,0,0,0,0,0,0,0,0,~
0)';
    'VCCIN'<160>:'(0,0,0,0,0,0,0,0,0,0,0,0,0,0,0,0,0,BK73,0,0,0,0,0,0,0,0,0,0,0,~
0)';
    'VCCIN'<159>:'(0,0,0,0,0,0,0,0,0,0,0,0,0,0,0,0,0,BK75,0,0,0,0,0,0,0,0,0,0,0,~
0)';
    'VCCIN'<158>:'(0,0,0,0,0,0,0,0,0,0,0,0,0,0,0,0,0,BK77,0,0,0,0,0,0,0,0,0,0,0,~
0)';
    'VCCIN'<157>:'(0,0,0,0,0,0,0,0,0,0,0,0,0,0,0,0,0,BK79,0,0,0,0,0,0,0,0,0,0,0,~
0)';
    'VCCIN'<156>:'(0,0,0,0,0,0,0,0,0,0,0,0,0,0,0,0,0,BK81,0,0,0,0,0,0,0,0,0,0,0,~
0)';
    'VCCIN'<155>:'(0,0,0,0,0,0,0,0,0,0,0,0,0,0,0,0,0,BK83,0,0,0,0,0,0,0,0,0,0,0,~
0)';
    'VCCIN'<154>:'(0,0,0,0,0,0,0,0,0,0,0,0,0,0,0,0,0,BL60,0,0,0,0,0,0,0,0,0,0,0,~
0)';
    'VCCIN'<153>:'(0,0,0,0,0,0,0,0,0,0,0,0,0,0,0,0,0,BL62,0,0,0,0,0,0,0,0,0,0,0,~
0)';
    'VCCIN'<152>:'(0,0,0,0,0,0,0,0,0,0,0,0,0,0,0,0,0,BL84,0,0,0,0,0,0,0,0,0,0,0,~
0)';
    'VCCIN'<151>:'(0,0,0,0,0,0,0,0,0,0,0,0,0,0,0,0,0,BM61,0,0,0,0,0,0,0,0,0,0,0,~
0)';
    'VCCIN'<150>:'(0,0,0,0,0,0,0,0,0,0,0,0,0,0,0,0,0,BM63,0,0,0,0,0,0,0,0,0,0,0,~
0)';
    'VCCIN'<149>:'(0,0,0,0,0,0,0,0,0,0,0,0,0,0,0,0,0,BM65,0,0,0,0,0,0,0,0,0,0,0,~
0)';
    'VCCIN'<148>:'(0,0,0,0,0,0,0,0,0,0,0,0,0,0,0,0,0,BM67,0,0,0,0,0,0,0,0,0,0,0,~
0)';
    'VCCIN'<147>:'(0,0,0,0,0,0,0,0,0,0,0,0,0,0,0,0,0,BM69,0,0,0,0,0,0,0,0,0,0,0,~
0)';
    'VCCIN'<146>:'(0,0,0,0,0,0,0,0,0,0,0,0,0,0,0,0,0,BM71,0,0,0,0,0,0,0,0,0,0,0,~
0)';
    'VCCIN'<145>:'(0,0,0,0,0,0,0,0,0,0,0,0,0,0,0,0,0,BM73,0,0,0,0,0,0,0,0,0,0,0,~
0)';
    'VCCIN'<144>:'(0,0,0,0,0,0,0,0,0,0,0,0,0,0,0,0,0,BM75,0,0,0,0,0,0,0,0,0,0,0,~
0)';
    'VCCIN'<143>:'(0,0,0,0,0,0,0,0,0,0,0,0,0,0,0,0,0,BM77,0,0,0,0,0,0,0,0,0,0,0,~
0)';
    'VCCIN'<142>:'(0,0,0,0,0,0,0,0,0,0,0,0,0,0,0,0,0,BM79,0,0,0,0,0,0,0,0,0,0,0,~
0)';
    'VCCIN'<141>:'(0,0,0,0,0,0,0,0,0,0,0,0,0,0,0,0,0,BM81,0,0,0,0,0,0,0,0,0,0,0,~
0)';
    'VCCIN'<140>:'(0,0,0,0,0,0,0,0,0,0,0,0,0,0,0,0,0,BM83,0,0,0,0,0,0,0,0,0,0,0,~
0)';
    'VCCIN'<139>:'(0,0,0,0,0,0,0,0,0,0,0,0,0,0,0,0,0,BN60,0,0,0,0,0,0,0,0,0,0,0,~
0)';
    'VCCIN'<138>:'(0,0,0,0,0,0,0,0,0,0,0,0,0,0,0,0,0,BN62,0,0,0,0,0,0,0,0,0,0,0,~
0)';
    'VCCIN'<137>:'(0,0,0,0,0,0,0,0,0,0,0,0,0,0,0,0,0,BN64,0,0,0,0,0,0,0,0,0,0,0,~
0)';
    'VCCIN'<136>:'(0,0,0,0,0,0,0,0,0,0,0,0,0,0,0,0,0,BN66,0,0,0,0,0,0,0,0,0,0,0,~
0)';
    'VCCIN'<135>:'(0,0,0,0,0,0,0,0,0,0,0,0,0,0,0,0,0,BN68,0,0,0,0,0,0,0,0,0,0,0,~
0)';
    'VCCIN'<134>:'(0,0,0,0,0,0,0,0,0,0,0,0,0,0,0,0,0,BN70,0,0,0,0,0,0,0,0,0,0,0,~
0)';
    'VCCIN'<133>:'(0,0,0,0,0,0,0,0,0,0,0,0,0,0,0,0,0,BN72,0,0,0,0,0,0,0,0,0,0,0,~
0)';
    'VCCIN'<132>:'(0,0,0,0,0,0,0,0,0,0,0,0,0,0,0,0,0,BN74,0,0,0,0,0,0,0,0,0,0,0,~
0)';
    'VCCIN'<131>:'(0,0,0,0,0,0,0,0,0,0,0,0,0,0,0,0,0,BN76,0,0,0,0,0,0,0,0,0,0,0,~
0)';
    'VCCIN'<130>:'(0,0,0,0,0,0,0,0,0,0,0,0,0,0,0,0,0,BN78,0,0,0,0,0,0,0,0,0,0,0,~
0)';
    'VCCIN'<129>:'(0,0,0,0,0,0,0,0,0,0,0,0,0,0,0,0,0,0,BN80,0,0,0,0,0,0,0,0,0,0,~
0)';
    'VCCIN'<128>:'(0,0,0,0,0,0,0,0,0,0,0,0,0,0,0,0,0,0,BN82,0,0,0,0,0,0,0,0,0,0,~
0)';
    'VCCIN'<127>:'(0,0,0,0,0,0,0,0,0,0,0,0,0,0,0,0,0,0,BN84,0,0,0,0,0,0,0,0,0,0,~
0)';
    'VCCIN'<126>:'(0,0,0,0,0,0,0,0,0,0,0,0,0,0,0,0,0,0,BP61,0,0,0,0,0,0,0,0,0,0,~
0)';
    'VCCIN'<125>:'(0,0,0,0,0,0,0,0,0,0,0,0,0,0,0,0,0,0,BP63,0,0,0,0,0,0,0,0,0,0,~
0)';
    'VCCIN'<124>:'(0,0,0,0,0,0,0,0,0,0,0,0,0,0,0,0,0,0,BP65,0,0,0,0,0,0,0,0,0,0,~
0)';
    'VCCIN'<123>:'(0,0,0,0,0,0,0,0,0,0,0,0,0,0,0,0,0,0,BP67,0,0,0,0,0,0,0,0,0,0,~
0)';
    'VCCIN'<122>:'(0,0,0,0,0,0,0,0,0,0,0,0,0,0,0,0,0,0,BP69,0,0,0,0,0,0,0,0,0,0,~
0)';
    'VCCIN'<121>:'(0,0,0,0,0,0,0,0,0,0,0,0,0,0,0,0,0,0,BP71,0,0,0,0,0,0,0,0,0,0,~
0)';
    'VCCIN'<120>:'(0,0,0,0,0,0,0,0,0,0,0,0,0,0,0,0,0,0,BP73,0,0,0,0,0,0,0,0,0,0,~
0)';
    'VCCIN'<119>:'(0,0,0,0,0,0,0,0,0,0,0,0,0,0,0,0,0,0,BP75,0,0,0,0,0,0,0,0,0,0,~
0)';
    'VCCIN'<118>:'(0,0,0,0,0,0,0,0,0,0,0,0,0,0,0,0,0,0,BP77,0,0,0,0,0,0,0,0,0,0,~
0)';
    'VCCIN'<117>:'(0,0,0,0,0,0,0,0,0,0,0,0,0,0,0,0,0,0,BP79,0,0,0,0,0,0,0,0,0,0,~
0)';
    'VCCIN'<116>:'(0,0,0,0,0,0,0,0,0,0,0,0,0,0,0,0,0,0,BP81,0,0,0,0,0,0,0,0,0,0,~
0)';
    'VCCIN'<115>:'(0,0,0,0,0,0,0,0,0,0,0,0,0,0,0,0,0,0,BP83,0,0,0,0,0,0,0,0,0,0,~
0)';
    'VCCIN'<114>:'(0,0,0,0,0,0,0,0,0,0,0,0,0,0,0,0,0,0,BR60,0,0,0,0,0,0,0,0,0,0,~
0)';
    'VCCIN'<113>:'(0,0,0,0,0,0,0,0,0,0,0,0,0,0,0,0,0,0,BR62,0,0,0,0,0,0,0,0,0,0,~
0)';
    'VCCIN'<112>:'(0,0,0,0,0,0,0,0,0,0,0,0,0,0,0,0,0,0,BR84,0,0,0,0,0,0,0,0,0,0,~
0)';
    'VCCIN'<111>:'(0,0,0,0,0,0,0,0,0,0,0,0,0,0,0,0,0,0,BT61,0,0,0,0,0,0,0,0,0,0,~
0)';
    'VCCIN'<110>:'(0,0,0,0,0,0,0,0,0,0,0,0,0,0,0,0,0,0,BT63,0,0,0,0,0,0,0,0,0,0,~
0)';
    'VCCIN'<109>:'(0,0,0,0,0,0,0,0,0,0,0,0,0,0,0,0,0,0,BT65,0,0,0,0,0,0,0,0,0,0,~
0)';
    'VCCIN'<108>:'(0,0,0,0,0,0,0,0,0,0,0,0,0,0,0,0,0,0,BT67,0,0,0,0,0,0,0,0,0,0,~
0)';
    'VCCIN'<107>:'(0,0,0,0,0,0,0,0,0,0,0,0,0,0,0,0,0,0,BT69,0,0,0,0,0,0,0,0,0,0,~
0)';
    'VCCIN'<106>:'(0,0,0,0,0,0,0,0,0,0,0,0,0,0,0,0,0,0,BT71,0,0,0,0,0,0,0,0,0,0,~
0)';
    'VCCIN'<105>:'(0,0,0,0,0,0,0,0,0,0,0,0,0,0,0,0,0,0,BT73,0,0,0,0,0,0,0,0,0,0,~
0)';
    'VCCIN'<104>:'(0,0,0,0,0,0,0,0,0,0,0,0,0,0,0,0,0,0,BT75,0,0,0,0,0,0,0,0,0,0,~
0)';
    'VCCIN'<103>:'(0,0,0,0,0,0,0,0,0,0,0,0,0,0,0,0,0,0,BT77,0,0,0,0,0,0,0,0,0,0,~
0)';
    'VCCIN'<102>:'(0,0,0,0,0,0,0,0,0,0,0,0,0,0,0,0,0,0,BT79,0,0,0,0,0,0,0,0,0,0,~
0)';
    'VCCIN'<101>:'(0,0,0,0,0,0,0,0,0,0,0,0,0,0,0,0,0,0,BT81,0,0,0,0,0,0,0,0,0,0,~
0)';
    'VCCIN'<100>:'(0,0,0,0,0,0,0,0,0,0,0,0,0,0,0,0,0,0,BT83,0,0,0,0,0,0,0,0,0,0,~
0)';
    'VCCIN'<99>:'(0,0,0,0,0,0,0,0,0,0,0,0,0,0,0,0,0,0,BU60,0,0,0,0,0,0,0,0,0,0,0~
)';
    'VCCIN'<98>:'(0,0,0,0,0,0,0,0,0,0,0,0,0,0,0,0,0,0,BU62,0,0,0,0,0,0,0,0,0,0,0~
)';
    'VCCIN'<97>:'(0,0,0,0,0,0,0,0,0,0,0,0,0,0,0,0,0,0,BU64,0,0,0,0,0,0,0,0,0,0,0~
)';
    'VCCIN'<96>:'(0,0,0,0,0,0,0,0,0,0,0,0,0,0,0,0,0,0,BU66,0,0,0,0,0,0,0,0,0,0,0~
)';
    'VCCIN'<95>:'(0,0,0,0,0,0,0,0,0,0,0,0,0,0,0,0,0,0,BU68,0,0,0,0,0,0,0,0,0,0,0~
)';
    'VCCIN'<94>:'(0,0,0,0,0,0,0,0,0,0,0,0,0,0,0,0,0,0,BU70,0,0,0,0,0,0,0,0,0,0,0~
)';
    'VCCIN'<93>:'(0,0,0,0,0,0,0,0,0,0,0,0,0,0,0,0,0,0,BU72,0,0,0,0,0,0,0,0,0,0,0~
)';
    'VCCIN'<92>:'(0,0,0,0,0,0,0,0,0,0,0,0,0,0,0,0,0,0,BU74,0,0,0,0,0,0,0,0,0,0,0~
)';
    'VCCIN'<91>:'(0,0,0,0,0,0,0,0,0,0,0,0,0,0,0,0,0,0,BU76,0,0,0,0,0,0,0,0,0,0,0~
)';
    'VCCIN'<90>:'(0,0,0,0,0,0,0,0,0,0,0,0,0,0,0,0,0,0,BU78,0,0,0,0,0,0,0,0,0,0,0~
)';
    'VCCIN'<89>:'(0,0,0,0,0,0,0,0,0,0,0,0,0,0,0,0,0,0,BU80,0,0,0,0,0,0,0,0,0,0,0~
)';
    'VCCIN'<88>:'(0,0,0,0,0,0,0,0,0,0,0,0,0,0,0,0,0,0,BU82,0,0,0,0,0,0,0,0,0,0,0~
)';
    'VCCIN'<87>:'(0,0,0,0,0,0,0,0,0,0,0,0,0,0,0,0,0,0,BU84,0,0,0,0,0,0,0,0,0,0,0~
)';
    'VCCIN'<86>:'(0,0,0,0,0,0,0,0,0,0,0,0,0,0,0,0,0,0,BV61,0,0,0,0,0,0,0,0,0,0,0~
)';
    'VCCIN'<85>:'(0,0,0,0,0,0,0,0,0,0,0,0,0,0,0,0,0,0,BV63,0,0,0,0,0,0,0,0,0,0,0~
)';
    'VCCIN'<84>:'(0,0,0,0,0,0,0,0,0,0,0,0,0,0,0,0,0,0,BV65,0,0,0,0,0,0,0,0,0,0,0~
)';
    'VCCIN'<83>:'(0,0,0,0,0,0,0,0,0,0,0,0,0,0,0,0,0,0,BV67,0,0,0,0,0,0,0,0,0,0,0~
)';
    'VCCIN'<82>:'(0,0,0,0,0,0,0,0,0,0,0,0,0,0,0,0,0,0,BV69,0,0,0,0,0,0,0,0,0,0,0~
)';
    'VCCIN'<81>:'(0,0,0,0,0,0,0,0,0,0,0,0,0,0,0,0,0,0,BV71,0,0,0,0,0,0,0,0,0,0,0~
)';
    'VCCIN'<80>:'(0,0,0,0,0,0,0,0,0,0,0,0,0,0,0,0,0,0,BV73,0,0,0,0,0,0,0,0,0,0,0~
)';
    'VCCIN'<79>:'(0,0,0,0,0,0,0,0,0,0,0,0,0,0,0,0,0,0,BV75,0,0,0,0,0,0,0,0,0,0,0~
)';
    'VCCIN'<78>:'(0,0,0,0,0,0,0,0,0,0,0,0,0,0,0,0,0,0,BV77,0,0,0,0,0,0,0,0,0,0,0~
)';
    'VCCIN'<77>:'(0,0,0,0,0,0,0,0,0,0,0,0,0,0,0,0,0,0,BV79,0,0,0,0,0,0,0,0,0,0,0~
)';
    'VCCIN'<76>:'(0,0,0,0,0,0,0,0,0,0,0,0,0,0,0,0,0,0,BV81,0,0,0,0,0,0,0,0,0,0,0~
)';
    'VCCIN'<75>:'(0,0,0,0,0,0,0,0,0,0,0,0,0,0,0,0,0,0,BV83,0,0,0,0,0,0,0,0,0,0,0~
)';
    'VCCIN'<74>:'(0,0,0,0,0,0,0,0,0,0,0,0,0,0,0,0,0,0,BW60,0,0,0,0,0,0,0,0,0,0,0~
)';
    'VCCIN'<73>:'(0,0,0,0,0,0,0,0,0,0,0,0,0,0,0,0,0,0,BW62,0,0,0,0,0,0,0,0,0,0,0~
)';
    'VCCIN'<72>:'(0,0,0,0,0,0,0,0,0,0,0,0,0,0,0,0,0,0,BW64,0,0,0,0,0,0,0,0,0,0,0~
)';
    'VCCIN'<71>:'(0,0,0,0,0,0,0,0,0,0,0,0,0,0,0,0,0,0,BW66,0,0,0,0,0,0,0,0,0,0,0~
)';
    'VCCIN'<70>:'(0,0,0,0,0,0,0,0,0,0,0,0,0,0,0,0,0,0,BW68,0,0,0,0,0,0,0,0,0,0,0~
)';
    'VCCIN'<69>:'(0,0,0,0,0,0,0,0,0,0,0,0,0,0,0,0,0,0,BW70,0,0,0,0,0,0,0,0,0,0,0~
)';
    'VCCIN'<68>:'(0,0,0,0,0,0,0,0,0,0,0,0,0,0,0,0,0,0,BW84,0,0,0,0,0,0,0,0,0,0,0~
)';
    'VCCIN'<67>:'(0,0,0,0,0,0,0,0,0,0,0,0,0,0,0,0,0,0,BY61,0,0,0,0,0,0,0,0,0,0,0~
)';
    'VCCIN'<66>:'(0,0,0,0,0,0,0,0,0,0,0,0,0,0,0,0,0,0,BY73,0,0,0,0,0,0,0,0,0,0,0~
)';
    'VCCIN'<65>:'(0,0,0,0,0,0,0,0,0,0,0,0,0,0,0,0,0,0,BY75,0,0,0,0,0,0,0,0,0,0,0~
)';
    'VCCIN'<64>:'(0,0,0,0,0,0,0,0,0,0,0,0,0,0,0,0,0,0,BY77,0,0,0,0,0,0,0,0,0,0,0~
)';
    'VCCIN'<63>:'(0,0,0,0,0,0,0,0,0,0,0,0,0,0,0,0,0,0,BY79,0,0,0,0,0,0,0,0,0,0,0~
)';
    'VCCIN'<62>:'(0,0,0,0,0,0,0,0,0,0,0,0,0,0,0,0,0,0,BY81,0,0,0,0,0,0,0,0,0,0,0~
)';
    'VCCIN'<61>:'(0,0,0,0,0,0,0,0,0,0,0,0,0,0,0,0,0,0,BY83,0,0,0,0,0,0,0,0,0,0,0~
)';
    'VCCIN'<60>:'(0,0,0,0,0,0,0,0,0,0,0,0,0,0,0,0,0,0,CA60,0,0,0,0,0,0,0,0,0,0,0~
)';
    'VCCIN'<59>:'(0,0,0,0,0,0,0,0,0,0,0,0,0,0,0,0,0,0,CA62,0,0,0,0,0,0,0,0,0,0,0~
)';
    'VCCIN'<58>:'(0,0,0,0,0,0,0,0,0,0,0,0,0,0,0,0,0,0,CA72,0,0,0,0,0,0,0,0,0,0,0~
)';
    'VCCIN'<57>:'(0,0,0,0,0,0,0,0,0,0,0,0,0,0,0,0,0,0,CA74,0,0,0,0,0,0,0,0,0,0,0~
)';
    'VCCIN'<56>:'(0,0,0,0,0,0,0,0,0,0,0,0,0,0,0,0,0,0,CA76,0,0,0,0,0,0,0,0,0,0,0~
)';
    'VCCIN'<55>:'(0,0,0,0,0,0,0,0,0,0,0,0,0,0,0,0,0,0,CA78,0,0,0,0,0,0,0,0,0,0,0~
)';
    'VCCIN'<54>:'(0,0,0,0,0,0,0,0,0,0,0,0,0,0,0,0,0,0,CA80,0,0,0,0,0,0,0,0,0,0,0~
)';
    'VCCIN'<53>:'(0,0,0,0,0,0,0,0,0,0,0,0,0,0,0,0,0,0,CA82,0,0,0,0,0,0,0,0,0,0,0~
)';
    'VCCIN'<52>:'(0,0,0,0,0,0,0,0,0,0,0,0,0,0,0,0,0,0,CA84,0,0,0,0,0,0,0,0,0,0,0~
)';
    'VCCIN'<51>:'(0,0,0,0,0,0,0,0,0,0,0,0,0,0,0,0,0,0,CB61,0,0,0,0,0,0,0,0,0,0,0~
)';
    'VCCIN'<50>:'(0,0,0,0,0,0,0,0,0,0,0,0,0,0,0,0,0,0,CB73,0,0,0,0,0,0,0,0,0,0,0~
)';
    'VCCIN'<49>:'(0,0,0,0,0,0,0,0,0,0,0,0,0,0,0,0,0,0,CB75,0,0,0,0,0,0,0,0,0,0,0~
)';
    'VCCIN'<48>:'(0,0,0,0,0,0,0,0,0,0,0,0,0,0,0,0,0,0,CB77,0,0,0,0,0,0,0,0,0,0,0~
)';
    'VCCIN'<47>:'(0,0,0,0,0,0,0,0,0,0,0,0,0,0,0,0,0,0,CB79,0,0,0,0,0,0,0,0,0,0,0~
)';
    'VCCIN'<46>:'(0,0,0,0,0,0,0,0,0,0,0,0,0,0,0,0,0,0,CB81,0,0,0,0,0,0,0,0,0,0,0~
)';
    'VCCIN'<45>:'(0,0,0,0,0,0,0,0,0,0,0,0,0,0,0,0,0,0,CB83,0,0,0,0,0,0,0,0,0,0,0~
)';
    'VCCIN'<44>:'(0,0,0,0,0,0,0,0,0,0,0,0,0,0,0,0,0,0,CC60,0,0,0,0,0,0,0,0,0,0,0~
)';
    'VCCIN'<43>:'(0,0,0,0,0,0,0,0,0,0,0,0,0,0,0,0,0,0,CC62,0,0,0,0,0,0,0,0,0,0,0~
)';
    'VCCIN'<42>:'(0,0,0,0,0,0,0,0,0,0,0,0,0,0,0,0,0,0,CC84,0,0,0,0,0,0,0,0,0,0,0~
)';
    'VCCIN'<41>:'(0,0,0,0,0,0,0,0,0,0,0,0,0,0,0,0,0,0,CD61,0,0,0,0,0,0,0,0,0,0,0~
)';
    'VCCIN'<40>:'(0,0,0,0,0,0,0,0,0,0,0,0,0,0,0,0,0,0,CD83,0,0,0,0,0,0,0,0,0,0,0~
)';
    'VCCIN'<39>:'(0,0,0,0,0,0,0,0,0,0,0,0,0,0,0,0,0,0,CD85,0,0,0,0,0,0,0,0,0,0,0~
)';
    'VCCIN'<38>:'(0,0,0,0,0,0,0,0,0,0,0,0,0,0,0,0,0,0,CE60,0,0,0,0,0,0,0,0,0,0,0~
)';
    'VCCIN'<37>:'(0,0,0,0,0,0,0,0,0,0,0,0,0,0,0,0,0,0,CE84,0,0,0,0,0,0,0,0,0,0,0~
)';
    'VCCIN'<36>:'(0,0,0,0,0,0,0,0,0,0,0,0,0,0,0,0,0,0,CF61,0,0,0,0,0,0,0,0,0,0,0~
)';
    'VCCIN'<35>:'(0,0,0,0,0,0,0,0,0,0,0,0,0,0,0,0,0,0,CF85,0,0,0,0,0,0,0,0,0,0,0~
)';
    'VCCIN'<34>:'(0,0,0,0,0,0,0,0,0,0,0,0,0,0,0,0,0,0,CG60,0,0,0,0,0,0,0,0,0,0,0~
)';
    'VCCIN'<33>:'(0,0,0,0,0,0,0,0,0,0,0,0,0,0,0,0,0,0,CG84,0,0,0,0,0,0,0,0,0,0,0~
)';
    'VCCIN'<32>:'(0,0,0,0,0,0,0,0,0,0,0,0,0,0,0,0,0,0,CH61,0,0,0,0,0,0,0,0,0,0,0~
)';
    'VCCIN'<31>:'(0,0,0,0,0,0,0,0,0,0,0,0,0,0,0,0,0,0,CH85,0,0,0,0,0,0,0,0,0,0,0~
)';
    'VCCIN'<30>:'(0,0,0,0,0,0,0,0,0,0,0,0,0,0,0,0,0,0,CJ60,0,0,0,0,0,0,0,0,0,0,0~
)';
    'VCCIN'<29>:'(0,0,0,0,0,0,0,0,0,0,0,0,0,0,0,0,0,0,CK59,0,0,0,0,0,0,0,0,0,0,0~
)';
    'VCCIN'<28>:'(0,0,0,0,0,0,0,0,0,0,0,0,0,0,0,0,0,0,CK61,0,0,0,0,0,0,0,0,0,0,0~
)';
    'VCCIN'<27>:'(0,0,0,0,0,0,0,0,0,0,0,0,0,0,0,0,0,0,CL58,0,0,0,0,0,0,0,0,0,0,0~
)';
    'VCCIN'<26>:'(0,0,0,0,0,0,0,0,0,0,0,0,0,0,0,0,0,0,CL60,0,0,0,0,0,0,0,0,0,0,0~
)';
    'VCCIN'<25>:'(0,0,0,0,0,0,0,0,0,0,0,0,0,0,0,0,0,0,CM57,0,0,0,0,0,0,0,0,0,0,0~
)';
    'VCCIN'<24>:'(0,0,0,0,0,0,0,0,0,0,0,0,0,0,0,0,0,0,CM59,0,0,0,0,0,0,0,0,0,0,0~
)';
    'VCCIN'<23>:'(0,0,0,0,0,0,0,0,0,0,0,0,0,0,0,0,0,0,CN56,0,0,0,0,0,0,0,0,0,0,0~
)';
    'VCCIN'<22>:'(0,0,0,0,0,0,0,0,0,0,0,0,0,0,0,0,0,0,CN58,0,0,0,0,0,0,0,0,0,0,0~
)';
    'VCCIN'<21>:'(0,0,0,0,0,0,0,0,0,0,0,0,0,0,0,0,0,0,CP33,0,0,0,0,0,0,0,0,0,0,0~
)';
    'VCCIN'<20>:'(0,0,0,0,0,0,0,0,0,0,0,0,0,0,0,0,0,0,CP55,0,0,0,0,0,0,0,0,0,0,0~
)';
    'VCCIN'<19>:'(0,0,0,0,0,0,0,0,0,0,0,0,0,0,0,0,0,0,CP57,0,0,0,0,0,0,0,0,0,0,0~
)';
    'VCCIN'<18>:'(0,0,0,0,0,0,0,0,0,0,0,0,0,0,0,0,0,0,CR34,0,0,0,0,0,0,0,0,0,0,0~
)';
    'VCCIN'<17>:'(0,0,0,0,0,0,0,0,0,0,0,0,0,0,0,0,0,0,CR54,0,0,0,0,0,0,0,0,0,0,0~
)';
    'VCCIN'<16>:'(0,0,0,0,0,0,0,0,0,0,0,0,0,0,0,0,0,0,CR56,0,0,0,0,0,0,0,0,0,0,0~
)';
    'VCCIN'<15>:'(0,0,0,0,0,0,0,0,0,0,0,0,0,0,0,0,0,0,CT37,0,0,0,0,0,0,0,0,0,0,0~
)';
    'VCCIN'<14>:'(0,0,0,0,0,0,0,0,0,0,0,0,0,0,0,0,0,0,CT39,0,0,0,0,0,0,0,0,0,0,0~
)';
    'VCCIN'<13>:'(0,0,0,0,0,0,0,0,0,0,0,0,0,0,0,0,0,0,CT41,0,0,0,0,0,0,0,0,0,0,0~
)';
    'VCCIN'<12>:'(0,0,0,0,0,0,0,0,0,0,0,0,0,0,0,0,0,0,CT53,0,0,0,0,0,0,0,0,0,0,0~
)';
    'VCCIN'<11>:'(0,0,0,0,0,0,0,0,0,0,0,0,0,0,0,0,0,0,CT55,0,0,0,0,0,0,0,0,0,0,0~
)';
    'VCCIN'<10>:'(0,0,0,0,0,0,0,0,0,0,0,0,0,0,0,0,0,0,CU38,0,0,0,0,0,0,0,0,0,0,0~
)';
    'VCCIN'<9>:'(0,0,0,0,0,0,0,0,0,0,0,0,0,0,0,0,0,0,CU40,0,0,0,0,0,0,0,0,0,0,0)~
';
    'VCCIN'<8>:'(0,0,0,0,0,0,0,0,0,0,0,0,0,0,0,0,0,0,CU42,0,0,0,0,0,0,0,0,0,0,0)~
';
    'VCCIN'<7>:'(0,0,0,0,0,0,0,0,0,0,0,0,0,0,0,0,0,0,CU52,0,0,0,0,0,0,0,0,0,0,0)~
';
    'VCCIN'<6>:'(0,0,0,0,0,0,0,0,0,0,0,0,0,0,0,0,0,0,CU54,0,0,0,0,0,0,0,0,0,0,0)~
';
    'VCCIN'<5>:'(0,0,0,0,0,0,0,0,0,0,0,0,0,0,0,0,0,0,CV51,0,0,0,0,0,0,0,0,0,0,0)~
';
    'VCCIN'<4>:'(0,0,0,0,0,0,0,0,0,0,0,0,0,0,0,0,0,0,CW46,0,0,0,0,0,0,0,0,0,0,0)~
';
    'VCCIN'<3>:'(0,0,0,0,0,0,0,0,0,0,0,0,0,0,0,0,0,0,CW48,0,0,0,0,0,0,0,0,0,0,0)~
';
    'VCCIN'<2>:'(0,0,0,0,0,0,0,0,0,0,0,0,0,0,0,0,0,0,CW50,0,0,0,0,0,0,0,0,0,0,0)~
';
    'VCCIN'<1>:'(0,0,0,0,0,0,0,0,0,0,0,0,0,0,0,0,0,0,CY47,0,0,0,0,0,0,0,0,0,0,0)~
';
    'VCCIN'<0>:'(0,0,0,0,0,0,0,0,0,0,0,0,0,0,0,0,0,0,CY49,0,0,0,0,0,0,0,0,0,0,0)~
';
    'VCCINPMAX'<1>:'(0,0,0,0,0,0,0,0,0,0,0,0,0,0,0,0,0,0,AV85,0,0,0,0,0,0,0,0,0,~
0,0)';
    'VCCINPMAX'<0>:'(0,0,0,0,0,0,0,0,0,0,0,0,0,0,0,0,0,0,AW86,0,0,0,0,0,0,0,0,0,~
0,0)';
    'VCCIN_SENSE':'(0,0,0,0,0,0,0,0,0,0,0,0,0,0,0,0,0,0,BA86,0,0,0,0,0,0,0,0,0,0~
,0)';$S;BIDI;
    'VCCIO'<104>:'(0,0,0,0,0,0,0,0,0,0,0,0,0,0,0,0,0,0,0,0,AR28,0,0,0,0,0,0,0,0,~
0)';
    'VCCIO'<103>:'(0,0,0,0,0,0,0,0,0,0,0,0,0,0,0,0,0,0,0,0,AL28,0,0,0,0,0,0,0,0,~
0)';
    'VCCIO'<102>:'(0,0,0,0,0,0,0,0,0,0,0,0,0,0,0,0,0,0,0,0,AM29,0,0,0,0,0,0,0,0,~
0)';
    'VCCIO'<101>:'(0,0,0,0,0,0,0,0,0,0,0,0,0,0,0,0,0,0,0,0,AG34,0,0,0,0,0,0,0,0,~
0)';
    'VCCIO'<100>:'(0,0,0,0,0,0,0,0,0,0,0,0,0,0,0,0,0,0,0,0,AE34,0,0,0,0,0,0,0,0,~
0)';
    'VCCIO'<99>:'(0,0,0,0,0,0,0,0,0,0,0,0,0,0,0,0,0,0,0,0,AD35,0,0,0,0,0,0,0,0,0~
)';
    'VCCIO'<98>:'(0,0,0,0,0,0,0,0,0,0,0,0,0,0,0,0,0,0,0,0,AF35,0,0,0,0,0,0,0,0,0~
)';
    'VCCIO'<97>:'(0,0,0,0,0,0,0,0,0,0,0,0,0,0,0,0,0,0,0,0,AC36,0,0,0,0,0,0,0,0,0~
)';
    'VCCIO'<96>:'(0,0,0,0,0,0,0,0,0,0,0,0,0,0,0,0,0,0,0,0,AD37,0,0,0,0,0,0,0,0,0~
)';
    'VCCIO'<95>:'(0,0,0,0,0,0,0,0,0,0,0,0,0,0,0,0,0,0,0,0,AE36,0,0,0,0,0,0,0,0,0~
)';
    'VCCIO'<94>:'(0,0,0,0,0,0,0,0,0,0,0,0,0,0,0,0,0,0,0,0,BF27,0,0,0,0,0,0,0,0,0~
)';
    'VCCIO'<93>:'(0,0,0,0,0,0,0,0,0,0,0,0,0,0,0,0,0,0,0,0,BG26,0,0,0,0,0,0,0,0,0~
)';
    'VCCIO'<92>:'(0,0,0,0,0,0,0,0,0,0,0,0,0,0,0,0,0,0,0,0,BH25,0,0,0,0,0,0,0,0,0~
)';
    'VCCIO'<91>:'(0,0,0,0,0,0,0,0,0,0,0,0,0,0,0,0,0,0,0,0,BH27,0,0,0,0,0,0,0,0,0~
)';
    'VCCIO'<90>:'(0,0,0,0,0,0,0,0,0,0,0,0,0,0,0,0,0,0,0,0,BJ26,0,0,0,0,0,0,0,0,0~
)';
    'VCCIO'<89>:'(0,0,0,0,0,0,0,0,0,0,0,0,0,0,0,0,0,0,0,0,BK25,0,0,0,0,0,0,0,0,0~
)';
    'VCCIO'<88>:'(0,0,0,0,0,0,0,0,0,0,0,0,0,0,0,0,0,0,0,0,BK27,0,0,0,0,0,0,0,0,0~
)';
    'VCCIO'<87>:'(0,0,0,0,0,0,0,0,0,0,0,0,0,0,0,0,0,0,0,0,BL26,0,0,0,0,0,0,0,0,0~
)';
    'VCCIO'<86>:'(0,0,0,0,0,0,0,0,0,0,0,0,0,0,0,0,0,0,0,0,BM27,0,0,0,0,0,0,0,0,0~
)';
    'VCCIO'<85>:'(0,0,0,0,0,0,0,0,0,0,0,0,0,0,0,0,0,0,0,0,CH27,0,0,0,0,0,0,0,0,0~
)';
    'VCCIO'<84>:'(0,0,0,0,0,0,0,0,0,0,0,0,0,0,0,0,0,0,0,0,CJ28,0,0,0,0,0,0,0,0,0~
)';
    'VCCIO'<83>:'(0,0,0,0,0,0,0,0,0,0,0,0,0,0,0,0,0,0,0,0,CC26,0,0,0,0,0,0,0,0,0~
)';
    'VCCIO'<82>:'(0,0,0,0,0,0,0,0,0,0,0,0,0,0,0,0,0,0,0,0,CD27,0,0,0,0,0,0,0,0,0~
)';
    'VCCIO'<81>:'(0,0,0,0,0,0,0,0,0,0,0,0,0,0,0,0,0,0,0,0,CF27,0,0,0,0,0,0,0,0,0~
)';
    'VCCIO'<80>:'(0,0,0,0,0,0,0,0,0,0,0,0,0,0,0,0,0,0,0,0,AV27,0,0,0,0,0,0,0,0,0~
)';
    'VCCIO'<79>:'(0,0,0,0,0,0,0,0,0,0,0,0,0,0,0,0,0,0,0,0,AW26,0,0,0,0,0,0,0,0,0~
)';
    'VCCIO'<78>:'(0,0,0,0,0,0,0,0,0,0,0,0,0,0,0,0,0,0,0,0,AY27,0,0,0,0,0,0,0,0,0~
)';
    'VCCIO'<77>:'(0,0,0,0,0,0,0,0,0,0,0,0,0,0,0,0,0,0,0,0,BA26,0,0,0,0,0,0,0,0,0~
)';
    'VCCIO'<76>:'(0,0,0,0,0,0,0,0,0,0,0,0,0,0,0,0,0,0,0,0,BB27,0,0,0,0,0,0,0,0,0~
)';
    'VCCIO'<75>:'(0,0,0,0,0,0,0,0,0,0,0,0,0,0,0,0,0,0,0,0,BC26,0,0,0,0,0,0,0,0,0~
)';
    'VCCIO'<74>:'(0,0,0,0,0,0,0,0,0,0,0,0,0,0,0,0,0,0,0,0,W10,0,0,0,0,0,0,0,0,0)~
';
    'VCCIO'<73>:'(0,0,0,0,0,0,0,0,0,0,0,0,0,0,0,0,0,0,0,0,N18,0,0,0,0,0,0,0,0,0)~
';
    'VCCIO'<72>:'(0,0,0,0,0,0,0,0,0,0,0,0,0,0,0,0,0,0,0,0,M9,0,0,0,0,0,0,0,0,0)';
    'VCCIO'<71>:'(0,0,0,0,0,0,0,0,0,0,0,0,0,0,0,0,0,0,0,0,M7,0,0,0,0,0,0,0,0,0)';
    'VCCIO'<70>:'(0,0,0,0,0,0,0,0,0,0,0,0,0,0,0,0,0,0,0,0,K15,0,0,0,0,0,0,0,0,0)~
';
    'VCCIO'<69>:'(0,0,0,0,0,0,0,0,0,0,0,0,0,0,0,0,0,0,0,0,J2,0,0,0,0,0,0,0,0,0)';
    'VCCIO'<68>:'(0,0,0,0,0,0,0,0,0,0,0,0,0,0,0,0,0,0,0,0,EB15,0,0,0,0,0,0,0,0,0~
)';
    'VCCIO'<67>:'(0,0,0,0,0,0,0,0,0,0,0,0,0,0,0,0,0,0,0,0,EA12,0,0,0,0,0,0,0,0,0~
)';
    'VCCIO'<66>:'(0,0,0,0,0,0,0,0,0,0,0,0,0,0,0,0,0,0,0,0,DU20,0,0,0,0,0,0,0,0,0~
)';
    'VCCIO'<65>:'(0,0,0,0,0,0,0,0,0,0,0,0,0,0,0,0,0,0,0,0,DR2,0,0,0,0,0,0,0,0,0)~
';
    'VCCIO'<64>:'(0,0,0,0,0,0,0,0,0,0,0,0,0,0,0,0,0,0,0,0,DR10,0,0,0,0,0,0,0,0,0~
)';
    'VCCIO'<63>:'(0,0,0,0,0,0,0,0,0,0,0,0,0,0,0,0,0,0,0,0,DP19,0,0,0,0,0,0,0,0,0~
)';
    'VCCIO'<62>:'(0,0,0,0,0,0,0,0,0,0,0,0,0,0,0,0,0,0,0,0,DN8,0,0,0,0,0,0,0,0,0)~
';
    'VCCIO'<61>:'(0,0,0,0,0,0,0,0,0,0,0,0,0,0,0,0,0,0,0,0,DM17,0,0,0,0,0,0,0,0,0~
)';
    'VCCIO'<60>:'(0,0,0,0,0,0,0,0,0,0,0,0,0,0,0,0,0,0,0,0,DJ16,0,0,0,0,0,0,0,0,0~
)';
    'VCCIO'<59>:'(0,0,0,0,0,0,0,0,0,0,0,0,0,0,0,0,0,0,0,0,H13,0,0,0,0,0,0,0,0,0)~
';
    'VCCIO'<58>:'(0,0,0,0,0,0,0,0,0,0,0,0,0,0,0,0,0,0,0,0,J10,0,0,0,0,0,0,0,0,0)~
';
    'VCCIO'<57>:'(0,0,0,0,0,0,0,0,0,0,0,0,0,0,0,0,0,0,0,0,L14,0,0,0,0,0,0,0,0,0)~
';
    'VCCIO'<56>:'(0,0,0,0,0,0,0,0,0,0,0,0,0,0,0,0,0,0,0,0,L16,0,0,0,0,0,0,0,0,0)~
';
    'VCCIO'<55>:'(0,0,0,0,0,0,0,0,0,0,0,0,0,0,0,0,0,0,0,0,DH7,0,0,0,0,0,0,0,0,0)~
';
    'VCCIO'<54>:'(0,0,0,0,0,0,0,0,0,0,0,0,0,0,0,0,0,0,0,0,DG8,0,0,0,0,0,0,0,0,0)~
';
    'VCCIO'<53>:'(0,0,0,0,0,0,0,0,0,0,0,0,0,0,0,0,0,0,0,0,M11,0,0,0,0,0,0,0,0,0)~
';
    'VCCIO'<52>:'(0,0,0,0,0,0,0,0,0,0,0,0,0,0,0,0,0,0,0,0,M21,0,0,0,0,0,0,0,0,0)~
';
    'VCCIO'<51>:'(0,0,0,0,0,0,0,0,0,0,0,0,0,0,0,0,0,0,0,0,P5,0,0,0,0,0,0,0,0,0)';
    'VCCIO'<50>:'(0,0,0,0,0,0,0,0,0,0,0,0,0,0,0,0,0,0,0,0,T3,0,0,0,0,0,0,0,0,0)';
    'VCCIO'<49>:'(0,0,0,0,0,0,0,0,0,0,0,0,0,0,0,0,0,0,0,0,U14,0,0,0,0,0,0,0,0,0)~
';
    'VCCIO'<48>:'(0,0,0,0,0,0,0,0,0,0,0,0,0,0,0,0,0,0,0,0,DF21,0,0,0,0,0,0,0,0,0~
)';
    'VCCIO'<47>:'(0,0,0,0,0,0,0,0,0,0,0,0,0,0,0,0,0,0,0,0,W4,0,0,0,0,0,0,0,0,0)';
    'VCCIO'<46>:'(0,0,0,0,0,0,0,0,0,0,0,0,0,0,0,0,0,0,0,0,W6,0,0,0,0,0,0,0,0,0)';
    'VCCIO'<45>:'(0,0,0,0,0,0,0,0,0,0,0,0,0,0,0,0,0,0,0,0,AA10,0,0,0,0,0,0,0,0,0~
)';
    'VCCIO'<44>:'(0,0,0,0,0,0,0,0,0,0,0,0,0,0,0,0,0,0,0,0,AC20,0,0,0,0,0,0,0,0,0~
)';
    'VCCIO'<43>:'(0,0,0,0,0,0,0,0,0,0,0,0,0,0,0,0,0,0,0,0,AC4,0,0,0,0,0,0,0,0,0)~
';
    'VCCIO'<42>:'(0,0,0,0,0,0,0,0,0,0,0,0,0,0,0,0,0,0,0,0,AH9,0,0,0,0,0,0,0,0,0)~
';
    'VCCIO'<41>:'(0,0,0,0,0,0,0,0,0,0,0,0,0,0,0,0,0,0,0,0,DF13,0,0,0,0,0,0,0,0,0~
)';
    'VCCIO'<40>:'(0,0,0,0,0,0,0,0,0,0,0,0,0,0,0,0,0,0,0,0,AN10,0,0,0,0,0,0,0,0,0~
)';
    'VCCIO'<39>:'(0,0,0,0,0,0,0,0,0,0,0,0,0,0,0,0,0,0,0,0,DD7,0,0,0,0,0,0,0,0,0)~
';
    'VCCIO'<38>:'(0,0,0,0,0,0,0,0,0,0,0,0,0,0,0,0,0,0,0,0,AT11,0,0,0,0,0,0,0,0,0~
)';
    'VCCIO'<37>:'(0,0,0,0,0,0,0,0,0,0,0,0,0,0,0,0,0,0,0,0,AW6,0,0,0,0,0,0,0,0,0)~
';
    'VCCIO'<36>:'(0,0,0,0,0,0,0,0,0,0,0,0,0,0,0,0,0,0,0,0,AY11,0,0,0,0,0,0,0,0,0~
)';
    'VCCIO'<35>:'(0,0,0,0,0,0,0,0,0,0,0,0,0,0,0,0,0,0,0,0,BA24,0,0,0,0,0,0,0,0,0~
)';
    'VCCIO'<34>:'(0,0,0,0,0,0,0,0,0,0,0,0,0,0,0,0,0,0,0,0,BB5,0,0,0,0,0,0,0,0,0)~
';
    'VCCIO'<33>:'(0,0,0,0,0,0,0,0,0,0,0,0,0,0,0,0,0,0,0,0,DA14,0,0,0,0,0,0,0,0,0~
)';
    'VCCIO'<32>:'(0,0,0,0,0,0,0,0,0,0,0,0,0,0,0,0,0,0,0,0,BF23,0,0,0,0,0,0,0,0,0~
)';
    'VCCIO'<31>:'(0,0,0,0,0,0,0,0,0,0,0,0,0,0,0,0,0,0,0,0,BJ24,0,0,0,0,0,0,0,0,0~
)';
    'VCCIO'<30>:'(0,0,0,0,0,0,0,0,0,0,0,0,0,0,0,0,0,0,0,0,BP25,0,0,0,0,0,0,0,0,0~
)';
    'VCCIO'<29>:'(0,0,0,0,0,0,0,0,0,0,0,0,0,0,0,0,0,0,0,0,CB13,0,0,0,0,0,0,0,0,0~
)';
    'VCCIO'<28>:'(0,0,0,0,0,0,0,0,0,0,0,0,0,0,0,0,0,0,0,0,CB17,0,0,0,0,0,0,0,0,0~
)';
    'VCCIO'<27>:'(0,0,0,0,0,0,0,0,0,0,0,0,0,0,0,0,0,0,0,0,CD9,0,0,0,0,0,0,0,0,0)~
';
    'VCCIO'<26>:'(0,0,0,0,0,0,0,0,0,0,0,0,0,0,0,0,0,0,0,0,CE18,0,0,0,0,0,0,0,0,0~
)';
    'VCCIO'<25>:'(0,0,0,0,0,0,0,0,0,0,0,0,0,0,0,0,0,0,0,0,D7,0,0,0,0,0,0,0,0,0)';
    'VCCIO'<24>:'(0,0,0,0,0,0,0,0,0,0,0,0,0,0,0,0,0,0,0,0,CH9,0,0,0,0,0,0,0,0,0)~
';
    'VCCIO'<23>:'(0,0,0,0,0,0,0,0,0,0,0,0,0,0,0,0,0,0,0,0,CV7,0,0,0,0,0,0,0,0,0)~
';
    'VCCIO'<22>:'(0,0,0,0,0,0,0,0,0,0,0,0,0,0,0,0,0,0,0,0,CK5,0,0,0,0,0,0,0,0,0)~
';
    'VCCIO'<21>:'(0,0,0,0,0,0,0,0,0,0,0,0,0,0,0,0,0,0,0,0,CL12,0,0,0,0,0,0,0,0,0~
)';
    'VCCIO'<20>:'(0,0,0,0,0,0,0,0,0,0,0,0,0,0,0,0,0,0,0,0,CM15,0,0,0,0,0,0,0,0,0~
)';
    'VCCIO'<19>:'(0,0,0,0,0,0,0,0,0,0,0,0,0,0,0,0,0,0,0,0,0,CN6,0,0,0,0,0,0,0,0)~
';
    'VCCIO'<18>:'(0,0,0,0,0,0,0,0,0,0,0,0,0,0,0,0,0,0,0,0,0,CU12,0,0,0,0,0,0,0,0~
)';
    'VCCIO'<17>:'(0,0,0,0,0,0,0,0,0,0,0,0,0,0,0,0,0,0,0,0,0,CV21,0,0,0,0,0,0,0,0~
)';
    'VCCIO'<16>:'(0,0,0,0,0,0,0,0,0,0,0,0,0,0,0,0,0,0,0,0,0,CU18,0,0,0,0,0,0,0,0~
)';
    'VCCIO'<15>:'(0,0,0,0,0,0,0,0,0,0,0,0,0,0,0,0,0,0,0,0,0,CY17,0,0,0,0,0,0,0,0~
)';
    'VCCIO'<14>:'(0,0,0,0,0,0,0,0,0,0,0,0,0,0,0,0,0,0,0,0,0,DC18,0,0,0,0,0,0,0,0~
)';
    'VCCIO'<13>:'(0,0,0,0,0,0,0,0,0,0,0,0,0,0,0,0,0,0,0,0,0,DE14,0,0,0,0,0,0,0,0~
)';
    'VCCIO'<12>:'(0,0,0,0,0,0,0,0,0,0,0,0,0,0,0,0,0,0,0,0,0,CP13,0,0,0,0,0,0,0,0~
)';
    'VCCIO'<11>:'(0,0,0,0,0,0,0,0,0,0,0,0,0,0,0,0,0,0,0,0,0,CL20,0,0,0,0,0,0,0,0~
)';
    'VCCIO'<10>:'(0,0,0,0,0,0,0,0,0,0,0,0,0,0,0,0,0,0,0,0,0,CG14,0,0,0,0,0,0,0,0~
)';
    'VCCIO'<9>:'(0,0,0,0,0,0,0,0,0,0,0,0,0,0,0,0,0,0,0,0,0,CF5,0,0,0,0,0,0,0,0)';
    'VCCIO'<8>:'(0,0,0,0,0,0,0,0,0,0,0,0,0,0,0,0,0,0,0,0,0,DK21,0,0,0,0,0,0,0,0)~
';
    'VCCIO'<7>:'(0,0,0,0,0,0,0,0,0,0,0,0,0,0,0,0,0,0,0,0,0,BE24,0,0,0,0,0,0,0,0)~
';
    'VCCIO'<6>:'(0,0,0,0,0,0,0,0,0,0,0,0,0,0,0,0,0,0,0,0,0,AT7,0,0,0,0,0,0,0,0)';
    'VCCIO'<5>:'(0,0,0,0,0,0,0,0,0,0,0,0,0,0,0,0,0,0,0,0,0,AT5,0,0,0,0,0,0,0,0)';
    'VCCIO'<4>:'(0,0,0,0,0,0,0,0,0,0,0,0,0,0,0,0,0,0,0,0,0,AM5,0,0,0,0,0,0,0,0)';
    'VCCIO'<3>:'(0,0,0,0,0,0,0,0,0,0,0,0,0,0,0,0,0,0,0,0,0,DV11,0,0,0,0,0,0,0,0)~
';
    'VCCIO'<2>:'(0,0,0,0,0,0,0,0,0,0,0,0,0,0,0,0,0,0,0,0,0,AF5,0,0,0,0,0,0,0,0)';
    'VCCIO'<1>:'(0,0,0,0,0,0,0,0,0,0,0,0,0,0,0,0,0,0,0,0,0,AE10,0,0,0,0,0,0,0,0)~
';
    'VCCIO'<0>:'(0,0,0,0,0,0,0,0,0,0,0,0,0,0,0,0,0,0,0,0,0,EE10,0,0,0,0,0,0,0,0)~
';
    'VCCIO_SENSE':'(0,0,0,0,0,0,0,0,0,0,0,0,0,0,0,0,0,0,0,0,0,BH5,0,0,0,0,0,0,0,~
0)';$S;
    'VCCSA'<25>:'(0,0,0,0,0,0,0,0,0,0,0,0,0,0,0,0,0,0,0,0,CB65,0,0,0,0,0,0,0,0,0~
)';
    'VCCSA'<24>:'(0,0,0,0,0,0,0,0,0,0,0,0,0,0,0,0,0,0,0,0,CB67,0,0,0,0,0,0,0,0,0~
)';
    'VCCSA'<23>:'(0,0,0,0,0,0,0,0,0,0,0,0,0,0,0,0,0,0,0,0,CB69,0,0,0,0,0,0,0,0,0~
)';
    'VCCSA'<22>:'(0,0,0,0,0,0,0,0,0,0,0,0,0,0,0,0,0,0,0,0,CC66,0,0,0,0,0,0,0,0,0~
)';
    'VCCSA'<21>:'(0,0,0,0,0,0,0,0,0,0,0,0,0,0,0,0,0,0,0,0,CC68,0,0,0,0,0,0,0,0,0~
)';
    'VCCSA'<20>:'(0,0,0,0,0,0,0,0,0,0,0,0,0,0,0,0,0,0,0,0,CC70,0,0,0,0,0,0,0,0,0~
)';
    'VCCSA'<19>:'(0,0,0,0,0,0,0,0,0,0,0,0,0,0,0,0,0,0,0,0,CD65,0,0,0,0,0,0,0,0,0~
)';
    'VCCSA'<18>:'(0,0,0,0,0,0,0,0,0,0,0,0,0,0,0,0,0,0,0,0,CD67,0,0,0,0,0,0,0,0,0~
)';
    'VCCSA'<17>:'(0,0,0,0,0,0,0,0,0,0,0,0,0,0,0,0,0,0,0,0,CD69,0,0,0,0,0,0,0,0,0~
)';
    'VCCSA'<16>:'(0,0,0,0,0,0,0,0,0,0,0,0,0,0,0,0,0,0,0,0,CD71,0,0,0,0,0,0,0,0,0~
)';
    'VCCSA'<15>:'(0,0,0,0,0,0,0,0,0,0,0,0,0,0,0,0,0,0,0,0,CE64,0,0,0,0,0,0,0,0,0~
)';
    'VCCSA'<14>:'(0,0,0,0,0,0,0,0,0,0,0,0,0,0,0,0,0,0,0,0,CE66,0,0,0,0,0,0,0,0,0~
)';
    'VCCSA'<13>:'(0,0,0,0,0,0,0,0,0,0,0,0,0,0,0,0,0,0,0,0,CE68,0,0,0,0,0,0,0,0,0~
)';
    'VCCSA'<12>:'(0,0,0,0,0,0,0,0,0,0,0,0,0,0,0,0,0,0,0,0,CE72,0,0,0,0,0,0,0,0,0~
)';
    'VCCSA'<11>:'(0,0,0,0,0,0,0,0,0,0,0,0,0,0,0,0,0,0,0,0,CE74,0,0,0,0,0,0,0,0,0~
)';
    'VCCSA'<10>:'(0,0,0,0,0,0,0,0,0,0,0,0,0,0,0,0,0,0,0,0,CF65,0,0,0,0,0,0,0,0,0~
)';
    'VCCSA'<9>:'(0,0,0,0,0,0,0,0,0,0,0,0,0,0,0,0,0,0,0,0,CF67,0,0,0,0,0,0,0,0,0)~
';
    'VCCSA'<8>:'(0,0,0,0,0,0,0,0,0,0,0,0,0,0,0,0,0,0,0,0,CF73,0,0,0,0,0,0,0,0,0)~
';
    'VCCSA'<7>:'(0,0,0,0,0,0,0,0,0,0,0,0,0,0,0,0,0,0,0,0,CF75,0,0,0,0,0,0,0,0,0)~
';
    'VCCSA'<6>:'(0,0,0,0,0,0,0,0,0,0,0,0,0,0,0,0,0,0,0,0,CG64,0,0,0,0,0,0,0,0,0)~
';
    'VCCSA'<5>:'(0,0,0,0,0,0,0,0,0,0,0,0,0,0,0,0,0,0,0,0,CG66,0,0,0,0,0,0,0,0,0)~
';
    'VCCSA'<4>:'(0,0,0,0,0,0,0,0,0,0,0,0,0,0,0,0,0,0,0,0,CG74,0,0,0,0,0,0,0,0,0)~
';
    'VCCSA'<3>:'(0,0,0,0,0,0,0,0,0,0,0,0,0,0,0,0,0,0,0,0,CH65,0,0,0,0,0,0,0,0,0)~
';
    'VCCSA'<2>:'(0,0,0,0,0,0,0,0,0,0,0,0,0,0,0,0,0,0,0,0,CH75,0,0,0,0,0,0,0,0,0)~
';
    'VCCSA'<1>:'(0,0,0,0,0,0,0,0,0,0,0,0,0,0,0,0,0,0,0,0,CJ64,0,0,0,0,0,0,0,0,0)~
';
    'VCCSA'<0>:'(0,0,0,0,0,0,0,0,0,0,0,0,0,0,0,0,0,0,0,0,CJ66,0,0,0,0,0,0,0,0,0)~
';
    'VCCSA_SENSE':'(0,0,0,0,0,0,0,0,0,0,0,0,0,0,0,0,0,0,0,0,0,CE76,0,0,0,0,0,0,0~
,0)';$S;
    'VSENSEPMAX':'(0,0,0,0,0,0,0,0,0,0,0,0,0,0,0,0,0,0,AD41,0,0,0,0,0,0,0,0,0,0,~
0)';$S;
    'VSS'<1253>:'(0,0,0,0,0,0,0,0,0,0,0,0,0,0,0,0,0,0,0,0,0,0,B9,0,0,0,0,0,0,0)';
    'VSS'<1252>:'(0,0,0,0,0,0,0,0,0,0,0,0,0,0,0,0,0,0,0,0,0,0,A42,0,0,0,0,0,0,0)~
';
    'VSS'<1251>:'(0,0,0,0,0,0,0,0,0,0,0,0,0,0,0,0,0,0,0,0,0,0,B43,0,0,0,0,0,0,0)~
';
    'VSS'<1250>:'(0,0,0,0,0,0,0,0,0,0,0,0,0,0,0,0,0,0,0,0,0,0,B5,0,0,0,0,0,0,0)';
    'VSS'<1249>:'(0,0,0,0,0,0,0,0,0,0,0,0,0,0,0,0,0,0,0,0,0,0,B79,0,0,0,0,0,0,0)~
';
    'VSS'<1248>:'(0,0,0,0,0,0,0,0,0,0,0,0,0,0,0,0,0,0,0,0,0,0,C4,0,0,0,0,0,0,0)';
    'VSS'<1247>:'(0,0,0,0,0,0,0,0,0,0,0,0,0,0,0,0,0,0,0,0,0,0,C80,0,0,0,0,0,0,0)~
';
    'VSS'<1246>:'(0,0,0,0,0,0,0,0,0,0,0,0,0,0,0,0,0,0,0,0,0,0,D3,0,0,0,0,0,0,0)';
    'VSS'<1245>:'(0,0,0,0,0,0,0,0,0,0,0,0,0,0,0,0,0,0,0,0,0,0,D81,0,0,0,0,0,0,0)~
';
    'VSS'<1244>:'(0,0,0,0,0,0,0,0,0,0,0,0,0,0,0,0,0,0,0,0,0,0,E82,0,0,0,0,0,0,0)~
';
    'VSS'<1243>:'(0,0,0,0,0,0,0,0,0,0,0,0,0,0,0,0,0,0,0,0,0,0,J86,0,0,0,0,0,0,0)~
';
    'VSS'<1242>:'(0,0,0,0,0,0,0,0,0,0,0,0,0,0,0,0,0,0,0,0,0,0,DY85,0,0,0,0,0,0,0~
)';
    'VSS'<1241>:'(0,0,0,0,0,0,0,0,0,0,0,0,0,0,0,0,0,0,0,0,0,0,EA84,0,0,0,0,0,0,0~
)';
    'VSS'<1240>:'(0,0,0,0,0,0,0,0,0,0,0,0,0,0,0,0,0,0,0,0,0,0,EB83,0,0,0,0,0,0,0~
)';
    'VSS'<1239>:'(0,0,0,0,0,0,0,0,0,0,0,0,0,0,0,0,0,0,0,0,0,0,DW2,0,0,0,0,0,0,0)~
';
    'VSS'<1238>:'(0,0,0,0,0,0,0,0,0,0,0,0,0,0,0,0,0,0,0,0,0,0,EC42,0,0,0,0,0,0,0~
)';
    'VSS'<1237>:'(0,0,0,0,0,0,0,0,0,0,0,0,0,0,0,0,0,0,0,0,0,0,EC6,0,0,0,0,0,0,0)~
';
    'VSS'<1236>:'(0,0,0,0,0,0,0,0,0,0,0,0,0,0,0,0,0,0,0,0,0,0,EC82,0,0,0,0,0,0,0~
)';
    'VSS'<1235>:'(0,0,0,0,0,0,0,0,0,0,0,0,0,0,0,0,0,0,0,0,0,0,ED41,0,0,0,0,0,0,0~
)';
    'VSS'<1234>:'(0,0,0,0,0,0,0,0,0,0,0,0,0,0,0,0,0,0,0,0,0,0,ED7,0,0,0,0,0,0,0)~
';
    'VSS'<1233>:'(0,0,0,0,0,0,0,0,0,0,0,0,0,0,0,0,0,0,0,0,0,0,ED81,0,0,0,0,0,0,0~
)';
    'VSS'<1232>:'(0,0,0,0,0,0,0,0,0,0,0,0,0,0,0,0,0,0,0,0,0,0,EE40,0,0,0,0,0,0,0~
)';
    'VSS'<1231>:'(0,0,0,0,0,0,0,0,0,0,0,0,0,0,0,0,0,0,0,0,0,0,EE8,0,0,0,0,0,0,0)~
';
    'VSS'<1230>:'(0,0,0,0,0,0,0,0,0,0,0,0,0,0,0,0,0,0,0,0,0,0,EE80,0,0,0,0,0,0,0~
)';
    'VSS'<1229>:'(0,0,0,0,0,0,0,0,0,0,0,0,0,0,0,0,0,0,0,0,0,0,ED69,0,0,0,0,0,0,0~
)';
    'VSS'<1228>:'(0,0,0,0,0,0,0,0,0,0,0,0,0,0,0,0,0,0,0,0,0,0,E66,0,0,0,0,0,0,0)~
';
    'VSS'<1227>:'(0,0,0,0,0,0,0,0,0,0,0,0,0,0,0,0,0,0,0,0,0,0,V11,0,0,0,0,0,0,0)~
';
    'VSS'<1226>:'(0,0,0,0,0,0,0,0,0,0,0,0,0,0,0,0,0,0,0,0,0,0,L8,0,0,0,0,0,0,0)';
    'VSS'<1225>:'(0,0,0,0,0,0,0,0,0,0,0,0,0,0,0,0,0,0,0,0,0,0,EA14,0,0,0,0,0,0,0~
)';
    'VSS'<1224>:'(0,0,0,0,0,0,0,0,0,0,0,0,0,0,0,0,0,0,0,0,0,0,DY63,0,0,0,0,0,0,0~
)';
    'VSS'<1223>:'(0,0,0,0,0,0,0,0,0,0,0,0,0,0,0,0,0,0,0,0,0,0,DY61,0,0,0,0,0,0,0~
)';
    'VSS'<1222>:'(0,0,0,0,0,0,0,0,0,0,0,0,0,0,0,0,0,0,0,0,0,0,DY59,0,0,0,0,0,0,0~
)';
    'VSS'<1221>:'(0,0,0,0,0,0,0,0,0,0,0,0,0,0,0,0,0,0,0,0,0,0,DY57,0,0,0,0,0,0,0~
)';
    'VSS'<1220>:'(0,0,0,0,0,0,0,0,0,0,0,0,0,0,0,0,0,0,0,0,0,0,DY55,0,0,0,0,0,0,0~
)';
    'VSS'<1219>:'(0,0,0,0,0,0,0,0,0,0,0,0,0,0,0,0,0,0,0,0,0,0,DY53,0,0,0,0,0,0,0~
)';
    'VSS'<1218>:'(0,0,0,0,0,0,0,0,0,0,0,0,0,0,0,0,0,0,0,0,0,0,DY51,0,0,0,0,0,0,0~
)';
    'VSS'<1217>:'(0,0,0,0,0,0,0,0,0,0,0,0,0,0,0,0,0,0,0,0,0,0,DY49,0,0,0,0,0,0,0~
)';
    'VSS'<1216>:'(0,0,0,0,0,0,0,0,0,0,0,0,0,0,0,0,0,0,0,0,0,0,DY47,0,0,0,0,0,0,0~
)';
    'VSS'<1215>:'(0,0,0,0,0,0,0,0,0,0,0,0,0,0,0,0,0,0,0,0,0,0,DY45,0,0,0,0,0,0,0~
)';
    'VSS'<1214>:'(0,0,0,0,0,0,0,0,0,0,0,0,0,0,0,0,0,0,0,0,0,0,DV19,0,0,0,0,0,0,0~
)';
    'VSS'<1213>:'(0,0,0,0,0,0,0,0,0,0,0,0,0,0,0,0,0,0,0,0,0,0,DP9,0,0,0,0,0,0,0)~
';
    'VSS'<1212>:'(0,0,0,0,0,0,0,0,0,0,0,0,0,0,0,0,0,0,0,0,0,0,DP63,0,0,0,0,0,0,0~
)';
    'VSS'<1211>:'(0,0,0,0,0,0,0,0,0,0,0,0,0,0,0,0,0,0,0,0,0,0,DP61,0,0,0,0,0,0,0~
)';
    'VSS'<1210>:'(0,0,0,0,0,0,0,0,0,0,0,0,0,0,0,0,0,0,0,0,0,0,DP59,0,0,0,0,0,0,0~
)';
    'VSS'<1209>:'(0,0,0,0,0,0,0,0,0,0,0,0,0,0,0,0,0,0,0,0,0,0,DP57,0,0,0,0,0,0,0~
)';
    'VSS'<1208>:'(0,0,0,0,0,0,0,0,0,0,0,0,0,0,0,0,0,0,0,0,0,0,DP55,0,0,0,0,0,0,0~
)';
    'VSS'<1207>:'(0,0,0,0,0,0,0,0,0,0,0,0,0,0,0,0,0,0,0,0,0,0,DP53,0,0,0,0,0,0,0~
)';
    'VSS'<1206>:'(0,0,0,0,0,0,0,0,0,0,0,0,0,0,0,0,0,0,0,0,0,0,DP51,0,0,0,0,0,0,0~
)';
    'VSS'<1205>:'(0,0,0,0,0,0,0,0,0,0,0,0,0,0,0,0,0,0,0,0,0,0,DP49,0,0,0,0,0,0,0~
)';
    'VSS'<1204>:'(0,0,0,0,0,0,0,0,0,0,0,0,0,0,0,0,0,0,0,0,0,0,DP47,0,0,0,0,0,0,0~
)';
    'VSS'<1203>:'(0,0,0,0,0,0,0,0,0,0,0,0,0,0,0,0,0,0,0,0,0,0,DP45,0,0,0,0,0,0,0~
)';
    'VSS'<1202>:'(0,0,0,0,0,0,0,0,0,0,0,0,0,0,0,0,0,0,0,0,0,0,DN18,0,0,0,0,0,0,0~
)';
    'VSS'<1201>:'(0,0,0,0,0,0,0,0,0,0,0,0,0,0,0,0,0,0,0,0,0,0,DL8,0,0,0,0,0,0,0)~
';
    'VSS'<1200>:'(0,0,0,0,0,0,0,0,0,0,0,0,0,0,0,0,0,0,0,0,0,0,DE62,0,0,0,0,0,0,0~
)';
    'VSS'<1199>:'(0,0,0,0,0,0,0,0,0,0,0,0,0,0,0,0,0,0,0,0,0,0,DE60,0,0,0,0,0,0,0~
)';
    'VSS'<1198>:'(0,0,0,0,0,0,0,0,0,0,0,0,0,0,0,0,0,0,0,0,0,0,DE58,0,0,0,0,0,0,0~
)';
    'VSS'<1197>:'(0,0,0,0,0,0,0,0,0,0,0,0,0,0,0,0,0,0,0,0,0,0,DE56,0,0,0,0,0,0,0~
)';
    'VSS'<1196>:'(0,0,0,0,0,0,0,0,0,0,0,0,0,0,0,0,0,0,0,0,0,0,DE54,0,0,0,0,0,0,0~
)';
    'VSS'<1195>:'(0,0,0,0,0,0,0,0,0,0,0,0,0,0,0,0,0,0,0,0,0,0,DE52,0,0,0,0,0,0,0~
)';
    'VSS'<1194>:'(0,0,0,0,0,0,0,0,0,0,0,0,0,0,0,0,0,0,0,0,0,0,DE50,0,0,0,0,0,0,0~
)';
    'VSS'<1193>:'(0,0,0,0,0,0,0,0,0,0,0,0,0,0,0,0,0,0,0,0,0,0,DE48,0,0,0,0,0,0,0~
)';
    'VSS'<1192>:'(0,0,0,0,0,0,0,0,0,0,0,0,0,0,0,0,0,0,0,0,0,0,CW6,0,0,0,0,0,0,0)~
';
    'VSS'<1191>:'(0,0,0,0,0,0,0,0,0,0,0,0,0,0,0,0,0,0,0,0,0,0,CG6,0,0,0,0,0,0,0)~
';
    'VSS'<1190>:'(0,0,0,0,0,0,0,0,0,0,0,0,0,0,0,0,0,0,0,0,0,0,AR6,0,0,0,0,0,0,0)~
';
    'VSS'<1189>:'(0,0,0,0,0,0,0,0,0,0,0,0,0,0,0,0,0,0,0,0,0,0,AJ4,0,0,0,0,0,0,0)~
';
    'VSS'<1188>:'(0,0,0,0,0,0,0,0,0,0,0,0,0,0,0,0,0,0,0,0,0,0,AC62,0,0,0,0,0,0,0~
)';
    'VSS'<1187>:'(0,0,0,0,0,0,0,0,0,0,0,0,0,0,0,0,0,0,0,0,0,0,AC60,0,0,0,0,0,0,0~
)';
    'VSS'<1186>:'(0,0,0,0,0,0,0,0,0,0,0,0,0,0,0,0,0,0,0,0,0,0,AC58,0,0,0,0,0,0,0~
)';
    'VSS'<1185>:'(0,0,0,0,0,0,0,0,0,0,0,0,0,0,0,0,0,0,0,0,0,0,A26,0,0,0,0,0,0,0)~
';
    'VSS'<1184>:'(0,0,0,0,0,0,0,0,0,0,0,0,0,0,0,0,0,0,0,0,0,0,A30,0,0,0,0,0,0,0)~
';
    'VSS'<1183>:'(0,0,0,0,0,0,0,0,0,0,0,0,0,0,0,0,0,0,0,0,0,0,A32,0,0,0,0,0,0,0)~
';
    'VSS'<1182>:'(0,0,0,0,0,0,0,0,0,0,0,0,0,0,0,0,0,0,0,0,0,0,A36,0,0,0,0,0,0,0)~
';
    'VSS'<1181>:'(0,0,0,0,0,0,0,0,0,0,0,0,0,0,0,0,0,0,0,0,0,0,A38,0,0,0,0,0,0,0)~
';
    'VSS'<1180>:'(0,0,0,0,0,0,0,0,0,0,0,0,0,0,0,0,0,0,0,0,0,0,B25,0,0,0,0,0,0,0)~
';
    'VSS'<1179>:'(0,0,0,0,0,0,0,0,0,0,0,0,0,0,0,0,0,0,0,0,0,0,B31,0,0,0,0,0,0,0)~
';
    'VSS'<1178>:'(0,0,0,0,0,0,0,0,0,0,0,0,0,0,0,0,0,0,0,0,0,0,B37,0,0,0,0,0,0,0)~
';
    'VSS'<1177>:'(0,0,0,0,0,0,0,0,0,0,0,0,0,0,0,0,0,0,0,0,0,0,B71,0,0,0,0,0,0,0)~
';
    'VSS'<1176>:'(0,0,0,0,0,0,0,0,0,0,0,0,0,0,0,0,0,0,0,0,0,0,B75,0,0,0,0,0,0,0)~
';
    'VSS'<1175>:'(0,0,0,0,0,0,0,0,0,0,0,0,0,0,0,0,0,0,0,0,0,0,C8,0,0,0,0,0,0,0)';
    'VSS'<1174>:'(0,0,0,0,0,0,0,0,0,0,0,0,0,0,0,0,0,0,0,0,0,0,C10,0,0,0,0,0,0,0)~
';
    'VSS'<1173>:'(0,0,0,0,0,0,0,0,0,0,0,0,0,0,0,0,0,0,0,0,0,0,C12,0,0,0,0,0,0,0)~
';
    'VSS'<1172>:'(0,0,0,0,0,0,0,0,0,0,0,0,0,0,0,0,0,0,0,0,0,0,C14,0,0,0,0,0,0,0)~
';
    'VSS'<1171>:'(0,0,0,0,0,0,0,0,0,0,0,0,0,0,0,0,0,0,0,0,0,0,C16,0,0,0,0,0,0,0)~
';
    'VSS'<1170>:'(0,0,0,0,0,0,0,0,0,0,0,0,0,0,0,0,0,0,0,0,0,0,C76,0,0,0,0,0,0,0)~
';
    'VSS'<1169>:'(0,0,0,0,0,0,0,0,0,0,0,0,0,0,0,0,0,0,0,0,0,0,C78,0,0,0,0,0,0,0)~
';
    'VSS'<1168>:'(0,0,0,0,0,0,0,0,0,0,0,0,0,0,0,0,0,0,0,0,0,0,CM27,0,0,0,0,0,0,0~
)';
    'VSS'<1167>:'(0,0,0,0,0,0,0,0,0,0,0,0,0,0,0,0,0,0,0,0,0,0,D11,0,0,0,0,0,0,0)~
';
    'VSS'<1166>:'(0,0,0,0,0,0,0,0,0,0,0,0,0,0,0,0,0,0,0,0,0,0,D13,0,0,0,0,0,0,0)~
';
    'VSS'<1165>:'(0,0,0,0,0,0,0,0,0,0,0,0,0,0,0,0,0,0,0,0,0,0,D25,0,0,0,0,0,0,0)~
';
    'VSS'<1164>:'(0,0,0,0,0,0,0,0,0,0,0,0,0,0,0,0,0,0,0,0,0,0,D27,0,0,0,0,0,0,0)~
';
    'VSS'<1163>:'(0,0,0,0,0,0,0,0,0,0,0,0,0,0,0,0,0,0,0,0,0,0,D29,0,0,0,0,0,0,0)~
';
    'VSS'<1162>:'(0,0,0,0,0,0,0,0,0,0,0,0,0,0,0,0,0,0,0,0,0,0,D31,0,0,0,0,0,0,0)~
';
    'VSS'<1161>:'(0,0,0,0,0,0,0,0,0,0,0,0,0,0,0,0,0,0,0,0,0,0,D33,0,0,0,0,0,0,0)~
';
    'VSS'<1160>:'(0,0,0,0,0,0,0,0,0,0,0,0,0,0,0,0,0,0,0,0,0,0,D35,0,0,0,0,0,0,0)~
';
    'VSS'<1159>:'(0,0,0,0,0,0,0,0,0,0,0,0,0,0,0,0,0,0,0,0,0,0,D37,0,0,0,0,0,0,0)~
';
    'VSS'<1158>:'(0,0,0,0,0,0,0,0,0,0,0,0,0,0,0,0,0,0,0,0,0,0,D39,0,0,0,0,0,0,0)~
';
    'VSS'<1157>:'(0,0,0,0,0,0,0,0,0,0,0,0,0,0,0,0,0,0,0,0,0,0,D41,0,0,0,0,0,0,0)~
';
    'VSS'<1156>:'(0,0,0,0,0,0,0,0,0,0,0,0,0,0,0,0,0,0,0,0,0,0,D43,0,0,0,0,0,0,0)~
';
    'VSS'<1155>:'(0,0,0,0,0,0,0,0,0,0,0,0,0,0,0,0,0,0,0,0,0,0,D77,0,0,0,0,0,0,0)~
';
    'VSS'<1154>:'(0,0,0,0,0,0,0,0,0,0,0,0,0,0,0,0,0,0,0,0,0,0,E6,0,0,0,0,0,0,0)';
    'VSS'<1153>:'(0,0,0,0,0,0,0,0,0,0,0,0,0,0,0,0,0,0,0,0,0,0,E8,0,0,0,0,0,0,0)';
    'VSS'<1152>:'(0,0,0,0,0,0,0,0,0,0,0,0,0,0,0,0,0,0,0,0,0,0,E16,0,0,0,0,0,0,0)~
';
    'VSS'<1151>:'(0,0,0,0,0,0,0,0,0,0,0,0,0,0,0,0,0,0,0,0,0,0,E18,0,0,0,0,0,0,0)~
';
    'VSS'<1150>:'(0,0,0,0,0,0,0,0,0,0,0,0,0,0,0,0,0,0,0,0,0,0,E20,0,0,0,0,0,0,0)~
';
    'VSS'<1149>:'(0,0,0,0,0,0,0,0,0,0,0,0,0,0,0,0,0,0,0,0,0,0,E22,0,0,0,0,0,0,0)~
';
    'VSS'<1148>:'(0,0,0,0,0,0,0,0,0,0,0,0,0,0,0,0,0,0,0,0,0,0,E72,0,0,0,0,0,0,0)~
';
    'VSS'<1147>:'(0,0,0,0,0,0,0,0,0,0,0,0,0,0,0,0,0,0,0,0,0,0,E74,0,0,0,0,0,0,0)~
';
    'VSS'<1146>:'(0,0,0,0,0,0,0,0,0,0,0,0,0,0,0,0,0,0,0,0,0,0,E76,0,0,0,0,0,0,0)~
';
    'VSS'<1145>:'(0,0,0,0,0,0,0,0,0,0,0,0,0,0,0,0,0,0,0,0,0,0,F5,0,0,0,0,0,0,0)';
    'VSS'<1144>:'(0,0,0,0,0,0,0,0,0,0,0,0,0,0,0,0,0,0,0,0,0,0,F17,0,0,0,0,0,0,0)~
';
    'VSS'<1143>:'(0,0,0,0,0,0,0,0,0,0,0,0,0,0,0,0,0,0,0,0,0,0,F19,0,0,0,0,0,0,0)~
';
    'VSS'<1142>:'(0,0,0,0,0,0,0,0,0,0,0,0,0,0,0,0,0,0,0,0,0,0,F25,0,0,0,0,0,0,0)~
';
    'VSS'<1141>:'(0,0,0,0,0,0,0,0,0,0,0,0,0,0,0,0,0,0,0,0,0,0,F31,0,0,0,0,0,0,0)~
';
    'VSS'<1140>:'(0,0,0,0,0,0,0,0,0,0,0,0,0,0,0,0,0,0,0,0,0,0,F37,0,0,0,0,0,0,0)~
';
    'VSS'<1139>:'(0,0,0,0,0,0,0,0,0,0,0,0,0,0,0,0,0,0,0,0,0,0,F43,0,0,0,0,0,0,0)~
';
    'VSS'<1138>:'(0,0,0,0,0,0,0,0,0,0,0,0,0,0,0,0,0,0,0,0,0,0,F67,0,0,0,0,0,0,0)~
';
    'VSS'<1137>:'(0,0,0,0,0,0,0,0,0,0,0,0,0,0,0,0,0,0,0,0,0,0,F69,0,0,0,0,0,0,0)~
';
    'VSS'<1136>:'(0,0,0,0,0,0,0,0,0,0,0,0,0,0,0,0,0,0,0,0,0,0,G4,0,0,0,0,0,0,0)';
    'VSS'<1135>:'(0,0,0,0,0,0,0,0,0,0,0,0,0,0,0,0,0,0,0,0,0,0,G8,0,0,0,0,0,0,0)';
    'VSS'<1134>:'(0,0,0,0,0,0,0,0,0,0,0,0,0,0,0,0,0,0,0,0,0,0,G22,0,0,0,0,0,0,0)~
';
    'VSS'<1133>:'(0,0,0,0,0,0,0,0,0,0,0,0,0,0,0,0,0,0,0,0,0,0,G24,0,0,0,0,0,0,0)~
';
    'VSS'<1132>:'(0,0,0,0,0,0,0,0,0,0,0,0,0,0,0,0,0,0,0,0,0,0,G26,0,0,0,0,0,0,0)~
';
    'VSS'<1131>:'(0,0,0,0,0,0,0,0,0,0,0,0,0,0,0,0,0,0,0,0,0,0,G30,0,0,0,0,0,0,0)~
';
    'VSS'<1130>:'(0,0,0,0,0,0,0,0,0,0,0,0,0,0,0,0,0,0,0,0,0,0,G32,0,0,0,0,0,0,0)~
';
    'VSS'<1129>:'(0,0,0,0,0,0,0,0,0,0,0,0,0,0,0,0,0,0,0,0,0,0,G36,0,0,0,0,0,0,0)~
';
    'VSS'<1128>:'(0,0,0,0,0,0,0,0,0,0,0,0,0,0,0,0,0,0,0,0,0,0,G38,0,0,0,0,0,0,0)~
';
    'VSS'<1127>:'(0,0,0,0,0,0,0,0,0,0,0,0,0,0,0,0,0,0,0,0,0,0,G42,0,0,0,0,0,0,0)~
';
    'VSS'<1126>:'(0,0,0,0,0,0,0,0,0,0,0,0,0,0,0,0,0,0,0,0,0,0,G66,0,0,0,0,0,0,0)~
';
    'VSS'<1125>:'(0,0,0,0,0,0,0,0,0,0,0,0,0,0,0,0,0,0,0,0,0,0,G70,0,0,0,0,0,0,0)~
';
    'VSS'<1124>:'(0,0,0,0,0,0,0,0,0,0,0,0,0,0,0,0,0,0,0,0,0,0,G76,0,0,0,0,0,0,0)~
';
    'VSS'<1123>:'(0,0,0,0,0,0,0,0,0,0,0,0,0,0,0,0,0,0,0,0,0,0,G78,0,0,0,0,0,0,0)~
';
    'VSS'<1122>:'(0,0,0,0,0,0,0,0,0,0,0,0,0,0,0,0,0,0,0,0,0,0,G80,0,0,0,0,0,0,0)~
';
    'VSS'<1121>:'(0,0,0,0,0,0,0,0,0,0,0,0,0,0,0,0,0,0,0,0,0,0,G82,0,0,0,0,0,0,0)~
';
    'VSS'<1120>:'(0,0,0,0,0,0,0,0,0,0,0,0,0,0,0,0,0,0,0,0,0,0,H3,0,0,0,0,0,0,0)';
    'VSS'<1119>:'(0,0,0,0,0,0,0,0,0,0,0,0,0,0,0,0,0,0,0,0,0,0,H11,0,0,0,0,0,0,0)~
';
    'VSS'<1118>:'(0,0,0,0,0,0,0,0,0,0,0,0,0,0,0,0,0,0,0,0,0,0,H25,0,0,0,0,0,0,0)~
';
    'VSS'<1117>:'(0,0,0,0,0,0,0,0,0,0,0,0,0,0,0,0,0,0,0,0,0,0,H27,0,0,0,0,0,0,0)~
';
    'VSS'<1116>:'(0,0,0,0,0,0,0,0,0,0,0,0,0,0,0,0,0,0,0,0,0,0,H29,0,0,0,0,0,0,0)~
';
    'VSS'<1115>:'(0,0,0,0,0,0,0,0,0,0,0,0,0,0,0,0,0,0,0,0,0,0,H31,0,0,0,0,0,0,0)~
';
    'VSS'<1114>:'(0,0,0,0,0,0,0,0,0,0,0,0,0,0,0,0,0,0,0,0,0,0,H33,0,0,0,0,0,0,0)~
';
    'VSS'<1113>:'(0,0,0,0,0,0,0,0,0,0,0,0,0,0,0,0,0,0,0,0,0,0,H35,0,0,0,0,0,0,0)~
';
    'VSS'<1112>:'(0,0,0,0,0,0,0,0,0,0,0,0,0,0,0,0,0,0,0,0,0,0,H37,0,0,0,0,0,0,0)~
';
    'VSS'<1111>:'(0,0,0,0,0,0,0,0,0,0,0,0,0,0,0,0,0,0,0,0,0,0,H39,0,0,0,0,0,0,0)~
';
    'VSS'<1110>:'(0,0,0,0,0,0,0,0,0,0,0,0,0,0,0,0,0,0,0,0,0,0,H41,0,0,0,0,0,0,0)~
';
    'VSS'<1109>:'(0,0,0,0,0,0,0,0,0,0,0,0,0,0,0,0,0,0,0,0,0,0,H65,0,0,0,0,0,0,0)~
';
    'VSS'<1108>:'(0,0,0,0,0,0,0,0,0,0,0,0,0,0,0,0,0,0,0,0,0,0,H71,0,0,0,0,0,0,0)~
';
    'VSS'<1107>:'(0,0,0,0,0,0,0,0,0,0,0,0,0,0,0,0,0,0,0,0,0,0,H75,0,0,0,0,0,0,0)~
';
    'VSS'<1106>:'(0,0,0,0,0,0,0,0,0,0,0,0,0,0,0,0,0,0,0,0,0,0,DN44,0,0,0,0,0,0,0~
)';
    'VSS'<1105>:'(0,0,0,0,0,0,0,0,0,0,0,0,0,0,0,0,0,0,0,0,0,0,J4,0,0,0,0,0,0,0)';
    'VSS'<1104>:'(0,0,0,0,0,0,0,0,0,0,0,0,0,0,0,0,0,0,0,0,0,0,J12,0,0,0,0,0,0,0)~
';
    'VSS'<1103>:'(0,0,0,0,0,0,0,0,0,0,0,0,0,0,0,0,0,0,0,0,0,0,J14,0,0,0,0,0,0,0)~
';
    'VSS'<1102>:'(0,0,0,0,0,0,0,0,0,0,0,0,0,0,0,0,0,0,0,0,0,0,J22,0,0,0,0,0,0,0)~
';
    'VSS'<1101>:'(0,0,0,0,0,0,0,0,0,0,0,0,0,0,0,0,0,0,0,0,0,0,J26,0,0,0,0,0,0,0)~
';
    'VSS'<1100>:'(0,0,0,0,0,0,0,0,0,0,0,0,0,0,0,0,0,0,0,0,0,0,J28,0,0,0,0,0,0,0)~
';
    'VSS'<1099>:'(0,0,0,0,0,0,0,0,0,0,0,0,0,0,0,0,0,0,0,0,0,0,J32,0,0,0,0,0,0,0)~
';
    'VSS'<1098>:'(0,0,0,0,0,0,0,0,0,0,0,0,0,0,0,0,0,0,0,0,0,0,J34,0,0,0,0,0,0,0)~
';
    'VSS'<1097>:'(0,0,0,0,0,0,0,0,0,0,0,0,0,0,0,0,0,0,0,0,0,0,J38,0,0,0,0,0,0,0)~
';
    'VSS'<1096>:'(0,0,0,0,0,0,0,0,0,0,0,0,0,0,0,0,0,0,0,0,0,0,J40,0,0,0,0,0,0,0)~
';
    'VSS'<1095>:'(0,0,0,0,0,0,0,0,0,0,0,0,0,0,0,0,0,0,0,0,0,0,J72,0,0,0,0,0,0,0)~
';
    'VSS'<1094>:'(0,0,0,0,0,0,0,0,0,0,0,0,0,0,0,0,0,0,0,0,0,0,J74,0,0,0,0,0,0,0)~
';
    'VSS'<1093>:'(0,0,0,0,0,0,0,0,0,0,0,0,0,0,0,0,0,0,0,0,0,0,0,J76,0,0,0,0,0,0)~
';
    'VSS'<1092>:'(0,0,0,0,0,0,0,0,0,0,0,0,0,0,0,0,0,0,0,0,0,0,0,J82,0,0,0,0,0,0)~
';
    'VSS'<1091>:'(0,0,0,0,0,0,0,0,0,0,0,0,0,0,0,0,0,0,0,0,0,0,0,J84,0,0,0,0,0,0)~
';
    'VSS'<1090>:'(0,0,0,0,0,0,0,0,0,0,0,0,0,0,0,0,0,0,0,0,0,0,0,K1,0,0,0,0,0,0)';
    'VSS'<1089>:'(0,0,0,0,0,0,0,0,0,0,0,0,0,0,0,0,0,0,0,0,0,0,0,K11,0,0,0,0,0,0)~
';
    'VSS'<1088>:'(0,0,0,0,0,0,0,0,0,0,0,0,0,0,0,0,0,0,0,0,0,0,0,K13,0,0,0,0,0,0)~
';
    'VSS'<1087>:'(0,0,0,0,0,0,0,0,0,0,0,0,0,0,0,0,0,0,0,0,0,0,0,K17,0,0,0,0,0,0)~
';
    'VSS'<1086>:'(0,0,0,0,0,0,0,0,0,0,0,0,0,0,0,0,0,0,0,0,0,0,0,DB7,0,0,0,0,0,0)~
';
    'VSS'<1085>:'(0,0,0,0,0,0,0,0,0,0,0,0,0,0,0,0,0,0,0,0,0,0,0,K27,0,0,0,0,0,0)~
';
    'VSS'<1084>:'(0,0,0,0,0,0,0,0,0,0,0,0,0,0,0,0,0,0,0,0,0,0,0,K33,0,0,0,0,0,0)~
';
    'VSS'<1083>:'(0,0,0,0,0,0,0,0,0,0,0,0,0,0,0,0,0,0,0,0,0,0,0,K39,0,0,0,0,0,0)~
';
    'VSS'<1082>:'(0,0,0,0,0,0,0,0,0,0,0,0,0,0,0,0,0,0,0,0,0,0,0,K65,0,0,0,0,0,0)~
';
    'VSS'<1081>:'(0,0,0,0,0,0,0,0,0,0,0,0,0,0,0,0,0,0,0,0,0,0,0,K67,0,0,0,0,0,0)~
';
    'VSS'<1080>:'(0,0,0,0,0,0,0,0,0,0,0,0,0,0,0,0,0,0,0,0,0,0,0,K69,0,0,0,0,0,0)~
';
    'VSS'<1079>:'(0,0,0,0,0,0,0,0,0,0,0,0,0,0,0,0,0,0,0,0,0,0,0,K71,0,0,0,0,0,0)~
';
    'VSS'<1078>:'(0,0,0,0,0,0,0,0,0,0,0,0,0,0,0,0,0,0,0,0,0,0,0,K73,0,0,0,0,0,0)~
';
    'VSS'<1077>:'(0,0,0,0,0,0,0,0,0,0,0,0,0,0,0,0,0,0,0,0,0,0,0,K77,0,0,0,0,0,0)~
';
    'VSS'<1076>:'(0,0,0,0,0,0,0,0,0,0,0,0,0,0,0,0,0,0,0,0,0,0,0,K81,0,0,0,0,0,0)~
';
    'VSS'<1075>:'(0,0,0,0,0,0,0,0,0,0,0,0,0,0,0,0,0,0,0,0,0,0,0,K83,0,0,0,0,0,0)~
';
    'VSS'<1074>:'(0,0,0,0,0,0,0,0,0,0,0,0,0,0,0,0,0,0,0,0,0,0,0,K85,0,0,0,0,0,0)~
';
    'VSS'<1073>:'(0,0,0,0,0,0,0,0,0,0,0,0,0,0,0,0,0,0,0,0,0,0,0,L10,0,0,0,0,0,0)~
';
    'VSS'<1072>:'(0,0,0,0,0,0,0,0,0,0,0,0,0,0,0,0,0,0,0,0,0,0,0,L2,0,0,0,0,0,0)';
    'VSS'<1071>:'(0,0,0,0,0,0,0,0,0,0,0,0,0,0,0,0,0,0,0,0,0,0,0,L6,0,0,0,0,0,0)';
    'VSS'<1070>:'(0,0,0,0,0,0,0,0,0,0,0,0,0,0,0,0,0,0,0,0,0,0,0,L20,0,0,0,0,0,0)~
';
    'VSS'<1069>:'(0,0,0,0,0,0,0,0,0,0,0,0,0,0,0,0,0,0,0,0,0,0,0,L22,0,0,0,0,0,0)~
';
    'VSS'<1068>:'(0,0,0,0,0,0,0,0,0,0,0,0,0,0,0,0,0,0,0,0,0,0,0,L72,0,0,0,0,0,0)~
';
    'VSS'<1067>:'(0,0,0,0,0,0,0,0,0,0,0,0,0,0,0,0,0,0,0,0,0,0,0,L78,0,0,0,0,0,0)~
';
    'VSS'<1066>:'(0,0,0,0,0,0,0,0,0,0,0,0,0,0,0,0,0,0,0,0,0,0,0,L80,0,0,0,0,0,0)~
';
    'VSS'<1065>:'(0,0,0,0,0,0,0,0,0,0,0,0,0,0,0,0,0,0,0,0,0,0,0,L82,0,0,0,0,0,0)~
';
    'VSS'<1064>:'(0,0,0,0,0,0,0,0,0,0,0,0,0,0,0,0,0,0,0,0,0,0,0,BT9,0,0,0,0,0,0)~
';
    'VSS'<1063>:'(0,0,0,0,0,0,0,0,0,0,0,0,0,0,0,0,0,0,0,0,0,0,0,CT7,0,0,0,0,0,0)~
';
    'VSS'<1062>:'(0,0,0,0,0,0,0,0,0,0,0,0,0,0,0,0,0,0,0,0,0,0,0,M15,0,0,0,0,0,0)~
';
    'VSS'<1061>:'(0,0,0,0,0,0,0,0,0,0,0,0,0,0,0,0,0,0,0,0,0,0,0,M17,0,0,0,0,0,0)~
';
    'VSS'<1060>:'(0,0,0,0,0,0,0,0,0,0,0,0,0,0,0,0,0,0,0,0,0,0,0,M19,0,0,0,0,0,0)~
';
    'VSS'<1059>:'(0,0,0,0,0,0,0,0,0,0,0,0,0,0,0,0,0,0,0,0,0,0,0,M23,0,0,0,0,0,0)~
';
    'VSS'<1058>:'(0,0,0,0,0,0,0,0,0,0,0,0,0,0,0,0,0,0,0,0,0,0,0,M25,0,0,0,0,0,0)~
';
    'VSS'<1057>:'(0,0,0,0,0,0,0,0,0,0,0,0,0,0,0,0,0,0,0,0,0,0,0,M27,0,0,0,0,0,0)~
';
    'VSS'<1056>:'(0,0,0,0,0,0,0,0,0,0,0,0,0,0,0,0,0,0,0,0,0,0,0,M29,0,0,0,0,0,0)~
';
    'VSS'<1055>:'(0,0,0,0,0,0,0,0,0,0,0,0,0,0,0,0,0,0,0,0,0,0,0,M31,0,0,0,0,0,0)~
';
    'VSS'<1054>:'(0,0,0,0,0,0,0,0,0,0,0,0,0,0,0,0,0,0,0,0,0,0,0,M33,0,0,0,0,0,0)~
';
    'VSS'<1053>:'(0,0,0,0,0,0,0,0,0,0,0,0,0,0,0,0,0,0,0,0,0,0,0,M35,0,0,0,0,0,0)~
';
    'VSS'<1052>:'(0,0,0,0,0,0,0,0,0,0,0,0,0,0,0,0,0,0,0,0,0,0,0,M37,0,0,0,0,0,0)~
';
    'VSS'<1051>:'(0,0,0,0,0,0,0,0,0,0,0,0,0,0,0,0,0,0,0,0,0,0,0,M39,0,0,0,0,0,0)~
';
    'VSS'<1050>:'(0,0,0,0,0,0,0,0,0,0,0,0,0,0,0,0,0,0,0,0,0,0,0,M41,0,0,0,0,0,0)~
';
    'VSS'<1049>:'(0,0,0,0,0,0,0,0,0,0,0,0,0,0,0,0,0,0,0,0,0,0,0,M43,0,0,0,0,0,0)~
';
    'VSS'<1048>:'(0,0,0,0,0,0,0,0,0,0,0,0,0,0,0,0,0,0,0,0,0,0,0,M65,0,0,0,0,0,0)~
';
    'VSS'<1047>:'(0,0,0,0,0,0,0,0,0,0,0,0,0,0,0,0,0,0,0,0,0,0,0,M71,0,0,0,0,0,0)~
';
    'VSS'<1046>:'(0,0,0,0,0,0,0,0,0,0,0,0,0,0,0,0,0,0,0,0,0,0,0,M79,0,0,0,0,0,0)~
';
    'VSS'<1045>:'(0,0,0,0,0,0,0,0,0,0,0,0,0,0,0,0,0,0,0,0,0,0,0,M83,0,0,0,0,0,0)~
';
    'VSS'<1044>:'(0,0,0,0,0,0,0,0,0,0,0,0,0,0,0,0,0,0,0,0,0,0,0,M85,0,0,0,0,0,0)~
';
    'VSS'<1043>:'(0,0,0,0,0,0,0,0,0,0,0,0,0,0,0,0,0,0,0,0,0,0,0,DM19,0,0,0,0,0,0~
)';
    'VSS'<1042>:'(0,0,0,0,0,0,0,0,0,0,0,0,0,0,0,0,0,0,0,0,0,0,0,N20,0,0,0,0,0,0)~
';
    'VSS'<1041>:'(0,0,0,0,0,0,0,0,0,0,0,0,0,0,0,0,0,0,0,0,0,0,0,N22,0,0,0,0,0,0)~
';
    'VSS'<1040>:'(0,0,0,0,0,0,0,0,0,0,0,0,0,0,0,0,0,0,0,0,0,0,0,N6,0,0,0,0,0,0)';
    'VSS'<1039>:'(0,0,0,0,0,0,0,0,0,0,0,0,0,0,0,0,0,0,0,0,0,0,0,N66,0,0,0,0,0,0)~
';
    'VSS'<1038>:'(0,0,0,0,0,0,0,0,0,0,0,0,0,0,0,0,0,0,0,0,0,0,0,N70,0,0,0,0,0,0)~
';
    'VSS'<1037>:'(0,0,0,0,0,0,0,0,0,0,0,0,0,0,0,0,0,0,0,0,0,0,0,N72,0,0,0,0,0,0)~
';
    'VSS'<1036>:'(0,0,0,0,0,0,0,0,0,0,0,0,0,0,0,0,0,0,0,0,0,0,0,N74,0,0,0,0,0,0)~
';
    'VSS'<1035>:'(0,0,0,0,0,0,0,0,0,0,0,0,0,0,0,0,0,0,0,0,0,0,0,N76,0,0,0,0,0,0)~
';
    'VSS'<1034>:'(0,0,0,0,0,0,0,0,0,0,0,0,0,0,0,0,0,0,0,0,0,0,0,N78,0,0,0,0,0,0)~
';
    'VSS'<1033>:'(0,0,0,0,0,0,0,0,0,0,0,0,0,0,0,0,0,0,0,0,0,0,0,N4,0,0,0,0,0,0)';
    'VSS'<1032>:'(0,0,0,0,0,0,0,0,0,0,0,0,0,0,0,0,0,0,0,0,0,0,0,N8,0,0,0,0,0,0)';
    'VSS'<1031>:'(0,0,0,0,0,0,0,0,0,0,0,0,0,0,0,0,0,0,0,0,0,0,0,P11,0,0,0,0,0,0)~
';
    'VSS'<1030>:'(0,0,0,0,0,0,0,0,0,0,0,0,0,0,0,0,0,0,0,0,0,0,0,P15,0,0,0,0,0,0)~
';
    'VSS'<1029>:'(0,0,0,0,0,0,0,0,0,0,0,0,0,0,0,0,0,0,0,0,0,0,0,P27,0,0,0,0,0,0)~
';
    'VSS'<1028>:'(0,0,0,0,0,0,0,0,0,0,0,0,0,0,0,0,0,0,0,0,0,0,0,P33,0,0,0,0,0,0)~
';
    'VSS'<1027>:'(0,0,0,0,0,0,0,0,0,0,0,0,0,0,0,0,0,0,0,0,0,0,0,P39,0,0,0,0,0,0)~
';
    'VSS'<1026>:'(0,0,0,0,0,0,0,0,0,0,0,0,0,0,0,0,0,0,0,0,0,0,0,P67,0,0,0,0,0,0)~
';
    'VSS'<1025>:'(0,0,0,0,0,0,0,0,0,0,0,0,0,0,0,0,0,0,0,0,0,0,0,P69,0,0,0,0,0,0)~
';
    'VSS'<1024>:'(0,0,0,0,0,0,0,0,0,0,0,0,0,0,0,0,0,0,0,0,0,0,0,P71,0,0,0,0,0,0)~
';
    'VSS'<1023>:'(0,0,0,0,0,0,0,0,0,0,0,0,0,0,0,0,0,0,0,0,0,0,0,P81,0,0,0,0,0,0)~
';
    'VSS'<1022>:'(0,0,0,0,0,0,0,0,0,0,0,0,0,0,0,0,0,0,0,0,0,0,0,P83,0,0,0,0,0,0)~
';
    'VSS'<1021>:'(0,0,0,0,0,0,0,0,0,0,0,0,0,0,0,0,0,0,0,0,0,0,0,R14,0,0,0,0,0,0)~
';
    'VSS'<1020>:'(0,0,0,0,0,0,0,0,0,0,0,0,0,0,0,0,0,0,0,0,0,0,0,R18,0,0,0,0,0,0)~
';
    'VSS'<1019>:'(0,0,0,0,0,0,0,0,0,0,0,0,0,0,0,0,0,0,0,0,0,0,0,R2,0,0,0,0,0,0)';
    'VSS'<1018>:'(0,0,0,0,0,0,0,0,0,0,0,0,0,0,0,0,0,0,0,0,0,0,0,R4,0,0,0,0,0,0)';
    'VSS'<1017>:'(0,0,0,0,0,0,0,0,0,0,0,0,0,0,0,0,0,0,0,0,0,0,0,R22,0,0,0,0,0,0)~
';
    'VSS'<1016>:'(0,0,0,0,0,0,0,0,0,0,0,0,0,0,0,0,0,0,0,0,0,0,0,R26,0,0,0,0,0,0)~
';
    'VSS'<1015>:'(0,0,0,0,0,0,0,0,0,0,0,0,0,0,0,0,0,0,0,0,0,0,0,R28,0,0,0,0,0,0)~
';
    'VSS'<1014>:'(0,0,0,0,0,0,0,0,0,0,0,0,0,0,0,0,0,0,0,0,0,0,0,R32,0,0,0,0,0,0)~
';
    'VSS'<1013>:'(0,0,0,0,0,0,0,0,0,0,0,0,0,0,0,0,0,0,0,0,0,0,0,R34,0,0,0,0,0,0)~
';
    'VSS'<1012>:'(0,0,0,0,0,0,0,0,0,0,0,0,0,0,0,0,0,0,0,0,0,0,0,R38,0,0,0,0,0,0)~
';
    'VSS'<1011>:'(0,0,0,0,0,0,0,0,0,0,0,0,0,0,0,0,0,0,0,0,0,0,0,R40,0,0,0,0,0,0)~
';
    'VSS'<1010>:'(0,0,0,0,0,0,0,0,0,0,0,0,0,0,0,0,0,0,0,0,0,0,0,R68,0,0,0,0,0,0)~
';
    'VSS'<1009>:'(0,0,0,0,0,0,0,0,0,0,0,0,0,0,0,0,0,0,0,0,0,0,0,R72,0,0,0,0,0,0)~
';
    'VSS'<1008>:'(0,0,0,0,0,0,0,0,0,0,0,0,0,0,0,0,0,0,0,0,0,0,0,R78,0,0,0,0,0,0)~
';
    'VSS'<1007>:'(0,0,0,0,0,0,0,0,0,0,0,0,0,0,0,0,0,0,0,0,0,0,0,R86,0,0,0,0,0,0)~
';
    'VSS'<1006>:'(0,0,0,0,0,0,0,0,0,0,0,0,0,0,0,0,0,0,0,0,0,0,0,T13,0,0,0,0,0,0)~
';
    'VSS'<1005>:'(0,0,0,0,0,0,0,0,0,0,0,0,0,0,0,0,0,0,0,0,0,0,0,T17,0,0,0,0,0,0)~
';
    'VSS'<1004>:'(0,0,0,0,0,0,0,0,0,0,0,0,0,0,0,0,0,0,0,0,0,0,0,T25,0,0,0,0,0,0)~
';
    'VSS'<1003>:'(0,0,0,0,0,0,0,0,0,0,0,0,0,0,0,0,0,0,0,0,0,0,0,T29,0,0,0,0,0,0)~
';
    'VSS'<1002>:'(0,0,0,0,0,0,0,0,0,0,0,0,0,0,0,0,0,0,0,0,0,0,0,T31,0,0,0,0,0,0)~
';
    'VSS'<1001>:'(0,0,0,0,0,0,0,0,0,0,0,0,0,0,0,0,0,0,0,0,0,0,0,T35,0,0,0,0,0,0)~
';
    'VSS'<1000>:'(0,0,0,0,0,0,0,0,0,0,0,0,0,0,0,0,0,0,0,0,0,0,0,T37,0,0,0,0,0,0)~
';
    'VSS'<999>:'(0,0,0,0,0,0,0,0,0,0,0,0,0,0,0,0,0,0,0,0,0,0,0,T41,0,0,0,0,0,0)';
    'VSS'<998>:'(0,0,0,0,0,0,0,0,0,0,0,0,0,0,0,0,0,0,0,0,0,0,0,T65,0,0,0,0,0,0)';
    'VSS'<997>:'(0,0,0,0,0,0,0,0,0,0,0,0,0,0,0,0,0,0,0,0,0,0,0,T73,0,0,0,0,0,0)';
    'VSS'<996>:'(0,0,0,0,0,0,0,0,0,0,0,0,0,0,0,0,0,0,0,0,0,0,0,T77,0,0,0,0,0,0)';
    'VSS'<995>:'(0,0,0,0,0,0,0,0,0,0,0,0,0,0,0,0,0,0,0,0,0,0,0,T83,0,0,0,0,0,0)';
    'VSS'<994>:'(0,0,0,0,0,0,0,0,0,0,0,0,0,0,0,0,0,0,0,0,0,0,0,T85,0,0,0,0,0,0)';
    'VSS'<993>:'(0,0,0,0,0,0,0,0,0,0,0,0,0,0,0,0,0,0,0,0,0,0,0,U2,0,0,0,0,0,0)';~

    'VSS'<992>:'(0,0,0,0,0,0,0,0,0,0,0,0,0,0,0,0,0,0,0,0,0,0,0,U4,0,0,0,0,0,0)';~

    'VSS'<991>:'(0,0,0,0,0,0,0,0,0,0,0,0,0,0,0,0,0,0,0,0,0,0,0,U6,0,0,0,0,0,0)';~

    'VSS'<990>:'(0,0,0,0,0,0,0,0,0,0,0,0,0,0,0,0,0,0,0,0,0,0,0,U20,0,0,0,0,0,0)';
    'VSS'<989>:'(0,0,0,0,0,0,0,0,0,0,0,0,0,0,0,0,0,0,0,0,0,0,0,U22,0,0,0,0,0,0)';
    'VSS'<988>:'(0,0,0,0,0,0,0,0,0,0,0,0,0,0,0,0,0,0,0,0,0,0,0,U24,0,0,0,0,0,0)';
    'VSS'<987>:'(0,0,0,0,0,0,0,0,0,0,0,0,0,0,0,0,0,0,0,0,0,0,0,U30,0,0,0,0,0,0)';
    'VSS'<986>:'(0,0,0,0,0,0,0,0,0,0,0,0,0,0,0,0,0,0,0,0,0,0,0,U36,0,0,0,0,0,0)';
    'VSS'<985>:'(0,0,0,0,0,0,0,0,0,0,0,0,0,0,0,0,0,0,0,0,0,0,0,U42,0,0,0,0,0,0)';
    'VSS'<984>:'(0,0,0,0,0,0,0,0,0,0,0,0,0,0,0,0,0,0,0,0,0,0,0,U68,0,0,0,0,0,0)';
    'VSS'<983>:'(0,0,0,0,0,0,0,0,0,0,0,0,0,0,0,0,0,0,0,0,0,0,0,U70,0,0,0,0,0,0)';
    'VSS'<982>:'(0,0,0,0,0,0,0,0,0,0,0,0,0,0,0,0,0,0,0,0,0,0,0,U74,0,0,0,0,0,0)';
    'VSS'<981>:'(0,0,0,0,0,0,0,0,0,0,0,0,0,0,0,0,0,0,0,0,0,0,0,U76,0,0,0,0,0,0)';
    'VSS'<980>:'(0,0,0,0,0,0,0,0,0,0,0,0,0,0,0,0,0,0,0,0,0,0,0,U78,0,0,0,0,0,0)';
    'VSS'<979>:'(0,0,0,0,0,0,0,0,0,0,0,0,0,0,0,0,0,0,0,0,0,0,0,U80,0,0,0,0,0,0)';
    'VSS'<978>:'(0,0,0,0,0,0,0,0,0,0,0,0,0,0,0,0,0,0,0,0,0,0,0,U86,0,0,0,0,0,0)';
    'VSS'<977>:'(0,0,0,0,0,0,0,0,0,0,0,0,0,0,0,0,0,0,0,0,0,0,0,V1,0,0,0,0,0,0)';~

    'VSS'<976>:'(0,0,0,0,0,0,0,0,0,0,0,0,0,0,0,0,0,0,0,0,0,0,0,V5,0,0,0,0,0,0)';~

    'VSS'<975>:'(0,0,0,0,0,0,0,0,0,0,0,0,0,0,0,0,0,0,0,0,0,0,0,V9,0,0,0,0,0,0)';~

    'VSS'<974>:'(0,0,0,0,0,0,0,0,0,0,0,0,0,0,0,0,0,0,0,0,0,0,0,V13,0,0,0,0,0,0)';
    'VSS'<973>:'(0,0,0,0,0,0,0,0,0,0,0,0,0,0,0,0,0,0,0,0,0,0,0,V15,0,0,0,0,0,0)';
    'VSS'<972>:'(0,0,0,0,0,0,0,0,0,0,0,0,0,0,0,0,0,0,0,0,0,0,0,V21,0,0,0,0,0,0)';
    'VSS'<971>:'(0,0,0,0,0,0,0,0,0,0,0,0,0,0,0,0,0,0,0,0,0,0,0,V23,0,0,0,0,0,0)';
    'VSS'<970>:'(0,0,0,0,0,0,0,0,0,0,0,0,0,0,0,0,0,0,0,0,0,0,0,V43,0,0,0,0,0,0)';
    'VSS'<969>:'(0,0,0,0,0,0,0,0,0,0,0,0,0,0,0,0,0,0,0,0,0,0,0,V73,0,0,0,0,0,0)';
    'VSS'<968>:'(0,0,0,0,0,0,0,0,0,0,0,0,0,0,0,0,0,0,0,0,0,0,0,V75,0,0,0,0,0,0)';
    'VSS'<967>:'(0,0,0,0,0,0,0,0,0,0,0,0,0,0,0,0,0,0,0,0,0,0,0,V77,0,0,0,0,0,0)';
    'VSS'<966>:'(0,0,0,0,0,0,0,0,0,0,0,0,0,0,0,0,0,0,0,0,0,0,0,V83,0,0,0,0,0,0)';
    'VSS'<965>:'(0,0,0,0,0,0,0,0,0,0,0,0,0,0,0,0,0,0,0,0,0,0,0,W8,0,0,0,0,0,0)';~

    'VSS'<964>:'(0,0,0,0,0,0,0,0,0,0,0,0,0,0,0,0,0,0,0,0,0,0,0,AC56,0,0,0,0,0,0)~
';
    'VSS'<963>:'(0,0,0,0,0,0,0,0,0,0,0,0,0,0,0,0,0,0,0,0,0,0,0,W12,0,0,0,0,0,0)';
    'VSS'<962>:'(0,0,0,0,0,0,0,0,0,0,0,0,0,0,0,0,0,0,0,0,0,0,0,W22,0,0,0,0,0,0)';
    'VSS'<961>:'(0,0,0,0,0,0,0,0,0,0,0,0,0,0,0,0,0,0,0,0,0,0,0,W24,0,0,0,0,0,0)';
    'VSS'<960>:'(0,0,0,0,0,0,0,0,0,0,0,0,0,0,0,0,0,0,0,0,0,0,0,W26,0,0,0,0,0,0)';
    'VSS'<959>:'(0,0,0,0,0,0,0,0,0,0,0,0,0,0,0,0,0,0,0,0,0,0,0,W28,0,0,0,0,0,0)';
    'VSS'<958>:'(0,0,0,0,0,0,0,0,0,0,0,0,0,0,0,0,0,0,0,0,0,0,0,W30,0,0,0,0,0,0)';
    'VSS'<957>:'(0,0,0,0,0,0,0,0,0,0,0,0,0,0,0,0,0,0,0,0,0,0,0,W32,0,0,0,0,0,0)';
    'VSS'<956>:'(0,0,0,0,0,0,0,0,0,0,0,0,0,0,0,0,0,0,0,0,0,0,0,W34,0,0,0,0,0,0)';
    'VSS'<955>:'(0,0,0,0,0,0,0,0,0,0,0,0,0,0,0,0,0,0,0,0,0,0,0,W36,0,0,0,0,0,0)';
    'VSS'<954>:'(0,0,0,0,0,0,0,0,0,0,0,0,0,0,0,0,0,0,0,0,0,0,0,W38,0,0,0,0,0,0)';
    'VSS'<953>:'(0,0,0,0,0,0,0,0,0,0,0,0,0,0,0,0,0,0,0,0,0,0,0,W40,0,0,0,0,0,0)';
    'VSS'<952>:'(0,0,0,0,0,0,0,0,0,0,0,0,0,0,0,0,0,0,0,0,0,0,0,W42,0,0,0,0,0,0)';
    'VSS'<951>:'(0,0,0,0,0,0,0,0,0,0,0,0,0,0,0,0,0,0,0,0,0,0,0,W68,0,0,0,0,0,0)';
    'VSS'<950>:'(0,0,0,0,0,0,0,0,0,0,0,0,0,0,0,0,0,0,0,0,0,0,0,W74,0,0,0,0,0,0)';
    'VSS'<949>:'(0,0,0,0,0,0,0,0,0,0,0,0,0,0,0,0,0,0,0,0,0,0,0,W78,0,0,0,0,0,0)';
    'VSS'<948>:'(0,0,0,0,0,0,0,0,0,0,0,0,0,0,0,0,0,0,0,0,0,0,0,W82,0,0,0,0,0,0)';
    'VSS'<947>:'(0,0,0,0,0,0,0,0,0,0,0,0,0,0,0,0,0,0,0,0,0,0,0,Y15,0,0,0,0,0,0)';
    'VSS'<946>:'(0,0,0,0,0,0,0,0,0,0,0,0,0,0,0,0,0,0,0,0,0,0,0,Y17,0,0,0,0,0,0)';
    'VSS'<945>:'(0,0,0,0,0,0,0,0,0,0,0,0,0,0,0,0,0,0,0,0,0,0,0,Y5,0,0,0,0,0,0)';~

    'VSS'<944>:'(0,0,0,0,0,0,0,0,0,0,0,0,0,0,0,0,0,0,0,0,0,0,0,Y67,0,0,0,0,0,0)';
    'VSS'<943>:'(0,0,0,0,0,0,0,0,0,0,0,0,0,0,0,0,0,0,0,0,0,0,0,Y7,0,0,0,0,0,0)';~

    'VSS'<942>:'(0,0,0,0,0,0,0,0,0,0,0,0,0,0,0,0,0,0,0,0,0,0,0,Y9,0,0,0,0,0,0)';~

    'VSS'<941>:'(0,0,0,0,0,0,0,0,0,0,0,0,0,0,0,0,0,0,0,0,0,0,0,Y71,0,0,0,0,0,0)';
    'VSS'<940>:'(0,0,0,0,0,0,0,0,0,0,0,0,0,0,0,0,0,0,0,0,0,0,0,Y73,0,0,0,0,0,0)';
    'VSS'<939>:'(0,0,0,0,0,0,0,0,0,0,0,0,0,0,0,0,0,0,0,0,0,0,0,Y79,0,0,0,0,0,0)';
    'VSS'<938>:'(0,0,0,0,0,0,0,0,0,0,0,0,0,0,0,0,0,0,0,0,0,0,0,Y81,0,0,0,0,0,0)';
    'VSS'<937>:'(0,0,0,0,0,0,0,0,0,0,0,0,0,0,0,0,0,0,0,0,0,0,0,Y83,0,0,0,0,0,0)';
    'VSS'<936>:'(0,0,0,0,0,0,0,0,0,0,0,0,0,0,0,0,0,0,0,0,0,0,0,Y85,0,0,0,0,0,0)';
    'VSS'<935>:'(0,0,0,0,0,0,0,0,0,0,0,0,0,0,0,0,0,0,0,0,0,0,0,AA4,0,0,0,0,0,0)';
    'VSS'<934>:'(0,0,0,0,0,0,0,0,0,0,0,0,0,0,0,0,0,0,0,0,0,0,0,AA16,0,0,0,0,0,0)~
';
    'VSS'<933>:'(0,0,0,0,0,0,0,0,0,0,0,0,0,0,0,0,0,0,0,0,0,0,0,0,AA18,0,0,0,0,0)~
';
    'VSS'<932>:'(0,0,0,0,0,0,0,0,0,0,0,0,0,0,0,0,0,0,0,0,0,0,0,0,AA22,0,0,0,0,0)~
';
    'VSS'<931>:'(0,0,0,0,0,0,0,0,0,0,0,0,0,0,0,0,0,0,0,0,0,0,0,0,AA24,0,0,0,0,0)~
';
    'VSS'<930>:'(0,0,0,0,0,0,0,0,0,0,0,0,0,0,0,0,0,0,0,0,0,0,0,0,AA30,0,0,0,0,0)~
';
    'VSS'<929>:'(0,0,0,0,0,0,0,0,0,0,0,0,0,0,0,0,0,0,0,0,0,0,0,0,AA36,0,0,0,0,0)~
';
    'VSS'<928>:'(0,0,0,0,0,0,0,0,0,0,0,0,0,0,0,0,0,0,0,0,0,0,0,0,AA42,0,0,0,0,0)~
';
    'VSS'<927>:'(0,0,0,0,0,0,0,0,0,0,0,0,0,0,0,0,0,0,0,0,0,0,0,0,AA64,0,0,0,0,0)~
';
    'VSS'<926>:'(0,0,0,0,0,0,0,0,0,0,0,0,0,0,0,0,0,0,0,0,0,0,0,0,AA66,0,0,0,0,0)~
';
    'VSS'<925>:'(0,0,0,0,0,0,0,0,0,0,0,0,0,0,0,0,0,0,0,0,0,0,0,0,AA68,0,0,0,0,0)~
';
    'VSS'<924>:'(0,0,0,0,0,0,0,0,0,0,0,0,0,0,0,0,0,0,0,0,0,0,0,0,AA76,0,0,0,0,0)~
';
    'VSS'<923>:'(0,0,0,0,0,0,0,0,0,0,0,0,0,0,0,0,0,0,0,0,0,0,0,0,AA78,0,0,0,0,0)~
';
    'VSS'<922>:'(0,0,0,0,0,0,0,0,0,0,0,0,0,0,0,0,0,0,0,0,0,0,0,0,AA80,0,0,0,0,0)~
';
    'VSS'<921>:'(0,0,0,0,0,0,0,0,0,0,0,0,0,0,0,0,0,0,0,0,0,0,0,0,AA82,0,0,0,0,0)~
';
    'VSS'<920>:'(0,0,0,0,0,0,0,0,0,0,0,0,0,0,0,0,0,0,0,0,0,0,0,0,AB1,0,0,0,0,0)';
    'VSS'<919>:'(0,0,0,0,0,0,0,0,0,0,0,0,0,0,0,0,0,0,0,0,0,0,0,0,AB5,0,0,0,0,0)';
    'VSS'<918>:'(0,0,0,0,0,0,0,0,0,0,0,0,0,0,0,0,0,0,0,0,0,0,0,0,AB11,0,0,0,0,0)~
';
    'VSS'<917>:'(0,0,0,0,0,0,0,0,0,0,0,0,0,0,0,0,0,0,0,0,0,0,0,0,AB21,0,0,0,0,0)~
';
    'VSS'<916>:'(0,0,0,0,0,0,0,0,0,0,0,0,0,0,0,0,0,0,0,0,0,0,0,0,AB23,0,0,0,0,0)~
';
    'VSS'<915>:'(0,0,0,0,0,0,0,0,0,0,0,0,0,0,0,0,0,0,0,0,0,0,0,0,AB25,0,0,0,0,0)~
';
    'VSS'<914>:'(0,0,0,0,0,0,0,0,0,0,0,0,0,0,0,0,0,0,0,0,0,0,0,0,AB29,0,0,0,0,0)~
';
    'VSS'<913>:'(0,0,0,0,0,0,0,0,0,0,0,0,0,0,0,0,0,0,0,0,0,0,0,0,AB31,0,0,0,0,0)~
';
    'VSS'<912>:'(0,0,0,0,0,0,0,0,0,0,0,0,0,0,0,0,0,0,0,0,0,0,0,0,AB35,0,0,0,0,0)~
';
    'VSS'<911>:'(0,0,0,0,0,0,0,0,0,0,0,0,0,0,0,0,0,0,0,0,0,0,0,0,AB37,0,0,0,0,0)~
';
    'VSS'<910>:'(0,0,0,0,0,0,0,0,0,0,0,0,0,0,0,0,0,0,0,0,0,0,0,0,AB41,0,0,0,0,0)~
';
    'VSS'<909>:'(0,0,0,0,0,0,0,0,0,0,0,0,0,0,0,0,0,0,0,0,0,0,0,0,AB65,0,0,0,0,0)~
';
    'VSS'<908>:'(0,0,0,0,0,0,0,0,0,0,0,0,0,0,0,0,0,0,0,0,0,0,0,0,AB69,0,0,0,0,0)~
';
    'VSS'<907>:'(0,0,0,0,0,0,0,0,0,0,0,0,0,0,0,0,0,0,0,0,0,0,0,0,AB73,0,0,0,0,0)~
';
    'VSS'<906>:'(0,0,0,0,0,0,0,0,0,0,0,0,0,0,0,0,0,0,0,0,0,0,0,0,AB79,0,0,0,0,0)~
';
    'VSS'<905>:'(0,0,0,0,0,0,0,0,0,0,0,0,0,0,0,0,0,0,0,0,0,0,0,0,AB83,0,0,0,0,0)~
';
    'VSS'<904>:'(0,0,0,0,0,0,0,0,0,0,0,0,0,0,0,0,0,0,0,0,0,0,0,0,AB85,0,0,0,0,0)~
';
    'VSS'<903>:'(0,0,0,0,0,0,0,0,0,0,0,0,0,0,0,0,0,0,0,0,0,0,0,0,AC18,0,0,0,0,0)~
';
    'VSS'<902>:'(0,0,0,0,0,0,0,0,0,0,0,0,0,0,0,0,0,0,0,0,0,0,0,0,AC22,0,0,0,0,0)~
';
    'VSS'<901>:'(0,0,0,0,0,0,0,0,0,0,0,0,0,0,0,0,0,0,0,0,0,0,0,0,AC26,0,0,0,0,0)~
';
    'VSS'<900>:'(0,0,0,0,0,0,0,0,0,0,0,0,0,0,0,0,0,0,0,0,0,0,0,0,AC28,0,0,0,0,0)~
';
    'VSS'<899>:'(0,0,0,0,0,0,0,0,0,0,0,0,0,0,0,0,0,0,0,0,0,0,0,0,AC32,0,0,0,0,0)~
';
    'VSS'<898>:'(0,0,0,0,0,0,0,0,0,0,0,0,0,0,0,0,0,0,0,0,0,0,0,0,AC34,0,0,0,0,0)~
';
    'VSS'<897>:'(0,0,0,0,0,0,0,0,0,0,0,0,0,0,0,0,0,0,0,0,0,0,0,0,AC38,0,0,0,0,0)~
';
    'VSS'<896>:'(0,0,0,0,0,0,0,0,0,0,0,0,0,0,0,0,0,0,0,0,0,0,0,0,AC40,0,0,0,0,0)~
';
    'VSS'<895>:'(0,0,0,0,0,0,0,0,0,0,0,0,0,0,0,0,0,0,0,0,0,0,0,0,AC64,0,0,0,0,0)~
';
    'VSS'<894>:'(0,0,0,0,0,0,0,0,0,0,0,0,0,0,0,0,0,0,0,0,0,0,0,0,AC70,0,0,0,0,0)~
';
    'VSS'<893>:'(0,0,0,0,0,0,0,0,0,0,0,0,0,0,0,0,0,0,0,0,0,0,0,0,AC72,0,0,0,0,0)~
';
    'VSS'<892>:'(0,0,0,0,0,0,0,0,0,0,0,0,0,0,0,0,0,0,0,0,0,0,0,0,AC78,0,0,0,0,0)~
';
    'VSS'<891>:'(0,0,0,0,0,0,0,0,0,0,0,0,0,0,0,0,0,0,0,0,0,0,0,0,AC84,0,0,0,0,0)~
';
    'VSS'<890>:'(0,0,0,0,0,0,0,0,0,0,0,0,0,0,0,0,0,0,0,0,0,0,0,0,AC86,0,0,0,0,0)~
';
    'VSS'<889>:'(0,0,0,0,0,0,0,0,0,0,0,0,0,0,0,0,0,0,0,0,0,0,0,0,AD3,0,0,0,0,0)';
    'VSS'<888>:'(0,0,0,0,0,0,0,0,0,0,0,0,0,0,0,0,0,0,0,0,0,0,0,0,AD7,0,0,0,0,0)';
    'VSS'<887>:'(0,0,0,0,0,0,0,0,0,0,0,0,0,0,0,0,0,0,0,0,0,0,0,0,AD9,0,0,0,0,0)';
    'VSS'<886>:'(0,0,0,0,0,0,0,0,0,0,0,0,0,0,0,0,0,0,0,0,0,0,0,0,AD11,0,0,0,0,0)~
';
    'VSS'<885>:'(0,0,0,0,0,0,0,0,0,0,0,0,0,0,0,0,0,0,0,0,0,0,0,0,AD13,0,0,0,0,0)~
';
    'VSS'<884>:'(0,0,0,0,0,0,0,0,0,0,0,0,0,0,0,0,0,0,0,0,0,0,0,0,AD15,0,0,0,0,0)~
';
    'VSS'<883>:'(0,0,0,0,0,0,0,0,0,0,0,0,0,0,0,0,0,0,0,0,0,0,0,0,AD19,0,0,0,0,0)~
';
    'VSS'<882>:'(0,0,0,0,0,0,0,0,0,0,0,0,0,0,0,0,0,0,0,0,0,0,0,0,AD21,0,0,0,0,0)~
';
    'VSS'<881>:'(0,0,0,0,0,0,0,0,0,0,0,0,0,0,0,0,0,0,0,0,0,0,0,0,AD27,0,0,0,0,0)~
';
    'VSS'<880>:'(0,0,0,0,0,0,0,0,0,0,0,0,0,0,0,0,0,0,0,0,0,0,0,0,AD33,0,0,0,0,0)~
';
    'VSS'<879>:'(0,0,0,0,0,0,0,0,0,0,0,0,0,0,0,0,0,0,0,0,0,0,0,0,AD39,0,0,0,0,0)~
';
    'VSS'<878>:'(0,0,0,0,0,0,0,0,0,0,0,0,0,0,0,0,0,0,0,0,0,0,0,0,AD43,0,0,0,0,0)~
';
    'VSS'<877>:'(0,0,0,0,0,0,0,0,0,0,0,0,0,0,0,0,0,0,0,0,0,0,0,0,AD71,0,0,0,0,0)~
';
    'VSS'<876>:'(0,0,0,0,0,0,0,0,0,0,0,0,0,0,0,0,0,0,0,0,0,0,0,0,AD73,0,0,0,0,0)~
';
    'VSS'<875>:'(0,0,0,0,0,0,0,0,0,0,0,0,0,0,0,0,0,0,0,0,0,0,0,0,AD75,0,0,0,0,0)~
';
    'VSS'<874>:'(0,0,0,0,0,0,0,0,0,0,0,0,0,0,0,0,0,0,0,0,0,0,0,0,AD81,0,0,0,0,0)~
';
    'VSS'<873>:'(0,0,0,0,0,0,0,0,0,0,0,0,0,0,0,0,0,0,0,0,0,0,0,0,AD83,0,0,0,0,0)~
';
    'VSS'<872>:'(0,0,0,0,0,0,0,0,0,0,0,0,0,0,0,0,0,0,0,0,0,0,0,0,AD85,0,0,0,0,0)~
';
    'VSS'<871>:'(0,0,0,0,0,0,0,0,0,0,0,0,0,0,0,0,0,0,0,0,0,0,0,0,AE4,0,0,0,0,0)';
    'VSS'<870>:'(0,0,0,0,0,0,0,0,0,0,0,0,0,0,0,0,0,0,0,0,0,0,0,0,AE8,0,0,0,0,0)';
    'VSS'<869>:'(0,0,0,0,0,0,0,0,0,0,0,0,0,0,0,0,0,0,0,0,0,0,0,0,AC54,0,0,0,0,0)~
';
    'VSS'<868>:'(0,0,0,0,0,0,0,0,0,0,0,0,0,0,0,0,0,0,0,0,0,0,0,0,AE16,0,0,0,0,0)~
';
    'VSS'<867>:'(0,0,0,0,0,0,0,0,0,0,0,0,0,0,0,0,0,0,0,0,0,0,0,0,AE38,0,0,0,0,0)~
';
    'VSS'<866>:'(0,0,0,0,0,0,0,0,0,0,0,0,0,0,0,0,0,0,0,0,0,0,0,0,AE40,0,0,0,0,0)~
';
    'VSS'<865>:'(0,0,0,0,0,0,0,0,0,0,0,0,0,0,0,0,0,0,0,0,0,0,0,0,AE42,0,0,0,0,0)~
';
    'VSS'<864>:'(0,0,0,0,0,0,0,0,0,0,0,0,0,0,0,0,0,0,0,0,0,0,0,0,AE64,0,0,0,0,0)~
';
    'VSS'<863>:'(0,0,0,0,0,0,0,0,0,0,0,0,0,0,0,0,0,0,0,0,0,0,0,0,AE66,0,0,0,0,0)~
';
    'VSS'<862>:'(0,0,0,0,0,0,0,0,0,0,0,0,0,0,0,0,0,0,0,0,0,0,0,0,AE68,0,0,0,0,0)~
';
    'VSS'<861>:'(0,0,0,0,0,0,0,0,0,0,0,0,0,0,0,0,0,0,0,0,0,0,0,0,AE70,0,0,0,0,0)~
';
    'VSS'<860>:'(0,0,0,0,0,0,0,0,0,0,0,0,0,0,0,0,0,0,0,0,0,0,0,0,AE78,0,0,0,0,0)~
';
    'VSS'<859>:'(0,0,0,0,0,0,0,0,0,0,0,0,0,0,0,0,0,0,0,0,0,0,0,0,AF1,0,0,0,0,0)';
    'VSS'<858>:'(0,0,0,0,0,0,0,0,0,0,0,0,0,0,0,0,0,0,0,0,0,0,0,0,AC52,0,0,0,0,0)~
';
    'VSS'<857>:'(0,0,0,0,0,0,0,0,0,0,0,0,0,0,0,0,0,0,0,0,0,0,0,0,AF9,0,0,0,0,0)';
    'VSS'<856>:'(0,0,0,0,0,0,0,0,0,0,0,0,0,0,0,0,0,0,0,0,0,0,0,0,AF21,0,0,0,0,0)~
';
    'VSS'<855>:'(0,0,0,0,0,0,0,0,0,0,0,0,0,0,0,0,0,0,0,0,0,0,0,0,AF23,0,0,0,0,0)~
';
    'VSS'<854>:'(0,0,0,0,0,0,0,0,0,0,0,0,0,0,0,0,0,0,0,0,0,0,0,0,AF25,0,0,0,0,0)~
';
    'VSS'<853>:'(0,0,0,0,0,0,0,0,0,0,0,0,0,0,0,0,0,0,0,0,0,0,0,0,AF27,0,0,0,0,0)~
';
    'VSS'<852>:'(0,0,0,0,0,0,0,0,0,0,0,0,0,0,0,0,0,0,0,0,0,0,0,0,AF29,0,0,0,0,0)~
';
    'VSS'<851>:'(0,0,0,0,0,0,0,0,0,0,0,0,0,0,0,0,0,0,0,0,0,0,0,0,AF31,0,0,0,0,0)~
';
    'VSS'<850>:'(0,0,0,0,0,0,0,0,0,0,0,0,0,0,0,0,0,0,0,0,0,0,0,0,AF33,0,0,0,0,0)~
';
    'VSS'<849>:'(0,0,0,0,0,0,0,0,0,0,0,0,0,0,0,0,0,0,0,0,0,0,0,0,AF37,0,0,0,0,0)~
';
    'VSS'<848>:'(0,0,0,0,0,0,0,0,0,0,0,0,0,0,0,0,0,0,0,0,0,0,0,0,AF39,0,0,0,0,0)~
';
    'VSS'<847>:'(0,0,0,0,0,0,0,0,0,0,0,0,0,0,0,0,0,0,0,0,0,0,0,0,AF41,0,0,0,0,0)~
';
    'VSS'<846>:'(0,0,0,0,0,0,0,0,0,0,0,0,0,0,0,0,0,0,0,0,0,0,0,0,AF73,0,0,0,0,0)~
';
    'VSS'<845>:'(0,0,0,0,0,0,0,0,0,0,0,0,0,0,0,0,0,0,0,0,0,0,0,0,AF77,0,0,0,0,0)~
';
    'VSS'<844>:'(0,0,0,0,0,0,0,0,0,0,0,0,0,0,0,0,0,0,0,0,0,0,0,0,AF83,0,0,0,0,0)~
';
    'VSS'<843>:'(0,0,0,0,0,0,0,0,0,0,0,0,0,0,0,0,0,0,0,0,0,0,0,0,AF85,0,0,0,0,0)~
';
    'VSS'<842>:'(0,0,0,0,0,0,0,0,0,0,0,0,0,0,0,0,0,0,0,0,0,0,0,0,AG12,0,0,0,0,0)~
';
    'VSS'<841>:'(0,0,0,0,0,0,0,0,0,0,0,0,0,0,0,0,0,0,0,0,0,0,0,0,AG14,0,0,0,0,0)~
';
    'VSS'<840>:'(0,0,0,0,0,0,0,0,0,0,0,0,0,0,0,0,0,0,0,0,0,0,0,0,AG18,0,0,0,0,0)~
';
    'VSS'<839>:'(0,0,0,0,0,0,0,0,0,0,0,0,0,0,0,0,0,0,0,0,0,0,0,0,AG36,0,0,0,0,0)~
';
    'VSS'<838>:'(0,0,0,0,0,0,0,0,0,0,0,0,0,0,0,0,0,0,0,0,0,0,0,0,AG64,0,0,0,0,0)~
';
    'VSS'<837>:'(0,0,0,0,0,0,0,0,0,0,0,0,0,0,0,0,0,0,0,0,0,0,0,0,AG70,0,0,0,0,0)~
';
    'VSS'<836>:'(0,0,0,0,0,0,0,0,0,0,0,0,0,0,0,0,0,0,0,0,0,0,0,0,AG74,0,0,0,0,0)~
';
    'VSS'<835>:'(0,0,0,0,0,0,0,0,0,0,0,0,0,0,0,0,0,0,0,0,0,0,0,0,AG76,0,0,0,0,0)~
';
    'VSS'<834>:'(0,0,0,0,0,0,0,0,0,0,0,0,0,0,0,0,0,0,0,0,0,0,0,0,AG78,0,0,0,0,0)~
';
    'VSS'<833>:'(0,0,0,0,0,0,0,0,0,0,0,0,0,0,0,0,0,0,0,0,0,0,0,0,AG80,0,0,0,0,0)~
';
    'VSS'<832>:'(0,0,0,0,0,0,0,0,0,0,0,0,0,0,0,0,0,0,0,0,0,0,0,0,AH1,0,0,0,0,0)';
    'VSS'<831>:'(0,0,0,0,0,0,0,0,0,0,0,0,0,0,0,0,0,0,0,0,0,0,0,0,AH5,0,0,0,0,0)';
    'VSS'<830>:'(0,0,0,0,0,0,0,0,0,0,0,0,0,0,0,0,0,0,0,0,0,0,0,0,AH21,0,0,0,0,0)~
';
    'VSS'<829>:'(0,0,0,0,0,0,0,0,0,0,0,0,0,0,0,0,0,0,0,0,0,0,0,0,AH27,0,0,0,0,0)~
';
    'VSS'<828>:'(0,0,0,0,0,0,0,0,0,0,0,0,0,0,0,0,0,0,0,0,0,0,0,0,AH33,0,0,0,0,0)~
';
    'VSS'<827>:'(0,0,0,0,0,0,0,0,0,0,0,0,0,0,0,0,0,0,0,0,0,0,0,0,AH35,0,0,0,0,0)~
';
    'VSS'<826>:'(0,0,0,0,0,0,0,0,0,0,0,0,0,0,0,0,0,0,0,0,0,0,0,0,AH45,0,0,0,0,0)~
';
    'VSS'<825>:'(0,0,0,0,0,0,0,0,0,0,0,0,0,0,0,0,0,0,0,0,0,0,0,0,AH47,0,0,0,0,0)~
';
    'VSS'<824>:'(0,0,0,0,0,0,0,0,0,0,0,0,0,0,0,0,0,0,0,0,0,0,0,0,AH49,0,0,0,0,0)~
';
    'VSS'<823>:'(0,0,0,0,0,0,0,0,0,0,0,0,0,0,0,0,0,0,0,0,0,0,0,0,AH51,0,0,0,0,0)~
';
    'VSS'<822>:'(0,0,0,0,0,0,0,0,0,0,0,0,0,0,0,0,0,0,0,0,0,0,0,0,AH53,0,0,0,0,0)~
';
    'VSS'<821>:'(0,0,0,0,0,0,0,0,0,0,0,0,0,0,0,0,0,0,0,0,0,0,0,0,AH59,0,0,0,0,0)~
';
    'VSS'<820>:'(0,0,0,0,0,0,0,0,0,0,0,0,0,0,0,0,0,0,0,0,0,0,0,0,AH61,0,0,0,0,0)~
';
    'VSS'<819>:'(0,0,0,0,0,0,0,0,0,0,0,0,0,0,0,0,0,0,0,0,0,0,0,0,AH65,0,0,0,0,0)~
';
    'VSS'<818>:'(0,0,0,0,0,0,0,0,0,0,0,0,0,0,0,0,0,0,0,0,0,0,0,0,AH69,0,0,0,0,0)~
';
    'VSS'<817>:'(0,0,0,0,0,0,0,0,0,0,0,0,0,0,0,0,0,0,0,0,0,0,0,0,AH75,0,0,0,0,0)~
';
    'VSS'<816>:'(0,0,0,0,0,0,0,0,0,0,0,0,0,0,0,0,0,0,0,0,0,0,0,0,AH77,0,0,0,0,0)~
';
    'VSS'<815>:'(0,0,0,0,0,0,0,0,0,0,0,0,0,0,0,0,0,0,0,0,0,0,0,0,AH83,0,0,0,0,0)~
';
    'VSS'<814>:'(0,0,0,0,0,0,0,0,0,0,0,0,0,0,0,0,0,0,0,0,0,0,0,0,AJ8,0,0,0,0,0)';
    'VSS'<813>:'(0,0,0,0,0,0,0,0,0,0,0,0,0,0,0,0,0,0,0,0,0,0,0,0,AJ22,0,0,0,0,0)~
';
    'VSS'<812>:'(0,0,0,0,0,0,0,0,0,0,0,0,0,0,0,0,0,0,0,0,0,0,0,0,AJ26,0,0,0,0,0)~
';
    'VSS'<811>:'(0,0,0,0,0,0,0,0,0,0,0,0,0,0,0,0,0,0,0,0,0,0,0,0,AJ28,0,0,0,0,0)~
';
    'VSS'<810>:'(0,0,0,0,0,0,0,0,0,0,0,0,0,0,0,0,0,0,0,0,0,0,0,0,AJ32,0,0,0,0,0)~
';
    'VSS'<809>:'(0,0,0,0,0,0,0,0,0,0,0,0,0,0,0,0,0,0,0,0,0,0,0,0,AJ34,0,0,0,0,0)~
';
    'VSS'<808>:'(0,0,0,0,0,0,0,0,0,0,0,0,0,0,0,0,0,0,0,0,0,0,0,0,AJ46,0,0,0,0,0)~
';
    'VSS'<807>:'(0,0,0,0,0,0,0,0,0,0,0,0,0,0,0,0,0,0,0,0,0,0,0,0,AJ48,0,0,0,0,0)~
';
    'VSS'<806>:'(0,0,0,0,0,0,0,0,0,0,0,0,0,0,0,0,0,0,0,0,0,0,0,0,AJ50,0,0,0,0,0)~
';
    'VSS'<805>:'(0,0,0,0,0,0,0,0,0,0,0,0,0,0,0,0,0,0,0,0,0,0,0,0,AJ52,0,0,0,0,0)~
';
    'VSS'<804>:'(0,0,0,0,0,0,0,0,0,0,0,0,0,0,0,0,0,0,0,0,0,0,0,0,AJ54,0,0,0,0,0)~
';
    'VSS'<803>:'(0,0,0,0,0,0,0,0,0,0,0,0,0,0,0,0,0,0,0,0,0,0,0,0,AJ66,0,0,0,0,0)~
';
    'VSS'<802>:'(0,0,0,0,0,0,0,0,0,0,0,0,0,0,0,0,0,0,0,0,0,0,0,0,AJ68,0,0,0,0,0)~
';
    'VSS'<801>:'(0,0,0,0,0,0,0,0,0,0,0,0,0,0,0,0,0,0,0,0,0,0,0,0,AJ74,0,0,0,0,0)~
';
    'VSS'<800>:'(0,0,0,0,0,0,0,0,0,0,0,0,0,0,0,0,0,0,0,0,0,0,0,0,AJ78,0,0,0,0,0)~
';
    'VSS'<799>:'(0,0,0,0,0,0,0,0,0,0,0,0,0,0,0,0,0,0,0,0,0,0,0,0,AJ82,0,0,0,0,0)~
';
    'VSS'<798>:'(0,0,0,0,0,0,0,0,0,0,0,0,0,0,0,0,0,0,0,0,0,0,0,0,AJ86,0,0,0,0,0)~
';
    'VSS'<797>:'(0,0,0,0,0,0,0,0,0,0,0,0,0,0,0,0,0,0,0,0,0,0,0,0,AK9,0,0,0,0,0)';
    'VSS'<796>:'(0,0,0,0,0,0,0,0,0,0,0,0,0,0,0,0,0,0,0,0,0,0,0,0,AK13,0,0,0,0,0)~
';
    'VSS'<795>:'(0,0,0,0,0,0,0,0,0,0,0,0,0,0,0,0,0,0,0,0,0,0,0,0,AK19,0,0,0,0,0)~
';
    'VSS'<794>:'(0,0,0,0,0,0,0,0,0,0,0,0,0,0,0,0,0,0,0,0,0,0,0,0,AK23,0,0,0,0,0)~
';
    'VSS'<793>:'(0,0,0,0,0,0,0,0,0,0,0,0,0,0,0,0,0,0,0,0,0,0,0,0,AK25,0,0,0,0,0)~
';
    'VSS'<792>:'(0,0,0,0,0,0,0,0,0,0,0,0,0,0,0,0,0,0,0,0,0,0,0,0,AK29,0,0,0,0,0)~
';
    'VSS'<791>:'(0,0,0,0,0,0,0,0,0,0,0,0,0,0,0,0,0,0,0,0,0,0,0,0,AK31,0,0,0,0,0)~
';
    'VSS'<790>:'(0,0,0,0,0,0,0,0,0,0,0,0,0,0,0,0,0,0,0,0,0,0,0,0,AK33,0,0,0,0,0)~
';
    'VSS'<789>:'(0,0,0,0,0,0,0,0,0,0,0,0,0,0,0,0,0,0,0,0,0,0,0,0,AK55,0,0,0,0,0)~
';
    'VSS'<788>:'(0,0,0,0,0,0,0,0,0,0,0,0,0,0,0,0,0,0,0,0,0,0,0,0,AK65,0,0,0,0,0)~
';
    'VSS'<787>:'(0,0,0,0,0,0,0,0,0,0,0,0,0,0,0,0,0,0,0,0,0,0,0,0,AK67,0,0,0,0,0)~
';
    'VSS'<786>:'(0,0,0,0,0,0,0,0,0,0,0,0,0,0,0,0,0,0,0,0,0,0,0,0,AK73,0,0,0,0,0)~
';
    'VSS'<785>:'(0,0,0,0,0,0,0,0,0,0,0,0,0,0,0,0,0,0,0,0,0,0,0,0,AK79,0,0,0,0,0)~
';
    'VSS'<784>:'(0,0,0,0,0,0,0,0,0,0,0,0,0,0,0,0,0,0,0,0,0,0,0,0,AK81,0,0,0,0,0)~
';
    'VSS'<783>:'(0,0,0,0,0,0,0,0,0,0,0,0,0,0,0,0,0,0,0,0,0,0,0,0,AK83,0,0,0,0,0)~
';
    'VSS'<782>:'(0,0,0,0,0,0,0,0,0,0,0,0,0,0,0,0,0,0,0,0,0,0,0,0,AK85,0,0,0,0,0)~
';
    'VSS'<781>:'(0,0,0,0,0,0,0,0,0,0,0,0,0,0,0,0,0,0,0,0,0,0,0,0,AL4,0,0,0,0,0)';
    'VSS'<780>:'(0,0,0,0,0,0,0,0,0,0,0,0,0,0,0,0,0,0,0,0,0,0,0,0,AL10,0,0,0,0,0)~
';
    'VSS'<779>:'(0,0,0,0,0,0,0,0,0,0,0,0,0,0,0,0,0,0,0,0,0,0,0,0,AL24,0,0,0,0,0)~
';
    'VSS'<778>:'(0,0,0,0,0,0,0,0,0,0,0,0,0,0,0,0,0,0,0,0,0,0,0,0,AL30,0,0,0,0,0)~
';
    'VSS'<777>:'(0,0,0,0,0,0,0,0,0,0,0,0,0,0,0,0,0,0,0,0,0,0,0,0,AL32,0,0,0,0,0)~
';
    'VSS'<776>:'(0,0,0,0,0,0,0,0,0,0,0,0,0,0,0,0,0,0,0,0,0,0,0,0,AL56,0,0,0,0,0)~
';
    'VSS'<775>:'(0,0,0,0,0,0,0,0,0,0,0,0,0,0,0,0,0,0,0,0,0,0,0,0,AL64,0,0,0,0,0)~
';
    'VSS'<774>:'(0,0,0,0,0,0,0,0,0,0,0,0,0,0,0,0,0,0,0,0,0,0,0,0,AL68,0,0,0,0,0)~
';
    'VSS'<773>:'(0,0,0,0,0,0,0,0,0,0,0,0,0,0,0,0,0,0,0,0,0,0,0,0,0,AL76,0,0,0,0)~
';
    'VSS'<772>:'(0,0,0,0,0,0,0,0,0,0,0,0,0,0,0,0,0,0,0,0,0,0,0,0,0,AL78,0,0,0,0)~
';
    'VSS'<771>:'(0,0,0,0,0,0,0,0,0,0,0,0,0,0,0,0,0,0,0,0,0,0,0,0,0,AL80,0,0,0,0)~
';
    'VSS'<770>:'(0,0,0,0,0,0,0,0,0,0,0,0,0,0,0,0,0,0,0,0,0,0,0,0,0,AL82,0,0,0,0)~
';
    'VSS'<769>:'(0,0,0,0,0,0,0,0,0,0,0,0,0,0,0,0,0,0,0,0,0,0,0,0,0,AL86,0,0,0,0)~
';
    'VSS'<768>:'(0,0,0,0,0,0,0,0,0,0,0,0,0,0,0,0,0,0,0,0,0,0,0,0,0,AM1,0,0,0,0)';
    'VSS'<767>:'(0,0,0,0,0,0,0,0,0,0,0,0,0,0,0,0,0,0,0,0,0,0,0,0,0,AC50,0,0,0,0)~
';
    'VSS'<766>:'(0,0,0,0,0,0,0,0,0,0,0,0,0,0,0,0,0,0,0,0,0,0,0,0,0,AM31,0,0,0,0)~
';
    'VSS'<765>:'(0,0,0,0,0,0,0,0,0,0,0,0,0,0,0,0,0,0,0,0,0,0,0,0,0,AM57,0,0,0,0)~
';
    'VSS'<764>:'(0,0,0,0,0,0,0,0,0,0,0,0,0,0,0,0,0,0,0,0,0,0,0,0,0,AM63,0,0,0,0)~
';
    'VSS'<763>:'(0,0,0,0,0,0,0,0,0,0,0,0,0,0,0,0,0,0,0,0,0,0,0,0,0,AM69,0,0,0,0)~
';
    'VSS'<762>:'(0,0,0,0,0,0,0,0,0,0,0,0,0,0,0,0,0,0,0,0,0,0,0,0,0,AM73,0,0,0,0)~
';
    'VSS'<761>:'(0,0,0,0,0,0,0,0,0,0,0,0,0,0,0,0,0,0,0,0,0,0,0,0,0,AM79,0,0,0,0)~
';
    'VSS'<760>:'(0,0,0,0,0,0,0,0,0,0,0,0,0,0,0,0,0,0,0,0,0,0,0,0,0,AM83,0,0,0,0)~
';
    'VSS'<759>:'(0,0,0,0,0,0,0,0,0,0,0,0,0,0,0,0,0,0,0,0,0,0,0,0,0,AN2,0,0,0,0)';
    'VSS'<758>:'(0,0,0,0,0,0,0,0,0,0,0,0,0,0,0,0,0,0,0,0,0,0,0,0,0,AN6,0,0,0,0)';
    'VSS'<757>:'(0,0,0,0,0,0,0,0,0,0,0,0,0,0,0,0,0,0,0,0,0,0,0,0,0,AN28,0,0,0,0)~
';
    'VSS'<756>:'(0,0,0,0,0,0,0,0,0,0,0,0,0,0,0,0,0,0,0,0,0,0,0,0,0,AN58,0,0,0,0)~
';
    'VSS'<755>:'(0,0,0,0,0,0,0,0,0,0,0,0,0,0,0,0,0,0,0,0,0,0,0,0,0,AN78,0,0,0,0)~
';
    'VSS'<754>:'(0,0,0,0,0,0,0,0,0,0,0,0,0,0,0,0,0,0,0,0,0,0,0,0,0,AP5,0,0,0,0)';
    'VSS'<753>:'(0,0,0,0,0,0,0,0,0,0,0,0,0,0,0,0,0,0,0,0,0,0,0,0,0,AP9,0,0,0,0)';
    'VSS'<752>:'(0,0,0,0,0,0,0,0,0,0,0,0,0,0,0,0,0,0,0,0,0,0,0,0,0,AP13,0,0,0,0)~
';
    'VSS'<751>:'(0,0,0,0,0,0,0,0,0,0,0,0,0,0,0,0,0,0,0,0,0,0,0,0,0,AP19,0,0,0,0)~
';
    'VSS'<750>:'(0,0,0,0,0,0,0,0,0,0,0,0,0,0,0,0,0,0,0,0,0,0,0,0,0,AP31,0,0,0,0)~
';
    'VSS'<749>:'(0,0,0,0,0,0,0,0,0,0,0,0,0,0,0,0,0,0,0,0,0,0,0,0,0,AP59,0,0,0,0)~
';
    'VSS'<748>:'(0,0,0,0,0,0,0,0,0,0,0,0,0,0,0,0,0,0,0,0,0,0,0,0,0,AP63,0,0,0,0)~
';
    'VSS'<747>:'(0,0,0,0,0,0,0,0,0,0,0,0,0,0,0,0,0,0,0,0,0,0,0,0,0,AP65,0,0,0,0)~
';
    'VSS'<746>:'(0,0,0,0,0,0,0,0,0,0,0,0,0,0,0,0,0,0,0,0,0,0,0,0,0,AP67,0,0,0,0)~
';
    'VSS'<745>:'(0,0,0,0,0,0,0,0,0,0,0,0,0,0,0,0,0,0,0,0,0,0,0,0,0,AP69,0,0,0,0)~
';
    'VSS'<744>:'(0,0,0,0,0,0,0,0,0,0,0,0,0,0,0,0,0,0,0,0,0,0,0,0,0,AP73,0,0,0,0)~
';
    'VSS'<743>:'(0,0,0,0,0,0,0,0,0,0,0,0,0,0,0,0,0,0,0,0,0,0,0,0,0,AP75,0,0,0,0)~
';
    'VSS'<742>:'(0,0,0,0,0,0,0,0,0,0,0,0,0,0,0,0,0,0,0,0,0,0,0,0,0,AP81,0,0,0,0)~
';
    'VSS'<741>:'(0,0,0,0,0,0,0,0,0,0,0,0,0,0,0,0,0,0,0,0,0,0,0,0,0,AP83,0,0,0,0)~
';
    'VSS'<740>:'(0,0,0,0,0,0,0,0,0,0,0,0,0,0,0,0,0,0,0,0,0,0,0,0,0,AP85,0,0,0,0)~
';
    'VSS'<739>:'(0,0,0,0,0,0,0,0,0,0,0,0,0,0,0,0,0,0,0,0,0,0,0,0,0,AR10,0,0,0,0)~
';
    'VSS'<738>:'(0,0,0,0,0,0,0,0,0,0,0,0,0,0,0,0,0,0,0,0,0,0,0,0,0,AR24,0,0,0,0)~
';
    'VSS'<737>:'(0,0,0,0,0,0,0,0,0,0,0,0,0,0,0,0,0,0,0,0,0,0,0,0,0,AR30,0,0,0,0)~
';
    'VSS'<736>:'(0,0,0,0,0,0,0,0,0,0,0,0,0,0,0,0,0,0,0,0,0,0,0,0,0,AR60,0,0,0,0)~
';
    'VSS'<735>:'(0,0,0,0,0,0,0,0,0,0,0,0,0,0,0,0,0,0,0,0,0,0,0,0,0,AR72,0,0,0,0)~
';
    'VSS'<734>:'(0,0,0,0,0,0,0,0,0,0,0,0,0,0,0,0,0,0,0,0,0,0,0,0,0,AR78,0,0,0,0)~
';
    'VSS'<733>:'(0,0,0,0,0,0,0,0,0,0,0,0,0,0,0,0,0,0,0,0,0,0,0,0,0,AC48,0,0,0,0)~
';
    'VSS'<732>:'(0,0,0,0,0,0,0,0,0,0,0,0,0,0,0,0,0,0,0,0,0,0,0,0,0,P63,0,0,0,0)';
    'VSS'<731>:'(0,0,0,0,0,0,0,0,0,0,0,0,0,0,0,0,0,0,0,0,0,0,0,0,0,AT15,0,0,0,0)~
';
    'VSS'<730>:'(0,0,0,0,0,0,0,0,0,0,0,0,0,0,0,0,0,0,0,0,0,0,0,0,0,AT17,0,0,0,0)~
';
    'VSS'<729>:'(0,0,0,0,0,0,0,0,0,0,0,0,0,0,0,0,0,0,0,0,0,0,0,0,0,AT21,0,0,0,0)~
';
    'VSS'<728>:'(0,0,0,0,0,0,0,0,0,0,0,0,0,0,0,0,0,0,0,0,0,0,0,0,0,AT27,0,0,0,0)~
';
    'VSS'<727>:'(0,0,0,0,0,0,0,0,0,0,0,0,0,0,0,0,0,0,0,0,0,0,0,0,0,AT61,0,0,0,0)~
';
    'VSS'<726>:'(0,0,0,0,0,0,0,0,0,0,0,0,0,0,0,0,0,0,0,0,0,0,0,0,0,AT63,0,0,0,0)~
';
    'VSS'<725>:'(0,0,0,0,0,0,0,0,0,0,0,0,0,0,0,0,0,0,0,0,0,0,0,0,0,AT69,0,0,0,0)~
';
    'VSS'<724>:'(0,0,0,0,0,0,0,0,0,0,0,0,0,0,0,0,0,0,0,0,0,0,0,0,0,AT73,0,0,0,0)~
';
    'VSS'<723>:'(0,0,0,0,0,0,0,0,0,0,0,0,0,0,0,0,0,0,0,0,0,0,0,0,0,AT77,0,0,0,0)~
';
    'VSS'<722>:'(0,0,0,0,0,0,0,0,0,0,0,0,0,0,0,0,0,0,0,0,0,0,0,0,0,AT83,0,0,0,0)~
';
    'VSS'<721>:'(0,0,0,0,0,0,0,0,0,0,0,0,0,0,0,0,0,0,0,0,0,0,0,0,0,AT85,0,0,0,0)~
';
    'VSS'<720>:'(0,0,0,0,0,0,0,0,0,0,0,0,0,0,0,0,0,0,0,0,0,0,0,0,0,AU2,0,0,0,0)';
    'VSS'<719>:'(0,0,0,0,0,0,0,0,0,0,0,0,0,0,0,0,0,0,0,0,0,0,0,0,0,AU6,0,0,0,0)';
    'VSS'<718>:'(0,0,0,0,0,0,0,0,0,0,0,0,0,0,0,0,0,0,0,0,0,0,0,0,0,AU26,0,0,0,0)~
';
    'VSS'<717>:'(0,0,0,0,0,0,0,0,0,0,0,0,0,0,0,0,0,0,0,0,0,0,0,0,0,AU28,0,0,0,0)~
';
    'VSS'<716>:'(0,0,0,0,0,0,0,0,0,0,0,0,0,0,0,0,0,0,0,0,0,0,0,0,0,AU62,0,0,0,0)~
';
    'VSS'<715>:'(0,0,0,0,0,0,0,0,0,0,0,0,0,0,0,0,0,0,0,0,0,0,0,0,0,AU64,0,0,0,0)~
';
    'VSS'<714>:'(0,0,0,0,0,0,0,0,0,0,0,0,0,0,0,0,0,0,0,0,0,0,0,0,0,AU68,0,0,0,0)~
';
    'VSS'<713>:'(0,0,0,0,0,0,0,0,0,0,0,0,0,0,0,0,0,0,0,0,0,0,0,0,0,AU74,0,0,0,0)~
';
    'VSS'<712>:'(0,0,0,0,0,0,0,0,0,0,0,0,0,0,0,0,0,0,0,0,0,0,0,0,0,AU76,0,0,0,0)~
';
    'VSS'<711>:'(0,0,0,0,0,0,0,0,0,0,0,0,0,0,0,0,0,0,0,0,0,0,0,0,0,AU78,0,0,0,0)~
';
    'VSS'<710>:'(0,0,0,0,0,0,0,0,0,0,0,0,0,0,0,0,0,0,0,0,0,0,0,0,0,AU80,0,0,0,0)~
';
    'VSS'<709>:'(0,0,0,0,0,0,0,0,0,0,0,0,0,0,0,0,0,0,0,0,0,0,0,0,0,AU84,0,0,0,0)~
';
    'VSS'<708>:'(0,0,0,0,0,0,0,0,0,0,0,0,0,0,0,0,0,0,0,0,0,0,0,0,0,AU86,0,0,0,0)~
';
    'VSS'<707>:'(0,0,0,0,0,0,0,0,0,0,0,0,0,0,0,0,0,0,0,0,0,0,0,0,0,AV1,0,0,0,0)';
    'VSS'<706>:'(0,0,0,0,0,0,0,0,0,0,0,0,0,0,0,0,0,0,0,0,0,0,0,0,0,AV3,0,0,0,0)';
    'VSS'<705>:'(0,0,0,0,0,0,0,0,0,0,0,0,0,0,0,0,0,0,0,0,0,0,0,0,0,AV7,0,0,0,0)';
    'VSS'<704>:'(0,0,0,0,0,0,0,0,0,0,0,0,0,0,0,0,0,0,0,0,0,0,0,0,0,AV11,0,0,0,0)~
';
    'VSS'<703>:'(0,0,0,0,0,0,0,0,0,0,0,0,0,0,0,0,0,0,0,0,0,0,0,0,0,AV13,0,0,0,0)~
';
    'VSS'<702>:'(0,0,0,0,0,0,0,0,0,0,0,0,0,0,0,0,0,0,0,0,0,0,0,0,0,AV19,0,0,0,0)~
';
    'VSS'<701>:'(0,0,0,0,0,0,0,0,0,0,0,0,0,0,0,0,0,0,0,0,0,0,0,0,0,AV23,0,0,0,0)~
';
    'VSS'<700>:'(0,0,0,0,0,0,0,0,0,0,0,0,0,0,0,0,0,0,0,0,0,0,0,0,0,AV25,0,0,0,0)~
';
    'VSS'<699>:'(0,0,0,0,0,0,0,0,0,0,0,0,0,0,0,0,0,0,0,0,0,0,0,0,0,AV63,0,0,0,0)~
';
    'VSS'<698>:'(0,0,0,0,0,0,0,0,0,0,0,0,0,0,0,0,0,0,0,0,0,0,0,0,0,AV65,0,0,0,0)~
';
    'VSS'<697>:'(0,0,0,0,0,0,0,0,0,0,0,0,0,0,0,0,0,0,0,0,0,0,0,0,0,AV67,0,0,0,0)~
';
    'VSS'<696>:'(0,0,0,0,0,0,0,0,0,0,0,0,0,0,0,0,0,0,0,0,0,0,0,0,0,AV75,0,0,0,0)~
';
    'VSS'<695>:'(0,0,0,0,0,0,0,0,0,0,0,0,0,0,0,0,0,0,0,0,0,0,0,0,0,AV83,0,0,0,0)~
';
    'VSS'<694>:'(0,0,0,0,0,0,0,0,0,0,0,0,0,0,0,0,0,0,0,0,0,0,0,0,0,AW2,0,0,0,0)';
    'VSS'<693>:'(0,0,0,0,0,0,0,0,0,0,0,0,0,0,0,0,0,0,0,0,0,0,0,0,0,AW10,0,0,0,0)~
';
    'VSS'<692>:'(0,0,0,0,0,0,0,0,0,0,0,0,0,0,0,0,0,0,0,0,0,0,0,0,0,AW62,0,0,0,0)~
';
    'VSS'<691>:'(0,0,0,0,0,0,0,0,0,0,0,0,0,0,0,0,0,0,0,0,0,0,0,0,0,AW66,0,0,0,0)~
';
    'VSS'<690>:'(0,0,0,0,0,0,0,0,0,0,0,0,0,0,0,0,0,0,0,0,0,0,0,0,0,AW68,0,0,0,0)~
';
    'VSS'<689>:'(0,0,0,0,0,0,0,0,0,0,0,0,0,0,0,0,0,0,0,0,0,0,0,0,0,AW70,0,0,0,0)~
';
    'VSS'<688>:'(0,0,0,0,0,0,0,0,0,0,0,0,0,0,0,0,0,0,0,0,0,0,0,0,0,AW72,0,0,0,0)~
';
    'VSS'<687>:'(0,0,0,0,0,0,0,0,0,0,0,0,0,0,0,0,0,0,0,0,0,0,0,0,0,AW74,0,0,0,0)~
';
    'VSS'<686>:'(0,0,0,0,0,0,0,0,0,0,0,0,0,0,0,0,0,0,0,0,0,0,0,0,0,AW78,0,0,0,0)~
';
    'VSS'<685>:'(0,0,0,0,0,0,0,0,0,0,0,0,0,0,0,0,0,0,0,0,0,0,0,0,0,AW82,0,0,0,0)~
';
    'VSS'<684>:'(0,0,0,0,0,0,0,0,0,0,0,0,0,0,0,0,0,0,0,0,0,0,0,0,0,AW84,0,0,0,0)~
';
    'VSS'<683>:'(0,0,0,0,0,0,0,0,0,0,0,0,0,0,0,0,0,0,0,0,0,0,0,0,0,AY5,0,0,0,0)';
    'VSS'<682>:'(0,0,0,0,0,0,0,0,0,0,0,0,0,0,0,0,0,0,0,0,0,0,0,0,0,AY15,0,0,0,0)~
';
    'VSS'<681>:'(0,0,0,0,0,0,0,0,0,0,0,0,0,0,0,0,0,0,0,0,0,0,0,0,0,AY17,0,0,0,0)~
';
    'VSS'<680>:'(0,0,0,0,0,0,0,0,0,0,0,0,0,0,0,0,0,0,0,0,0,0,0,0,0,AY21,0,0,0,0)~
';
    'VSS'<679>:'(0,0,0,0,0,0,0,0,0,0,0,0,0,0,0,0,0,0,0,0,0,0,0,0,0,AY23,0,0,0,0)~
';
    'VSS'<678>:'(0,0,0,0,0,0,0,0,0,0,0,0,0,0,0,0,0,0,0,0,0,0,0,0,0,AY25,0,0,0,0)~
';
    'VSS'<677>:'(0,0,0,0,0,0,0,0,0,0,0,0,0,0,0,0,0,0,0,0,0,0,0,0,0,AY63,0,0,0,0)~
';
    'VSS'<676>:'(0,0,0,0,0,0,0,0,0,0,0,0,0,0,0,0,0,0,0,0,0,0,0,0,0,AY79,0,0,0,0)~
';
    'VSS'<675>:'(0,0,0,0,0,0,0,0,0,0,0,0,0,0,0,0,0,0,0,0,0,0,0,0,0,AY81,0,0,0,0)~
';
    'VSS'<674>:'(0,0,0,0,0,0,0,0,0,0,0,0,0,0,0,0,0,0,0,0,0,0,0,0,0,BA2,0,0,0,0)';
    'VSS'<673>:'(0,0,0,0,0,0,0,0,0,0,0,0,0,0,0,0,0,0,0,0,0,0,0,0,0,BA6,0,0,0,0)';
    'VSS'<672>:'(0,0,0,0,0,0,0,0,0,0,0,0,0,0,0,0,0,0,0,0,0,0,0,0,0,BA12,0,0,0,0)~
';
    'VSS'<671>:'(0,0,0,0,0,0,0,0,0,0,0,0,0,0,0,0,0,0,0,0,0,0,0,0,0,BA62,0,0,0,0)~
';
    'VSS'<670>:'(0,0,0,0,0,0,0,0,0,0,0,0,0,0,0,0,0,0,0,0,0,0,0,0,0,BA68,0,0,0,0)~
';
    'VSS'<669>:'(0,0,0,0,0,0,0,0,0,0,0,0,0,0,0,0,0,0,0,0,0,0,0,0,0,BA74,0,0,0,0)~
';
    'VSS'<668>:'(0,0,0,0,0,0,0,0,0,0,0,0,0,0,0,0,0,0,0,0,0,0,0,0,0,BA80,0,0,0,0)~
';
    'VSS'<667>:'(0,0,0,0,0,0,0,0,0,0,0,0,0,0,0,0,0,0,0,0,0,0,0,0,0,BA84,0,0,0,0)~
';
    'VSS'<666>:'(0,0,0,0,0,0,0,0,0,0,0,0,0,0,0,0,0,0,0,0,0,0,0,0,0,BB19,0,0,0,0)~
';
    'VSS'<665>:'(0,0,0,0,0,0,0,0,0,0,0,0,0,0,0,0,0,0,0,0,0,0,0,0,0,BB23,0,0,0,0)~
';
    'VSS'<664>:'(0,0,0,0,0,0,0,0,0,0,0,0,0,0,0,0,0,0,0,0,0,0,0,0,0,BB63,0,0,0,0)~
';
    'VSS'<663>:'(0,0,0,0,0,0,0,0,0,0,0,0,0,0,0,0,0,0,0,0,0,0,0,0,0,BB69,0,0,0,0)~
';
    'VSS'<662>:'(0,0,0,0,0,0,0,0,0,0,0,0,0,0,0,0,0,0,0,0,0,0,0,0,0,BB73,0,0,0,0)~
';
    'VSS'<661>:'(0,0,0,0,0,0,0,0,0,0,0,0,0,0,0,0,0,0,0,0,0,0,0,0,0,BB75,0,0,0,0)~
';
    'VSS'<660>:'(0,0,0,0,0,0,0,0,0,0,0,0,0,0,0,0,0,0,0,0,0,0,0,0,0,BB77,0,0,0,0)~
';
    'VSS'<659>:'(0,0,0,0,0,0,0,0,0,0,0,0,0,0,0,0,0,0,0,0,0,0,0,0,0,BB79,0,0,0,0)~
';
    'VSS'<658>:'(0,0,0,0,0,0,0,0,0,0,0,0,0,0,0,0,0,0,0,0,0,0,0,0,0,BB81,0,0,0,0)~
';
    'VSS'<657>:'(0,0,0,0,0,0,0,0,0,0,0,0,0,0,0,0,0,0,0,0,0,0,0,0,0,BB83,0,0,0,0)~
';
    'VSS'<656>:'(0,0,0,0,0,0,0,0,0,0,0,0,0,0,0,0,0,0,0,0,0,0,0,0,0,BC4,0,0,0,0)';
    'VSS'<655>:'(0,0,0,0,0,0,0,0,0,0,0,0,0,0,0,0,0,0,0,0,0,0,0,0,0,BC8,0,0,0,0)';
    'VSS'<654>:'(0,0,0,0,0,0,0,0,0,0,0,0,0,0,0,0,0,0,0,0,0,0,0,0,0,BC12,0,0,0,0)~
';
    'VSS'<653>:'(0,0,0,0,0,0,0,0,0,0,0,0,0,0,0,0,0,0,0,0,0,0,0,0,0,BC16,0,0,0,0)~
';
    'VSS'<652>:'(0,0,0,0,0,0,0,0,0,0,0,0,0,0,0,0,0,0,0,0,0,0,0,0,0,BC70,0,0,0,0)~
';
    'VSS'<651>:'(0,0,0,0,0,0,0,0,0,0,0,0,0,0,0,0,0,0,0,0,0,0,0,0,0,BC72,0,0,0,0)~
';
    'VSS'<650>:'(0,0,0,0,0,0,0,0,0,0,0,0,0,0,0,0,0,0,0,0,0,0,0,0,0,BC74,0,0,0,0)~
';
    'VSS'<649>:'(0,0,0,0,0,0,0,0,0,0,0,0,0,0,0,0,0,0,0,0,0,0,0,0,0,BC76,0,0,0,0)~
';
    'VSS'<648>:'(0,0,0,0,0,0,0,0,0,0,0,0,0,0,0,0,0,0,0,0,0,0,0,0,0,BC78,0,0,0,0)~
';
    'VSS'<647>:'(0,0,0,0,0,0,0,0,0,0,0,0,0,0,0,0,0,0,0,0,0,0,0,0,0,BC80,0,0,0,0)~
';
    'VSS'<646>:'(0,0,0,0,0,0,0,0,0,0,0,0,0,0,0,0,0,0,0,0,0,0,0,0,0,BC82,0,0,0,0)~
';
    'VSS'<645>:'(0,0,0,0,0,0,0,0,0,0,0,0,0,0,0,0,0,0,0,0,0,0,0,0,0,BD5,0,0,0,0)';
    'VSS'<644>:'(0,0,0,0,0,0,0,0,0,0,0,0,0,0,0,0,0,0,0,0,0,0,0,0,0,BD11,0,0,0,0)~
';
    'VSS'<643>:'(0,0,0,0,0,0,0,0,0,0,0,0,0,0,0,0,0,0,0,0,0,0,0,0,0,BD15,0,0,0,0)~
';
    'VSS'<642>:'(0,0,0,0,0,0,0,0,0,0,0,0,0,0,0,0,0,0,0,0,0,0,0,0,0,BD21,0,0,0,0)~
';
    'VSS'<641>:'(0,0,0,0,0,0,0,0,0,0,0,0,0,0,0,0,0,0,0,0,0,0,0,0,0,BD27,0,0,0,0)~
';
    'VSS'<640>:'(0,0,0,0,0,0,0,0,0,0,0,0,0,0,0,0,0,0,0,0,0,0,0,0,0,BD63,0,0,0,0)~
';
    'VSS'<639>:'(0,0,0,0,0,0,0,0,0,0,0,0,0,0,0,0,0,0,0,0,0,0,0,0,0,BD71,0,0,0,0)~
';
    'VSS'<638>:'(0,0,0,0,0,0,0,0,0,0,0,0,0,0,0,0,0,0,0,0,0,0,0,0,0,BE4,0,0,0,0)';
    'VSS'<637>:'(0,0,0,0,0,0,0,0,0,0,0,0,0,0,0,0,0,0,0,0,0,0,0,0,0,BE6,0,0,0,0)';
    'VSS'<636>:'(0,0,0,0,0,0,0,0,0,0,0,0,0,0,0,0,0,0,0,0,0,0,0,0,0,BE8,0,0,0,0)';
    'VSS'<635>:'(0,0,0,0,0,0,0,0,0,0,0,0,0,0,0,0,0,0,0,0,0,0,0,0,0,BE10,0,0,0,0)~
';
    'VSS'<634>:'(0,0,0,0,0,0,0,0,0,0,0,0,0,0,0,0,0,0,0,0,0,0,0,0,0,BE26,0,0,0,0)~
';
    'VSS'<633>:'(0,0,0,0,0,0,0,0,0,0,0,0,0,0,0,0,0,0,0,0,0,0,0,0,0,BE64,0,0,0,0)~
';
    'VSS'<632>:'(0,0,0,0,0,0,0,0,0,0,0,0,0,0,0,0,0,0,0,0,0,0,0,0,0,BE66,0,0,0,0)~
';
    'VSS'<631>:'(0,0,0,0,0,0,0,0,0,0,0,0,0,0,0,0,0,0,0,0,0,0,0,0,0,BE68,0,0,0,0)~
';
    'VSS'<630>:'(0,0,0,0,0,0,0,0,0,0,0,0,0,0,0,0,0,0,0,0,0,0,0,0,0,BE70,0,0,0,0)~
';
    'VSS'<629>:'(0,0,0,0,0,0,0,0,0,0,0,0,0,0,0,0,0,0,0,0,0,0,0,0,0,BF9,0,0,0,0)';
    'VSS'<628>:'(0,0,0,0,0,0,0,0,0,0,0,0,0,0,0,0,0,0,0,0,0,0,0,0,0,BF15,0,0,0,0)~
';
    'VSS'<627>:'(0,0,0,0,0,0,0,0,0,0,0,0,0,0,0,0,0,0,0,0,0,0,0,0,0,BF17,0,0,0,0)~
';
    'VSS'<626>:'(0,0,0,0,0,0,0,0,0,0,0,0,0,0,0,0,0,0,0,0,0,0,0,0,0,BF19,0,0,0,0)~
';
    'VSS'<625>:'(0,0,0,0,0,0,0,0,0,0,0,0,0,0,0,0,0,0,0,0,0,0,0,0,0,BF25,0,0,0,0)~
';
    'VSS'<624>:'(0,0,0,0,0,0,0,0,0,0,0,0,0,0,0,0,0,0,0,0,0,0,0,0,0,BF63,0,0,0,0)~
';
    'VSS'<623>:'(0,0,0,0,0,0,0,0,0,0,0,0,0,0,0,0,0,0,0,0,0,0,0,0,0,BF65,0,0,0,0)~
';
    'VSS'<622>:'(0,0,0,0,0,0,0,0,0,0,0,0,0,0,0,0,0,0,0,0,0,0,0,0,0,BF67,0,0,0,0)~
';
    'VSS'<621>:'(0,0,0,0,0,0,0,0,0,0,0,0,0,0,0,0,0,0,0,0,0,0,0,0,0,BF69,0,0,0,0)~
';
    'VSS'<620>:'(0,0,0,0,0,0,0,0,0,0,0,0,0,0,0,0,0,0,0,0,0,0,0,0,0,BF71,0,0,0,0)~
';
    'VSS'<619>:'(0,0,0,0,0,0,0,0,0,0,0,0,0,0,0,0,0,0,0,0,0,0,0,0,0,BG6,0,0,0,0)';
    'VSS'<618>:'(0,0,0,0,0,0,0,0,0,0,0,0,0,0,0,0,0,0,0,0,0,0,0,0,0,BG8,0,0,0,0)';
    'VSS'<617>:'(0,0,0,0,0,0,0,0,0,0,0,0,0,0,0,0,0,0,0,0,0,0,0,0,0,BG10,0,0,0,0)~
';
    'VSS'<616>:'(0,0,0,0,0,0,0,0,0,0,0,0,0,0,0,0,0,0,0,0,0,0,0,0,0,BG22,0,0,0,0)~
';
    'VSS'<615>:'(0,0,0,0,0,0,0,0,0,0,0,0,0,0,0,0,0,0,0,0,0,0,0,0,0,BG24,0,0,0,0)~
';
    'VSS'<614>:'(0,0,0,0,0,0,0,0,0,0,0,0,0,0,0,0,0,0,0,0,0,0,0,0,0,BG72,0,0,0,0)~
';
    'VSS'<613>:'(0,0,0,0,0,0,0,0,0,0,0,0,0,0,0,0,0,0,0,0,0,0,0,0,0,0,BG74,0,0,0)~
';
    'VSS'<612>:'(0,0,0,0,0,0,0,0,0,0,0,0,0,0,0,0,0,0,0,0,0,0,0,0,0,0,BG76,0,0,0)~
';
    'VSS'<611>:'(0,0,0,0,0,0,0,0,0,0,0,0,0,0,0,0,0,0,0,0,0,0,0,0,0,0,BG78,0,0,0)~
';
    'VSS'<610>:'(0,0,0,0,0,0,0,0,0,0,0,0,0,0,0,0,0,0,0,0,0,0,0,0,0,0,BG80,0,0,0)~
';
    'VSS'<609>:'(0,0,0,0,0,0,0,0,0,0,0,0,0,0,0,0,0,0,0,0,0,0,0,0,0,0,BG82,0,0,0)~
';
    'VSS'<608>:'(0,0,0,0,0,0,0,0,0,0,0,0,0,0,0,0,0,0,0,0,0,0,0,0,0,0,BH7,0,0,0)';
    'VSS'<607>:'(0,0,0,0,0,0,0,0,0,0,0,0,0,0,0,0,0,0,0,0,0,0,0,0,0,0,BH9,0,0,0)';
    'VSS'<606>:'(0,0,0,0,0,0,0,0,0,0,0,0,0,0,0,0,0,0,0,0,0,0,0,0,0,0,BH11,0,0,0)~
';
    'VSS'<605>:'(0,0,0,0,0,0,0,0,0,0,0,0,0,0,0,0,0,0,0,0,0,0,0,0,0,0,BH15,0,0,0)~
';
    'VSS'<604>:'(0,0,0,0,0,0,0,0,0,0,0,0,0,0,0,0,0,0,0,0,0,0,0,0,0,0,BH21,0,0,0)~
';
    'VSS'<603>:'(0,0,0,0,0,0,0,0,0,0,0,0,0,0,0,0,0,0,0,0,0,0,0,0,0,0,BJ4,0,0,0)';
    'VSS'<602>:'(0,0,0,0,0,0,0,0,0,0,0,0,0,0,0,0,0,0,0,0,0,0,0,0,0,0,BJ6,0,0,0)';
    'VSS'<601>:'(0,0,0,0,0,0,0,0,0,0,0,0,0,0,0,0,0,0,0,0,0,0,0,0,0,0,BK3,0,0,0)';
    'VSS'<600>:'(0,0,0,0,0,0,0,0,0,0,0,0,0,0,0,0,0,0,0,0,0,0,0,0,0,0,BK7,0,0,0)';
    'VSS'<599>:'(0,0,0,0,0,0,0,0,0,0,0,0,0,0,0,0,0,0,0,0,0,0,0,0,0,0,BK11,0,0,0)~
';
    'VSS'<598>:'(0,0,0,0,0,0,0,0,0,0,0,0,0,0,0,0,0,0,0,0,0,0,0,0,0,0,BK19,0,0,0)~
';
    'VSS'<597>:'(0,0,0,0,0,0,0,0,0,0,0,0,0,0,0,0,0,0,0,0,0,0,0,0,0,0,BL6,0,0,0)';
    'VSS'<596>:'(0,0,0,0,0,0,0,0,0,0,0,0,0,0,0,0,0,0,0,0,0,0,0,0,0,0,BL10,0,0,0)~
';
    'VSS'<595>:'(0,0,0,0,0,0,0,0,0,0,0,0,0,0,0,0,0,0,0,0,0,0,0,0,0,0,BL12,0,0,0)~
';
    'VSS'<594>:'(0,0,0,0,0,0,0,0,0,0,0,0,0,0,0,0,0,0,0,0,0,0,0,0,0,0,P61,0,0,0)';
    'VSS'<593>:'(0,0,0,0,0,0,0,0,0,0,0,0,0,0,0,0,0,0,0,0,0,0,0,0,0,0,BL22,0,0,0)~
';
    'VSS'<592>:'(0,0,0,0,0,0,0,0,0,0,0,0,0,0,0,0,0,0,0,0,0,0,0,0,0,0,BL24,0,0,0)~
';
    'VSS'<591>:'(0,0,0,0,0,0,0,0,0,0,0,0,0,0,0,0,0,0,0,0,0,0,0,0,0,0,BL64,0,0,0)~
';
    'VSS'<590>:'(0,0,0,0,0,0,0,0,0,0,0,0,0,0,0,0,0,0,0,0,0,0,0,0,0,0,BL66,0,0,0)~
';
    'VSS'<589>:'(0,0,0,0,0,0,0,0,0,0,0,0,0,0,0,0,0,0,0,0,0,0,0,0,0,0,BL68,0,0,0)~
';
    'VSS'<588>:'(0,0,0,0,0,0,0,0,0,0,0,0,0,0,0,0,0,0,0,0,0,0,0,0,0,0,BL70,0,0,0)~
';
    'VSS'<587>:'(0,0,0,0,0,0,0,0,0,0,0,0,0,0,0,0,0,0,0,0,0,0,0,0,0,0,BL72,0,0,0)~
';
    'VSS'<586>:'(0,0,0,0,0,0,0,0,0,0,0,0,0,0,0,0,0,0,0,0,0,0,0,0,0,0,BL74,0,0,0)~
';
    'VSS'<585>:'(0,0,0,0,0,0,0,0,0,0,0,0,0,0,0,0,0,0,0,0,0,0,0,0,0,0,BL76,0,0,0)~
';
    'VSS'<584>:'(0,0,0,0,0,0,0,0,0,0,0,0,0,0,0,0,0,0,0,0,0,0,0,0,0,0,BL78,0,0,0)~
';
    'VSS'<583>:'(0,0,0,0,0,0,0,0,0,0,0,0,0,0,0,0,0,0,0,0,0,0,0,0,0,0,BL80,0,0,0)~
';
    'VSS'<582>:'(0,0,0,0,0,0,0,0,0,0,0,0,0,0,0,0,0,0,0,0,0,0,0,0,0,0,BL82,0,0,0)~
';
    'VSS'<581>:'(0,0,0,0,0,0,0,0,0,0,0,0,0,0,0,0,0,0,0,0,0,0,0,0,0,0,BM9,0,0,0)';
    'VSS'<580>:'(0,0,0,0,0,0,0,0,0,0,0,0,0,0,0,0,0,0,0,0,0,0,0,0,0,0,BM13,0,0,0)~
';
    'VSS'<579>:'(0,0,0,0,0,0,0,0,0,0,0,0,0,0,0,0,0,0,0,0,0,0,0,0,0,0,BM15,0,0,0)~
';
    'VSS'<578>:'(0,0,0,0,0,0,0,0,0,0,0,0,0,0,0,0,0,0,0,0,0,0,0,0,0,0,P59,0,0,0)';
    'VSS'<577>:'(0,0,0,0,0,0,0,0,0,0,0,0,0,0,0,0,0,0,0,0,0,0,0,0,0,0,BM25,0,0,0)~
';
    'VSS'<576>:'(0,0,0,0,0,0,0,0,0,0,0,0,0,0,0,0,0,0,0,0,0,0,0,0,0,0,BN6,0,0,0)';
    'VSS'<575>:'(0,0,0,0,0,0,0,0,0,0,0,0,0,0,0,0,0,0,0,0,0,0,0,0,0,0,BN10,0,0,0)~
';
    'VSS'<574>:'(0,0,0,0,0,0,0,0,0,0,0,0,0,0,0,0,0,0,0,0,0,0,0,0,0,0,BN20,0,0,0)~
';
    'VSS'<573>:'(0,0,0,0,0,0,0,0,0,0,0,0,0,0,0,0,0,0,0,0,0,0,0,0,0,0,BN26,0,0,0)~
';
    'VSS'<572>:'(0,0,0,0,0,0,0,0,0,0,0,0,0,0,0,0,0,0,0,0,0,0,0,0,0,0,BP3,0,0,0)';
    'VSS'<571>:'(0,0,0,0,0,0,0,0,0,0,0,0,0,0,0,0,0,0,0,0,0,0,0,0,0,0,BP27,0,0,0)~
';
    'VSS'<570>:'(0,0,0,0,0,0,0,0,0,0,0,0,0,0,0,0,0,0,0,0,0,0,0,0,0,0,BR6,0,0,0)';
    'VSS'<569>:'(0,0,0,0,0,0,0,0,0,0,0,0,0,0,0,0,0,0,0,0,0,0,0,0,0,0,BR10,0,0,0)~
';
    'VSS'<568>:'(0,0,0,0,0,0,0,0,0,0,0,0,0,0,0,0,0,0,0,0,0,0,0,0,0,0,BR16,0,0,0)~
';
    'VSS'<567>:'(0,0,0,0,0,0,0,0,0,0,0,0,0,0,0,0,0,0,0,0,0,0,0,0,0,0,P57,0,0,0)';
    'VSS'<566>:'(0,0,0,0,0,0,0,0,0,0,0,0,0,0,0,0,0,0,0,0,0,0,0,0,0,0,BR64,0,0,0)~
';
    'VSS'<565>:'(0,0,0,0,0,0,0,0,0,0,0,0,0,0,0,0,0,0,0,0,0,0,0,0,0,0,BR66,0,0,0)~
';
    'VSS'<564>:'(0,0,0,0,0,0,0,0,0,0,0,0,0,0,0,0,0,0,0,0,0,0,0,0,0,0,BR68,0,0,0)~
';
    'VSS'<563>:'(0,0,0,0,0,0,0,0,0,0,0,0,0,0,0,0,0,0,0,0,0,0,0,0,0,0,BR70,0,0,0)~
';
    'VSS'<562>:'(0,0,0,0,0,0,0,0,0,0,0,0,0,0,0,0,0,0,0,0,0,0,0,0,0,0,BR72,0,0,0)~
';
    'VSS'<561>:'(0,0,0,0,0,0,0,0,0,0,0,0,0,0,0,0,0,0,0,0,0,0,0,0,0,0,BR74,0,0,0)~
';
    'VSS'<560>:'(0,0,0,0,0,0,0,0,0,0,0,0,0,0,0,0,0,0,0,0,0,0,0,0,0,0,BR76,0,0,0)~
';
    'VSS'<559>:'(0,0,0,0,0,0,0,0,0,0,0,0,0,0,0,0,0,0,0,0,0,0,0,0,0,0,BR78,0,0,0)~
';
    'VSS'<558>:'(0,0,0,0,0,0,0,0,0,0,0,0,0,0,0,0,0,0,0,0,0,0,0,0,0,0,BR80,0,0,0)~
';
    'VSS'<557>:'(0,0,0,0,0,0,0,0,0,0,0,0,0,0,0,0,0,0,0,0,0,0,0,0,0,0,BR82,0,0,0)~
';
    'VSS'<556>:'(0,0,0,0,0,0,0,0,0,0,0,0,0,0,0,0,0,0,0,0,0,0,0,0,0,0,BT3,0,0,0)';
    'VSS'<555>:'(0,0,0,0,0,0,0,0,0,0,0,0,0,0,0,0,0,0,0,0,0,0,0,0,0,0,BT5,0,0,0)';
    'VSS'<554>:'(0,0,0,0,0,0,0,0,0,0,0,0,0,0,0,0,0,0,0,0,0,0,0,0,0,0,BT21,0,0,0)~
';
    'VSS'<553>:'(0,0,0,0,0,0,0,0,0,0,0,0,0,0,0,0,0,0,0,0,0,0,0,0,0,0,BT23,0,0,0)~
';
    'VSS'<552>:'(0,0,0,0,0,0,0,0,0,0,0,0,0,0,0,0,0,0,0,0,0,0,0,0,0,0,BT25,0,0,0)~
';
    'VSS'<551>:'(0,0,0,0,0,0,0,0,0,0,0,0,0,0,0,0,0,0,0,0,0,0,0,0,0,0,BU8,0,0,0)';
    'VSS'<550>:'(0,0,0,0,0,0,0,0,0,0,0,0,0,0,0,0,0,0,0,0,0,0,0,0,0,0,BV5,0,0,0)';
    'VSS'<549>:'(0,0,0,0,0,0,0,0,0,0,0,0,0,0,0,0,0,0,0,0,0,0,0,0,0,0,BU10,0,0,0)~
';
    'VSS'<548>:'(0,0,0,0,0,0,0,0,0,0,0,0,0,0,0,0,0,0,0,0,0,0,0,0,0,0,BV17,0,0,0)~
';
    'VSS'<547>:'(0,0,0,0,0,0,0,0,0,0,0,0,0,0,0,0,0,0,0,0,0,0,0,0,0,0,BV25,0,0,0)~
';
    'VSS'<546>:'(0,0,0,0,0,0,0,0,0,0,0,0,0,0,0,0,0,0,0,0,0,0,0,0,0,0,BW6,0,0,0)';
    'VSS'<545>:'(0,0,0,0,0,0,0,0,0,0,0,0,0,0,0,0,0,0,0,0,0,0,0,0,0,0,P55,0,0,0)';
    'VSS'<544>:'(0,0,0,0,0,0,0,0,0,0,0,0,0,0,0,0,0,0,0,0,0,0,0,0,0,0,BW12,0,0,0)~
';
    'VSS'<543>:'(0,0,0,0,0,0,0,0,0,0,0,0,0,0,0,0,0,0,0,0,0,0,0,0,0,0,BW14,0,0,0)~
';
    'VSS'<542>:'(0,0,0,0,0,0,0,0,0,0,0,0,0,0,0,0,0,0,0,0,0,0,0,0,0,0,BW16,0,0,0)~
';
    'VSS'<541>:'(0,0,0,0,0,0,0,0,0,0,0,0,0,0,0,0,0,0,0,0,0,0,0,0,0,0,BW18,0,0,0)~
';
    'VSS'<540>:'(0,0,0,0,0,0,0,0,0,0,0,0,0,0,0,0,0,0,0,0,0,0,0,0,0,0,BW26,0,0,0)~
';
    'VSS'<539>:'(0,0,0,0,0,0,0,0,0,0,0,0,0,0,0,0,0,0,0,0,0,0,0,0,0,0,BW72,0,0,0)~
';
    'VSS'<538>:'(0,0,0,0,0,0,0,0,0,0,0,0,0,0,0,0,0,0,0,0,0,0,0,0,0,0,BW74,0,0,0)~
';
    'VSS'<537>:'(0,0,0,0,0,0,0,0,0,0,0,0,0,0,0,0,0,0,0,0,0,0,0,0,0,0,BW76,0,0,0)~
';
    'VSS'<536>:'(0,0,0,0,0,0,0,0,0,0,0,0,0,0,0,0,0,0,0,0,0,0,0,0,0,0,BW78,0,0,0)~
';
    'VSS'<535>:'(0,0,0,0,0,0,0,0,0,0,0,0,0,0,0,0,0,0,0,0,0,0,0,0,0,0,BW80,0,0,0)~
';
    'VSS'<534>:'(0,0,0,0,0,0,0,0,0,0,0,0,0,0,0,0,0,0,0,0,0,0,0,0,0,0,BW82,0,0,0)~
';
    'VSS'<533>:'(0,0,0,0,0,0,0,0,0,0,0,0,0,0,0,0,0,0,0,0,0,0,0,0,0,0,BY11,0,0,0)~
';
    'VSS'<532>:'(0,0,0,0,0,0,0,0,0,0,0,0,0,0,0,0,0,0,0,0,0,0,0,0,0,0,BY13,0,0,0)~
';
    'VSS'<531>:'(0,0,0,0,0,0,0,0,0,0,0,0,0,0,0,0,0,0,0,0,0,0,0,0,0,0,BY23,0,0,0)~
';
    'VSS'<530>:'(0,0,0,0,0,0,0,0,0,0,0,0,0,0,0,0,0,0,0,0,0,0,0,0,0,0,BY63,0,0,0)~
';
    'VSS'<529>:'(0,0,0,0,0,0,0,0,0,0,0,0,0,0,0,0,0,0,0,0,0,0,0,0,0,0,BY65,0,0,0)~
';
    'VSS'<528>:'(0,0,0,0,0,0,0,0,0,0,0,0,0,0,0,0,0,0,0,0,0,0,0,0,0,0,BY67,0,0,0)~
';
    'VSS'<527>:'(0,0,0,0,0,0,0,0,0,0,0,0,0,0,0,0,0,0,0,0,0,0,0,0,0,0,BY69,0,0,0)~
';
    'VSS'<526>:'(0,0,0,0,0,0,0,0,0,0,0,0,0,0,0,0,0,0,0,0,0,0,0,0,0,0,BY71,0,0,0)~
';
    'VSS'<525>:'(0,0,0,0,0,0,0,0,0,0,0,0,0,0,0,0,0,0,0,0,0,0,0,0,0,0,CA2,0,0,0)';
    'VSS'<524>:'(0,0,0,0,0,0,0,0,0,0,0,0,0,0,0,0,0,0,0,0,0,0,0,0,0,0,CA6,0,0,0)';
    'VSS'<523>:'(0,0,0,0,0,0,0,0,0,0,0,0,0,0,0,0,0,0,0,0,0,0,0,0,0,0,CA8,0,0,0)';
    'VSS'<522>:'(0,0,0,0,0,0,0,0,0,0,0,0,0,0,0,0,0,0,0,0,0,0,0,0,0,0,CA10,0,0,0)~
';
    'VSS'<521>:'(0,0,0,0,0,0,0,0,0,0,0,0,0,0,0,0,0,0,0,0,0,0,0,0,0,0,CA14,0,0,0)~
';
    'VSS'<520>:'(0,0,0,0,0,0,0,0,0,0,0,0,0,0,0,0,0,0,0,0,0,0,0,0,0,0,CA18,0,0,0)~
';
    'VSS'<519>:'(0,0,0,0,0,0,0,0,0,0,0,0,0,0,0,0,0,0,0,0,0,0,0,0,0,0,CA26,0,0,0)~
';
    'VSS'<518>:'(0,0,0,0,0,0,0,0,0,0,0,0,0,0,0,0,0,0,0,0,0,0,0,0,0,0,CA64,0,0,0)~
';
    'VSS'<517>:'(0,0,0,0,0,0,0,0,0,0,0,0,0,0,0,0,0,0,0,0,0,0,0,0,0,0,CA66,0,0,0)~
';
    'VSS'<516>:'(0,0,0,0,0,0,0,0,0,0,0,0,0,0,0,0,0,0,0,0,0,0,0,0,0,0,CA68,0,0,0)~
';
    'VSS'<515>:'(0,0,0,0,0,0,0,0,0,0,0,0,0,0,0,0,0,0,0,0,0,0,0,0,0,0,CA70,0,0,0)~
';
    'VSS'<514>:'(0,0,0,0,0,0,0,0,0,0,0,0,0,0,0,0,0,0,0,0,0,0,0,0,0,0,CB7,0,0,0)';
    'VSS'<513>:'(0,0,0,0,0,0,0,0,0,0,0,0,0,0,0,0,0,0,0,0,0,0,0,0,0,0,CB9,0,0,0)';
    'VSS'<512>:'(0,0,0,0,0,0,0,0,0,0,0,0,0,0,0,0,0,0,0,0,0,0,0,0,0,0,CB27,0,0,0)~
';
    'VSS'<511>:'(0,0,0,0,0,0,0,0,0,0,0,0,0,0,0,0,0,0,0,0,0,0,0,0,0,0,CB63,0,0,0)~
';
    'VSS'<510>:'(0,0,0,0,0,0,0,0,0,0,0,0,0,0,0,0,0,0,0,0,0,0,0,0,0,0,CB71,0,0,0)~
';
    'VSS'<509>:'(0,0,0,0,0,0,0,0,0,0,0,0,0,0,0,0,0,0,0,0,0,0,0,0,0,0,CC4,0,0,0)';
    'VSS'<508>:'(0,0,0,0,0,0,0,0,0,0,0,0,0,0,0,0,0,0,0,0,0,0,0,0,0,0,CC16,0,0,0)~
';
    'VSS'<507>:'(0,0,0,0,0,0,0,0,0,0,0,0,0,0,0,0,0,0,0,0,0,0,0,0,0,0,CC18,0,0,0)~
';
    'VSS'<506>:'(0,0,0,0,0,0,0,0,0,0,0,0,0,0,0,0,0,0,0,0,0,0,0,0,0,0,CC24,0,0,0)~
';
    'VSS'<505>:'(0,0,0,0,0,0,0,0,0,0,0,0,0,0,0,0,0,0,0,0,0,0,0,0,0,0,CC64,0,0,0)~
';
    'VSS'<504>:'(0,0,0,0,0,0,0,0,0,0,0,0,0,0,0,0,0,0,0,0,0,0,0,0,0,0,CC72,0,0,0)~
';
    'VSS'<503>:'(0,0,0,0,0,0,0,0,0,0,0,0,0,0,0,0,0,0,0,0,0,0,0,0,0,0,CC74,0,0,0)~
';
    'VSS'<502>:'(0,0,0,0,0,0,0,0,0,0,0,0,0,0,0,0,0,0,0,0,0,0,0,0,0,0,CC76,0,0,0)~
';
    'VSS'<501>:'(0,0,0,0,0,0,0,0,0,0,0,0,0,0,0,0,0,0,0,0,0,0,0,0,0,0,CC78,0,0,0)~
';
    'VSS'<500>:'(0,0,0,0,0,0,0,0,0,0,0,0,0,0,0,0,0,0,0,0,0,0,0,0,0,0,CC80,0,0,0)~
';
    'VSS'<499>:'(0,0,0,0,0,0,0,0,0,0,0,0,0,0,0,0,0,0,0,0,0,0,0,0,0,0,CC82,0,0,0)~
';
    'VSS'<498>:'(0,0,0,0,0,0,0,0,0,0,0,0,0,0,0,0,0,0,0,0,0,0,0,0,0,0,CD5,0,0,0)';
    'VSS'<497>:'(0,0,0,0,0,0,0,0,0,0,0,0,0,0,0,0,0,0,0,0,0,0,0,0,0,0,CD13,0,0,0)~
';
    'VSS'<496>:'(0,0,0,0,0,0,0,0,0,0,0,0,0,0,0,0,0,0,0,0,0,0,0,0,0,0,CD63,0,0,0)~
';
    'VSS'<495>:'(0,0,0,0,0,0,0,0,0,0,0,0,0,0,0,0,0,0,0,0,0,0,0,0,0,0,CD73,0,0,0)~
';
    'VSS'<494>:'(0,0,0,0,0,0,0,0,0,0,0,0,0,0,0,0,0,0,0,0,0,0,0,0,0,0,CD75,0,0,0)~
';
    'VSS'<493>:'(0,0,0,0,0,0,0,0,0,0,0,0,0,0,0,0,0,0,0,0,0,0,0,0,0,0,CD77,0,0,0)~
';
    'VSS'<492>:'(0,0,0,0,0,0,0,0,0,0,0,0,0,0,0,0,0,0,0,0,0,0,0,0,0,0,CD79,0,0,0)~
';
    'VSS'<491>:'(0,0,0,0,0,0,0,0,0,0,0,0,0,0,0,0,0,0,0,0,0,0,0,0,0,0,CD81,0,0,0)~
';
    'VSS'<490>:'(0,0,0,0,0,0,0,0,0,0,0,0,0,0,0,0,0,0,0,0,0,0,0,0,0,0,CE10,0,0,0)~
';
    'VSS'<489>:'(0,0,0,0,0,0,0,0,0,0,0,0,0,0,0,0,0,0,0,0,0,0,0,0,0,0,CE14,0,0,0)~
';
    'VSS'<488>:'(0,0,0,0,0,0,0,0,0,0,0,0,0,0,0,0,0,0,0,0,0,0,0,0,0,0,CE20,0,0,0)~
';
    'VSS'<487>:'(0,0,0,0,0,0,0,0,0,0,0,0,0,0,0,0,0,0,0,0,0,0,0,0,0,0,CE26,0,0,0)~
';
    'VSS'<486>:'(0,0,0,0,0,0,0,0,0,0,0,0,0,0,0,0,0,0,0,0,0,0,0,0,0,0,CE62,0,0,0)~
';
    'VSS'<485>:'(0,0,0,0,0,0,0,0,0,0,0,0,0,0,0,0,0,0,0,0,0,0,0,0,0,0,CE70,0,0,0)~
';
    'VSS'<484>:'(0,0,0,0,0,0,0,0,0,0,0,0,0,0,0,0,0,0,0,0,0,0,0,0,0,0,CE82,0,0,0)~
';
    'VSS'<483>:'(0,0,0,0,0,0,0,0,0,0,0,0,0,0,0,0,0,0,0,0,0,0,0,0,0,0,P53,0,0,0)';
    'VSS'<482>:'(0,0,0,0,0,0,0,0,0,0,0,0,0,0,0,0,0,0,0,0,0,0,0,0,0,0,CF9,0,0,0)';
    'VSS'<481>:'(0,0,0,0,0,0,0,0,0,0,0,0,0,0,0,0,0,0,0,0,0,0,0,0,0,0,CF63,0,0,0)~
';
    'VSS'<480>:'(0,0,0,0,0,0,0,0,0,0,0,0,0,0,0,0,0,0,0,0,0,0,0,0,0,0,CF69,0,0,0)~
';
    'VSS'<479>:'(0,0,0,0,0,0,0,0,0,0,0,0,0,0,0,0,0,0,0,0,0,0,0,0,0,0,CF71,0,0,0)~
';
    'VSS'<478>:'(0,0,0,0,0,0,0,0,0,0,0,0,0,0,0,0,0,0,0,0,0,0,0,0,0,0,CF77,0,0,0)~
';
    'VSS'<477>:'(0,0,0,0,0,0,0,0,0,0,0,0,0,0,0,0,0,0,0,0,0,0,0,0,0,0,CF83,0,0,0)~
';
    'VSS'<476>:'(0,0,0,0,0,0,0,0,0,0,0,0,0,0,0,0,0,0,0,0,0,0,0,0,0,0,P51,0,0,0)';
    'VSS'<475>:'(0,0,0,0,0,0,0,0,0,0,0,0,0,0,0,0,0,0,0,0,0,0,0,0,0,0,CG18,0,0,0)~
';
    'VSS'<474>:'(0,0,0,0,0,0,0,0,0,0,0,0,0,0,0,0,0,0,0,0,0,0,0,0,0,0,CG22,0,0,0)~
';
    'VSS'<473>:'(0,0,0,0,0,0,0,0,0,0,0,0,0,0,0,0,0,0,0,0,0,0,0,0,0,0,CG62,0,0,0)~
';
    'VSS'<472>:'(0,0,0,0,0,0,0,0,0,0,0,0,0,0,0,0,0,0,0,0,0,0,0,0,0,0,CG68,0,0,0)~
';
    'VSS'<471>:'(0,0,0,0,0,0,0,0,0,0,0,0,0,0,0,0,0,0,0,0,0,0,0,0,0,0,CG72,0,0,0)~
';
    'VSS'<470>:'(0,0,0,0,0,0,0,0,0,0,0,0,0,0,0,0,0,0,0,0,0,0,0,0,0,0,CG80,0,0,0)~
';
    'VSS'<469>:'(0,0,0,0,0,0,0,0,0,0,0,0,0,0,0,0,0,0,0,0,0,0,0,0,0,0,CH1,0,0,0)';
    'VSS'<468>:'(0,0,0,0,0,0,0,0,0,0,0,0,0,0,0,0,0,0,0,0,0,0,0,0,0,0,CH3,0,0,0)';
    'VSS'<467>:'(0,0,0,0,0,0,0,0,0,0,0,0,0,0,0,0,0,0,0,0,0,0,0,0,0,0,CH15,0,0,0)~
';
    'VSS'<466>:'(0,0,0,0,0,0,0,0,0,0,0,0,0,0,0,0,0,0,0,0,0,0,0,0,0,0,CH19,0,0,0)~
';
    'VSS'<465>:'(0,0,0,0,0,0,0,0,0,0,0,0,0,0,0,0,0,0,0,0,0,0,0,0,0,0,CH63,0,0,0)~
';
    'VSS'<464>:'(0,0,0,0,0,0,0,0,0,0,0,0,0,0,0,0,0,0,0,0,0,0,0,0,0,0,CH67,0,0,0)~
';
    'VSS'<463>:'(0,0,0,0,0,0,0,0,0,0,0,0,0,0,0,0,0,0,0,0,0,0,0,0,0,0,CH73,0,0,0)~
';
    'VSS'<462>:'(0,0,0,0,0,0,0,0,0,0,0,0,0,0,0,0,0,0,0,0,0,0,0,0,0,0,CH79,0,0,0)~
';
    'VSS'<461>:'(0,0,0,0,0,0,0,0,0,0,0,0,0,0,0,0,0,0,0,0,0,0,0,0,0,0,CH81,0,0,0)~
';
    'VSS'<460>:'(0,0,0,0,0,0,0,0,0,0,0,0,0,0,0,0,0,0,0,0,0,0,0,0,0,0,CH83,0,0,0)~
';
    'VSS'<459>:'(0,0,0,0,0,0,0,0,0,0,0,0,0,0,0,0,0,0,0,0,0,0,0,0,0,0,CJ2,0,0,0)';
    'VSS'<458>:'(0,0,0,0,0,0,0,0,0,0,0,0,0,0,0,0,0,0,0,0,0,0,0,0,0,0,CJ6,0,0,0)';
    'VSS'<457>:'(0,0,0,0,0,0,0,0,0,0,0,0,0,0,0,0,0,0,0,0,0,0,0,0,0,0,CJ8,0,0,0)';
    'VSS'<456>:'(0,0,0,0,0,0,0,0,0,0,0,0,0,0,0,0,0,0,0,0,0,0,0,0,0,0,CJ10,0,0,0)~
';
    'VSS'<455>:'(0,0,0,0,0,0,0,0,0,0,0,0,0,0,0,0,0,0,0,0,0,0,0,0,0,0,CJ12,0,0,0)~
';
    'VSS'<454>:'(0,0,0,0,0,0,0,0,0,0,0,0,0,0,0,0,0,0,0,0,0,0,0,0,0,0,P49,0,0,0)';
    'VSS'<453>:'(0,0,0,0,0,0,0,0,0,0,0,0,0,0,0,0,0,0,0,0,0,0,0,0,0,0,0,P47,0,0)';
    'VSS'<452>:'(0,0,0,0,0,0,0,0,0,0,0,0,0,0,0,0,0,0,0,0,0,0,0,0,0,0,0,CJ62,0,0)~
';
    'VSS'<451>:'(0,0,0,0,0,0,0,0,0,0,0,0,0,0,0,0,0,0,0,0,0,0,0,0,0,0,0,CJ74,0,0)~
';
    'VSS'<450>:'(0,0,0,0,0,0,0,0,0,0,0,0,0,0,0,0,0,0,0,0,0,0,0,0,0,0,0,CJ76,0,0)~
';
    'VSS'<449>:'(0,0,0,0,0,0,0,0,0,0,0,0,0,0,0,0,0,0,0,0,0,0,0,0,0,0,0,CJ78,0,0)~
';
    'VSS'<448>:'(0,0,0,0,0,0,0,0,0,0,0,0,0,0,0,0,0,0,0,0,0,0,0,0,0,0,0,CJ82,0,0)~
';
    'VSS'<447>:'(0,0,0,0,0,0,0,0,0,0,0,0,0,0,0,0,0,0,0,0,0,0,0,0,0,0,0,CJ84,0,0)~
';
    'VSS'<446>:'(0,0,0,0,0,0,0,0,0,0,0,0,0,0,0,0,0,0,0,0,0,0,0,0,0,0,0,CJ86,0,0)~
';
    'VSS'<445>:'(0,0,0,0,0,0,0,0,0,0,0,0,0,0,0,0,0,0,0,0,0,0,0,0,0,0,0,CK11,0,0)~
';
    'VSS'<444>:'(0,0,0,0,0,0,0,0,0,0,0,0,0,0,0,0,0,0,0,0,0,0,0,0,0,0,0,CK15,0,0)~
';
    'VSS'<443>:'(0,0,0,0,0,0,0,0,0,0,0,0,0,0,0,0,0,0,0,0,0,0,0,0,0,0,0,CK21,0,0)~
';
    'VSS'<442>:'(0,0,0,0,0,0,0,0,0,0,0,0,0,0,0,0,0,0,0,0,0,0,0,0,0,0,0,CK27,0,0)~
';
    'VSS'<441>:'(0,0,0,0,0,0,0,0,0,0,0,0,0,0,0,0,0,0,0,0,0,0,0,0,0,0,0,CK63,0,0)~
';
    'VSS'<440>:'(0,0,0,0,0,0,0,0,0,0,0,0,0,0,0,0,0,0,0,0,0,0,0,0,0,0,0,CK65,0,0)~
';
    'VSS'<439>:'(0,0,0,0,0,0,0,0,0,0,0,0,0,0,0,0,0,0,0,0,0,0,0,0,0,0,0,CK67,0,0)~
';
    'VSS'<438>:'(0,0,0,0,0,0,0,0,0,0,0,0,0,0,0,0,0,0,0,0,0,0,0,0,0,0,0,CK69,0,0)~
';
    'VSS'<437>:'(0,0,0,0,0,0,0,0,0,0,0,0,0,0,0,0,0,0,0,0,0,0,0,0,0,0,0,CK71,0,0)~
';
    'VSS'<436>:'(0,0,0,0,0,0,0,0,0,0,0,0,0,0,0,0,0,0,0,0,0,0,0,0,0,0,0,CK73,0,0)~
';
    'VSS'<435>:'(0,0,0,0,0,0,0,0,0,0,0,0,0,0,0,0,0,0,0,0,0,0,0,0,0,0,0,CK75,0,0)~
';
    'VSS'<434>:'(0,0,0,0,0,0,0,0,0,0,0,0,0,0,0,0,0,0,0,0,0,0,0,0,0,0,0,CK83,0,0)~
';
    'VSS'<433>:'(0,0,0,0,0,0,0,0,0,0,0,0,0,0,0,0,0,0,0,0,0,0,0,0,0,0,0,CK85,0,0)~
';
    'VSS'<432>:'(0,0,0,0,0,0,0,0,0,0,0,0,0,0,0,0,0,0,0,0,0,0,0,0,0,0,0,CL8,0,0)';
    'VSS'<431>:'(0,0,0,0,0,0,0,0,0,0,0,0,0,0,0,0,0,0,0,0,0,0,0,0,0,0,0,CL14,0,0)~
';
    'VSS'<430>:'(0,0,0,0,0,0,0,0,0,0,0,0,0,0,0,0,0,0,0,0,0,0,0,0,0,0,0,CL18,0,0)~
';
    'VSS'<429>:'(0,0,0,0,0,0,0,0,0,0,0,0,0,0,0,0,0,0,0,0,0,0,0,0,0,0,0,P45,0,0)';
    'VSS'<428>:'(0,0,0,0,0,0,0,0,0,0,0,0,0,0,0,0,0,0,0,0,0,0,0,0,0,0,0,H63,0,0)';
    'VSS'<427>:'(0,0,0,0,0,0,0,0,0,0,0,0,0,0,0,0,0,0,0,0,0,0,0,0,0,0,0,CL62,0,0)~
';
    'VSS'<426>:'(0,0,0,0,0,0,0,0,0,0,0,0,0,0,0,0,0,0,0,0,0,0,0,0,0,0,0,CL64,0,0)~
';
    'VSS'<425>:'(0,0,0,0,0,0,0,0,0,0,0,0,0,0,0,0,0,0,0,0,0,0,0,0,0,0,0,CL66,0,0)~
';
    'VSS'<424>:'(0,0,0,0,0,0,0,0,0,0,0,0,0,0,0,0,0,0,0,0,0,0,0,0,0,0,0,CL74,0,0)~
';
    'VSS'<423>:'(0,0,0,0,0,0,0,0,0,0,0,0,0,0,0,0,0,0,0,0,0,0,0,0,0,0,0,CL76,0,0)~
';
    'VSS'<422>:'(0,0,0,0,0,0,0,0,0,0,0,0,0,0,0,0,0,0,0,0,0,0,0,0,0,0,0,CL78,0,0)~
';
    'VSS'<421>:'(0,0,0,0,0,0,0,0,0,0,0,0,0,0,0,0,0,0,0,0,0,0,0,0,0,0,0,CL80,0,0)~
';
    'VSS'<420>:'(0,0,0,0,0,0,0,0,0,0,0,0,0,0,0,0,0,0,0,0,0,0,0,0,0,0,0,CM19,0,0)~
';
    'VSS'<419>:'(0,0,0,0,0,0,0,0,0,0,0,0,0,0,0,0,0,0,0,0,0,0,0,0,0,0,0,CM29,0,0)~
';
    'VSS'<418>:'(0,0,0,0,0,0,0,0,0,0,0,0,0,0,0,0,0,0,0,0,0,0,0,0,0,0,0,CM5,0,0)';
    'VSS'<417>:'(0,0,0,0,0,0,0,0,0,0,0,0,0,0,0,0,0,0,0,0,0,0,0,0,0,0,0,CM31,0,0)~
';
    'VSS'<416>:'(0,0,0,0,0,0,0,0,0,0,0,0,0,0,0,0,0,0,0,0,0,0,0,0,0,0,0,CM61,0,0)~
';
    'VSS'<415>:'(0,0,0,0,0,0,0,0,0,0,0,0,0,0,0,0,0,0,0,0,0,0,0,0,0,0,0,CM63,0,0)~
';
    'VSS'<414>:'(0,0,0,0,0,0,0,0,0,0,0,0,0,0,0,0,0,0,0,0,0,0,0,0,0,0,0,CM67,0,0)~
';
    'VSS'<413>:'(0,0,0,0,0,0,0,0,0,0,0,0,0,0,0,0,0,0,0,0,0,0,0,0,0,0,0,CM73,0,0)~
';
    'VSS'<412>:'(0,0,0,0,0,0,0,0,0,0,0,0,0,0,0,0,0,0,0,0,0,0,0,0,0,0,0,CM77,0,0)~
';
    'VSS'<411>:'(0,0,0,0,0,0,0,0,0,0,0,0,0,0,0,0,0,0,0,0,0,0,0,0,0,0,0,CM83,0,0)~
';
    'VSS'<410>:'(0,0,0,0,0,0,0,0,0,0,0,0,0,0,0,0,0,0,0,0,0,0,0,0,0,0,0,CM85,0,0)~
';
    'VSS'<409>:'(0,0,0,0,0,0,0,0,0,0,0,0,0,0,0,0,0,0,0,0,0,0,0,0,0,0,0,CN2,0,0)';
    'VSS'<408>:'(0,0,0,0,0,0,0,0,0,0,0,0,0,0,0,0,0,0,0,0,0,0,0,0,0,0,0,CN12,0,0)~
';
    'VSS'<407>:'(0,0,0,0,0,0,0,0,0,0,0,0,0,0,0,0,0,0,0,0,0,0,0,0,0,0,0,H61,0,0)';
    'VSS'<406>:'(0,0,0,0,0,0,0,0,0,0,0,0,0,0,0,0,0,0,0,0,0,0,0,0,0,0,0,CN26,0,0)~
';
    'VSS'<405>:'(0,0,0,0,0,0,0,0,0,0,0,0,0,0,0,0,0,0,0,0,0,0,0,0,0,0,0,CN32,0,0)~
';
    'VSS'<404>:'(0,0,0,0,0,0,0,0,0,0,0,0,0,0,0,0,0,0,0,0,0,0,0,0,0,0,0,CN60,0,0)~
';
    'VSS'<403>:'(0,0,0,0,0,0,0,0,0,0,0,0,0,0,0,0,0,0,0,0,0,0,0,0,0,0,0,CN62,0,0)~
';
    'VSS'<402>:'(0,0,0,0,0,0,0,0,0,0,0,0,0,0,0,0,0,0,0,0,0,0,0,0,0,0,0,CN68,0,0)~
';
    'VSS'<401>:'(0,0,0,0,0,0,0,0,0,0,0,0,0,0,0,0,0,0,0,0,0,0,0,0,0,0,0,CN78,0,0)~
';
    'VSS'<400>:'(0,0,0,0,0,0,0,0,0,0,0,0,0,0,0,0,0,0,0,0,0,0,0,0,0,0,0,CP1,0,0)';
    'VSS'<399>:'(0,0,0,0,0,0,0,0,0,0,0,0,0,0,0,0,0,0,0,0,0,0,0,0,0,0,0,H59,0,0)';
    'VSS'<398>:'(0,0,0,0,0,0,0,0,0,0,0,0,0,0,0,0,0,0,0,0,0,0,0,0,0,0,0,CP25,0,0)~
';
    'VSS'<397>:'(0,0,0,0,0,0,0,0,0,0,0,0,0,0,0,0,0,0,0,0,0,0,0,0,0,0,0,CP59,0,0)~
';
    'VSS'<396>:'(0,0,0,0,0,0,0,0,0,0,0,0,0,0,0,0,0,0,0,0,0,0,0,0,0,0,0,CP69,0,0)~
';
    'VSS'<395>:'(0,0,0,0,0,0,0,0,0,0,0,0,0,0,0,0,0,0,0,0,0,0,0,0,0,0,0,CP73,0,0)~
';
    'VSS'<394>:'(0,0,0,0,0,0,0,0,0,0,0,0,0,0,0,0,0,0,0,0,0,0,0,0,0,0,0,CP75,0,0)~
';
    'VSS'<393>:'(0,0,0,0,0,0,0,0,0,0,0,0,0,0,0,0,0,0,0,0,0,0,0,0,0,0,0,CP81,0,0)~
';
    'VSS'<392>:'(0,0,0,0,0,0,0,0,0,0,0,0,0,0,0,0,0,0,0,0,0,0,0,0,0,0,0,CP83,0,0)~
';
    'VSS'<391>:'(0,0,0,0,0,0,0,0,0,0,0,0,0,0,0,0,0,0,0,0,0,0,0,0,0,0,0,CR6,0,0)';
    'VSS'<390>:'(0,0,0,0,0,0,0,0,0,0,0,0,0,0,0,0,0,0,0,0,0,0,0,0,0,0,0,CR10,0,0)~
';
    'VSS'<389>:'(0,0,0,0,0,0,0,0,0,0,0,0,0,0,0,0,0,0,0,0,0,0,0,0,0,0,0,CR22,0,0)~
';
    'VSS'<388>:'(0,0,0,0,0,0,0,0,0,0,0,0,0,0,0,0,0,0,0,0,0,0,0,0,0,0,0,CR24,0,0)~
';
    'VSS'<387>:'(0,0,0,0,0,0,0,0,0,0,0,0,0,0,0,0,0,0,0,0,0,0,0,0,0,0,0,CR32,0,0)~
';
    'VSS'<386>:'(0,0,0,0,0,0,0,0,0,0,0,0,0,0,0,0,0,0,0,0,0,0,0,0,0,0,0,CR58,0,0)~
';
    'VSS'<385>:'(0,0,0,0,0,0,0,0,0,0,0,0,0,0,0,0,0,0,0,0,0,0,0,0,0,0,0,CR62,0,0)~
';
    'VSS'<384>:'(0,0,0,0,0,0,0,0,0,0,0,0,0,0,0,0,0,0,0,0,0,0,0,0,0,0,0,CR64,0,0)~
';
    'VSS'<383>:'(0,0,0,0,0,0,0,0,0,0,0,0,0,0,0,0,0,0,0,0,0,0,0,0,0,0,0,CR66,0,0)~
';
    'VSS'<382>:'(0,0,0,0,0,0,0,0,0,0,0,0,0,0,0,0,0,0,0,0,0,0,0,0,0,0,0,CR68,0,0)~
';
    'VSS'<381>:'(0,0,0,0,0,0,0,0,0,0,0,0,0,0,0,0,0,0,0,0,0,0,0,0,0,0,0,CR78,0,0)~
';
    'VSS'<380>:'(0,0,0,0,0,0,0,0,0,0,0,0,0,0,0,0,0,0,0,0,0,0,0,0,0,0,0,CR86,0,0)~
';
    'VSS'<379>:'(0,0,0,0,0,0,0,0,0,0,0,0,0,0,0,0,0,0,0,0,0,0,0,0,0,0,0,H57,0,0)';
    'VSS'<378>:'(0,0,0,0,0,0,0,0,0,0,0,0,0,0,0,0,0,0,0,0,0,0,0,0,0,0,0,CT13,0,0)~
';
    'VSS'<377>:'(0,0,0,0,0,0,0,0,0,0,0,0,0,0,0,0,0,0,0,0,0,0,0,0,0,0,0,CT19,0,0)~
';
    'VSS'<376>:'(0,0,0,0,0,0,0,0,0,0,0,0,0,0,0,0,0,0,0,0,0,0,0,0,0,0,0,CT27,0,0)~
';
    'VSS'<375>:'(0,0,0,0,0,0,0,0,0,0,0,0,0,0,0,0,0,0,0,0,0,0,0,0,0,0,0,CT29,0,0)~
';
    'VSS'<374>:'(0,0,0,0,0,0,0,0,0,0,0,0,0,0,0,0,0,0,0,0,0,0,0,0,0,0,0,CT33,0,0)~
';
    'VSS'<373>:'(0,0,0,0,0,0,0,0,0,0,0,0,0,0,0,0,0,0,0,0,0,0,0,0,0,0,0,CT35,0,0)~
';
    'VSS'<372>:'(0,0,0,0,0,0,0,0,0,0,0,0,0,0,0,0,0,0,0,0,0,0,0,0,0,0,0,CT57,0,0)~
';
    'VSS'<371>:'(0,0,0,0,0,0,0,0,0,0,0,0,0,0,0,0,0,0,0,0,0,0,0,0,0,0,0,CT73,0,0)~
';
    'VSS'<370>:'(0,0,0,0,0,0,0,0,0,0,0,0,0,0,0,0,0,0,0,0,0,0,0,0,0,0,0,CT79,0,0)~
';
    'VSS'<369>:'(0,0,0,0,0,0,0,0,0,0,0,0,0,0,0,0,0,0,0,0,0,0,0,0,0,0,0,CT83,0,0)~
';
    'VSS'<368>:'(0,0,0,0,0,0,0,0,0,0,0,0,0,0,0,0,0,0,0,0,0,0,0,0,0,0,0,CT85,0,0)~
';
    'VSS'<367>:'(0,0,0,0,0,0,0,0,0,0,0,0,0,0,0,0,0,0,0,0,0,0,0,0,0,0,0,CU4,0,0)';
    'VSS'<366>:'(0,0,0,0,0,0,0,0,0,0,0,0,0,0,0,0,0,0,0,0,0,0,0,0,0,0,0,CU22,0,0)~
';
    'VSS'<365>:'(0,0,0,0,0,0,0,0,0,0,0,0,0,0,0,0,0,0,0,0,0,0,0,0,0,0,0,CU28,0,0)~
';
    'VSS'<364>:'(0,0,0,0,0,0,0,0,0,0,0,0,0,0,0,0,0,0,0,0,0,0,0,0,0,0,0,CU30,0,0)~
';
    'VSS'<363>:'(0,0,0,0,0,0,0,0,0,0,0,0,0,0,0,0,0,0,0,0,0,0,0,0,0,0,0,CU34,0,0)~
';
    'VSS'<362>:'(0,0,0,0,0,0,0,0,0,0,0,0,0,0,0,0,0,0,0,0,0,0,0,0,0,0,0,CU36,0,0)~
';
    'VSS'<361>:'(0,0,0,0,0,0,0,0,0,0,0,0,0,0,0,0,0,0,0,0,0,0,0,0,0,0,0,CU56,0,0)~
';
    'VSS'<360>:'(0,0,0,0,0,0,0,0,0,0,0,0,0,0,0,0,0,0,0,0,0,0,0,0,0,0,0,CU62,0,0)~
';
    'VSS'<359>:'(0,0,0,0,0,0,0,0,0,0,0,0,0,0,0,0,0,0,0,0,0,0,0,0,0,0,0,CU68,0,0)~
';
    'VSS'<358>:'(0,0,0,0,0,0,0,0,0,0,0,0,0,0,0,0,0,0,0,0,0,0,0,0,0,0,0,CU76,0,0)~
';
    'VSS'<357>:'(0,0,0,0,0,0,0,0,0,0,0,0,0,0,0,0,0,0,0,0,0,0,0,0,0,0,0,CU78,0,0)~
';
    'VSS'<356>:'(0,0,0,0,0,0,0,0,0,0,0,0,0,0,0,0,0,0,0,0,0,0,0,0,0,0,0,CU80,0,0)~
';
    'VSS'<355>:'(0,0,0,0,0,0,0,0,0,0,0,0,0,0,0,0,0,0,0,0,0,0,0,0,0,0,0,CU82,0,0)~
';
    'VSS'<354>:'(0,0,0,0,0,0,0,0,0,0,0,0,0,0,0,0,0,0,0,0,0,0,0,0,0,0,0,CU86,0,0)~
';
    'VSS'<353>:'(0,0,0,0,0,0,0,0,0,0,0,0,0,0,0,0,0,0,0,0,0,0,0,0,0,0,0,CV1,0,0)';
    'VSS'<352>:'(0,0,0,0,0,0,0,0,0,0,0,0,0,0,0,0,0,0,0,0,0,0,0,0,0,0,0,H55,0,0)';
    'VSS'<351>:'(0,0,0,0,0,0,0,0,0,0,0,0,0,0,0,0,0,0,0,0,0,0,0,0,0,0,0,CV17,0,0)~
';
    'VSS'<350>:'(0,0,0,0,0,0,0,0,0,0,0,0,0,0,0,0,0,0,0,0,0,0,0,0,0,0,0,CV25,0,0)~
';
    'VSS'<349>:'(0,0,0,0,0,0,0,0,0,0,0,0,0,0,0,0,0,0,0,0,0,0,0,0,0,0,0,CV27,0,0)~
';
    'VSS'<348>:'(0,0,0,0,0,0,0,0,0,0,0,0,0,0,0,0,0,0,0,0,0,0,0,0,0,0,0,CV31,0,0)~
';
    'VSS'<347>:'(0,0,0,0,0,0,0,0,0,0,0,0,0,0,0,0,0,0,0,0,0,0,0,0,0,0,0,CV33,0,0)~
';
    'VSS'<346>:'(0,0,0,0,0,0,0,0,0,0,0,0,0,0,0,0,0,0,0,0,0,0,0,0,0,0,0,CV37,0,0)~
';
    'VSS'<345>:'(0,0,0,0,0,0,0,0,0,0,0,0,0,0,0,0,0,0,0,0,0,0,0,0,0,0,0,CV39,0,0)~
';
    'VSS'<344>:'(0,0,0,0,0,0,0,0,0,0,0,0,0,0,0,0,0,0,0,0,0,0,0,0,0,0,0,CV41,0,0)~
';
    'VSS'<343>:'(0,0,0,0,0,0,0,0,0,0,0,0,0,0,0,0,0,0,0,0,0,0,0,0,0,0,0,CV53,0,0)~
';
    'VSS'<342>:'(0,0,0,0,0,0,0,0,0,0,0,0,0,0,0,0,0,0,0,0,0,0,0,0,0,0,0,CV55,0,0)~
';
    'VSS'<341>:'(0,0,0,0,0,0,0,0,0,0,0,0,0,0,0,0,0,0,0,0,0,0,0,0,0,0,0,CV63,0,0)~
';
    'VSS'<340>:'(0,0,0,0,0,0,0,0,0,0,0,0,0,0,0,0,0,0,0,0,0,0,0,0,0,0,0,CV67,0,0)~
';
    'VSS'<339>:'(0,0,0,0,0,0,0,0,0,0,0,0,0,0,0,0,0,0,0,0,0,0,0,0,0,0,0,CV73,0,0)~
';
    'VSS'<338>:'(0,0,0,0,0,0,0,0,0,0,0,0,0,0,0,0,0,0,0,0,0,0,0,0,0,0,0,CV79,0,0)~
';
    'VSS'<337>:'(0,0,0,0,0,0,0,0,0,0,0,0,0,0,0,0,0,0,0,0,0,0,0,0,0,0,0,CV81,0,0)~
';
    'VSS'<336>:'(0,0,0,0,0,0,0,0,0,0,0,0,0,0,0,0,0,0,0,0,0,0,0,0,0,0,0,CV83,0,0)~
';
    'VSS'<335>:'(0,0,0,0,0,0,0,0,0,0,0,0,0,0,0,0,0,0,0,0,0,0,0,0,0,0,0,CW12,0,0)~
';
    'VSS'<334>:'(0,0,0,0,0,0,0,0,0,0,0,0,0,0,0,0,0,0,0,0,0,0,0,0,0,0,0,CW26,0,0)~
';
    'VSS'<333>:'(0,0,0,0,0,0,0,0,0,0,0,0,0,0,0,0,0,0,0,0,0,0,0,0,0,0,0,CW32,0,0)~
';
    'VSS'<332>:'(0,0,0,0,0,0,0,0,0,0,0,0,0,0,0,0,0,0,0,0,0,0,0,0,0,0,0,CW38,0,0)~
';
    'VSS'<331>:'(0,0,0,0,0,0,0,0,0,0,0,0,0,0,0,0,0,0,0,0,0,0,0,0,0,0,0,CW40,0,0)~
';
    'VSS'<330>:'(0,0,0,0,0,0,0,0,0,0,0,0,0,0,0,0,0,0,0,0,0,0,0,0,0,0,0,CW42,0,0)~
';
    'VSS'<329>:'(0,0,0,0,0,0,0,0,0,0,0,0,0,0,0,0,0,0,0,0,0,0,0,0,0,0,0,CW52,0,0)~
';
    'VSS'<328>:'(0,0,0,0,0,0,0,0,0,0,0,0,0,0,0,0,0,0,0,0,0,0,0,0,0,0,0,CW54,0,0)~
';
    'VSS'<327>:'(0,0,0,0,0,0,0,0,0,0,0,0,0,0,0,0,0,0,0,0,0,0,0,0,0,0,0,CW64,0,0)~
';
    'VSS'<326>:'(0,0,0,0,0,0,0,0,0,0,0,0,0,0,0,0,0,0,0,0,0,0,0,0,0,0,0,CW66,0,0)~
';
    'VSS'<325>:'(0,0,0,0,0,0,0,0,0,0,0,0,0,0,0,0,0,0,0,0,0,0,0,0,0,0,0,CW68,0,0)~
';
    'VSS'<324>:'(0,0,0,0,0,0,0,0,0,0,0,0,0,0,0,0,0,0,0,0,0,0,0,0,0,0,0,CW74,0,0)~
';
    'VSS'<323>:'(0,0,0,0,0,0,0,0,0,0,0,0,0,0,0,0,0,0,0,0,0,0,0,0,0,0,0,CW78,0,0)~
';
    'VSS'<322>:'(0,0,0,0,0,0,0,0,0,0,0,0,0,0,0,0,0,0,0,0,0,0,0,0,0,0,0,CW82,0,0)~
';
    'VSS'<321>:'(0,0,0,0,0,0,0,0,0,0,0,0,0,0,0,0,0,0,0,0,0,0,0,0,0,0,0,CY1,0,0)';
    'VSS'<320>:'(0,0,0,0,0,0,0,0,0,0,0,0,0,0,0,0,0,0,0,0,0,0,0,0,0,0,0,CY9,0,0)';
    'VSS'<319>:'(0,0,0,0,0,0,0,0,0,0,0,0,0,0,0,0,0,0,0,0,0,0,0,0,0,0,0,CY13,0,0)~
';
    'VSS'<318>:'(0,0,0,0,0,0,0,0,0,0,0,0,0,0,0,0,0,0,0,0,0,0,0,0,0,0,0,CY15,0,0)~
';
    'VSS'<317>:'(0,0,0,0,0,0,0,0,0,0,0,0,0,0,0,0,0,0,0,0,0,0,0,0,0,0,0,CY21,0,0)~
';
    'VSS'<316>:'(0,0,0,0,0,0,0,0,0,0,0,0,0,0,0,0,0,0,0,0,0,0,0,0,0,0,0,CY41,0,0)~
';
    'VSS'<315>:'(0,0,0,0,0,0,0,0,0,0,0,0,0,0,0,0,0,0,0,0,0,0,0,0,0,0,0,CY45,0,0)~
';
    'VSS'<314>:'(0,0,0,0,0,0,0,0,0,0,0,0,0,0,0,0,0,0,0,0,0,0,0,0,0,0,0,CY51,0,0)~
';
    'VSS'<313>:'(0,0,0,0,0,0,0,0,0,0,0,0,0,0,0,0,0,0,0,0,0,0,0,0,0,0,0,CY59,0,0)~
';
    'VSS'<312>:'(0,0,0,0,0,0,0,0,0,0,0,0,0,0,0,0,0,0,0,0,0,0,0,0,0,0,0,CY61,0,0)~
';
    'VSS'<311>:'(0,0,0,0,0,0,0,0,0,0,0,0,0,0,0,0,0,0,0,0,0,0,0,0,0,0,0,CY65,0,0)~
';
    'VSS'<310>:'(0,0,0,0,0,0,0,0,0,0,0,0,0,0,0,0,0,0,0,0,0,0,0,0,0,0,0,CY69,0,0)~
';
    'VSS'<309>:'(0,0,0,0,0,0,0,0,0,0,0,0,0,0,0,0,0,0,0,0,0,0,0,0,0,0,0,CY75,0,0)~
';
    'VSS'<308>:'(0,0,0,0,0,0,0,0,0,0,0,0,0,0,0,0,0,0,0,0,0,0,0,0,0,0,0,CY77,0,0)~
';
    'VSS'<307>:'(0,0,0,0,0,0,0,0,0,0,0,0,0,0,0,0,0,0,0,0,0,0,0,0,0,0,0,CY83,0,0)~
';
    'VSS'<306>:'(0,0,0,0,0,0,0,0,0,0,0,0,0,0,0,0,0,0,0,0,0,0,0,0,0,0,0,CY85,0,0)~
';
    'VSS'<305>:'(0,0,0,0,0,0,0,0,0,0,0,0,0,0,0,0,0,0,0,0,0,0,0,0,0,0,0,DA6,0,0)';
    'VSS'<304>:'(0,0,0,0,0,0,0,0,0,0,0,0,0,0,0,0,0,0,0,0,0,0,0,0,0,0,0,H53,0,0)';
    'VSS'<303>:'(0,0,0,0,0,0,0,0,0,0,0,0,0,0,0,0,0,0,0,0,0,0,0,0,0,0,0,DA18,0,0)~
';
    'VSS'<302>:'(0,0,0,0,0,0,0,0,0,0,0,0,0,0,0,0,0,0,0,0,0,0,0,0,0,0,0,DA26,0,0)~
';
    'VSS'<301>:'(0,0,0,0,0,0,0,0,0,0,0,0,0,0,0,0,0,0,0,0,0,0,0,0,0,0,0,DA28,0,0)~
';
    'VSS'<300>:'(0,0,0,0,0,0,0,0,0,0,0,0,0,0,0,0,0,0,0,0,0,0,0,0,0,0,0,DA30,0,0)~
';
    'VSS'<299>:'(0,0,0,0,0,0,0,0,0,0,0,0,0,0,0,0,0,0,0,0,0,0,0,0,0,0,0,DA32,0,0)~
';
    'VSS'<298>:'(0,0,0,0,0,0,0,0,0,0,0,0,0,0,0,0,0,0,0,0,0,0,0,0,0,0,0,DA34,0,0)~
';
    'VSS'<297>:'(0,0,0,0,0,0,0,0,0,0,0,0,0,0,0,0,0,0,0,0,0,0,0,0,0,0,0,DA36,0,0)~
';
    'VSS'<296>:'(0,0,0,0,0,0,0,0,0,0,0,0,0,0,0,0,0,0,0,0,0,0,0,0,0,0,0,DA38,0,0)~
';
    'VSS'<295>:'(0,0,0,0,0,0,0,0,0,0,0,0,0,0,0,0,0,0,0,0,0,0,0,0,0,0,0,DA44,0,0)~
';
    'VSS'<294>:'(0,0,0,0,0,0,0,0,0,0,0,0,0,0,0,0,0,0,0,0,0,0,0,0,0,0,0,DA46,0,0)~
';
    'VSS'<293>:'(0,0,0,0,0,0,0,0,0,0,0,0,0,0,0,0,0,0,0,0,0,0,0,0,0,0,0,0,DA48,0)~
';
    'VSS'<292>:'(0,0,0,0,0,0,0,0,0,0,0,0,0,0,0,0,0,0,0,0,0,0,0,0,0,0,0,0,DA50,0)~
';
    'VSS'<291>:'(0,0,0,0,0,0,0,0,0,0,0,0,0,0,0,0,0,0,0,0,0,0,0,0,0,0,0,0,DA64,0)~
';
    'VSS'<290>:'(0,0,0,0,0,0,0,0,0,0,0,0,0,0,0,0,0,0,0,0,0,0,0,0,0,0,0,0,DA70,0)~
';
    'VSS'<289>:'(0,0,0,0,0,0,0,0,0,0,0,0,0,0,0,0,0,0,0,0,0,0,0,0,0,0,0,0,DA74,0)~
';
    'VSS'<288>:'(0,0,0,0,0,0,0,0,0,0,0,0,0,0,0,0,0,0,0,0,0,0,0,0,0,0,0,0,DA76,0)~
';
    'VSS'<287>:'(0,0,0,0,0,0,0,0,0,0,0,0,0,0,0,0,0,0,0,0,0,0,0,0,0,0,0,0,DA78,0)~
';
    'VSS'<286>:'(0,0,0,0,0,0,0,0,0,0,0,0,0,0,0,0,0,0,0,0,0,0,0,0,0,0,0,0,DA80,0)~
';
    'VSS'<285>:'(0,0,0,0,0,0,0,0,0,0,0,0,0,0,0,0,0,0,0,0,0,0,0,0,0,0,0,0,DB3,0)';
    'VSS'<284>:'(0,0,0,0,0,0,0,0,0,0,0,0,0,0,0,0,0,0,0,0,0,0,0,0,0,0,0,0,DB13,0)~
';
    'VSS'<283>:'(0,0,0,0,0,0,0,0,0,0,0,0,0,0,0,0,0,0,0,0,0,0,0,0,0,0,0,0,DB17,0)~
';
    'VSS'<282>:'(0,0,0,0,0,0,0,0,0,0,0,0,0,0,0,0,0,0,0,0,0,0,0,0,0,0,0,0,DB23,0)~
';
    'VSS'<281>:'(0,0,0,0,0,0,0,0,0,0,0,0,0,0,0,0,0,0,0,0,0,0,0,0,0,0,0,0,DB25,0)~
';
    'VSS'<280>:'(0,0,0,0,0,0,0,0,0,0,0,0,0,0,0,0,0,0,0,0,0,0,0,0,0,0,0,0,DB39,0)~
';
    'VSS'<279>:'(0,0,0,0,0,0,0,0,0,0,0,0,0,0,0,0,0,0,0,0,0,0,0,0,0,0,0,0,DB41,0)~
';
    'VSS'<278>:'(0,0,0,0,0,0,0,0,0,0,0,0,0,0,0,0,0,0,0,0,0,0,0,0,0,0,0,0,DB47,0)~
';
    'VSS'<277>:'(0,0,0,0,0,0,0,0,0,0,0,0,0,0,0,0,0,0,0,0,0,0,0,0,0,0,0,0,DB49,0)~
';
    'VSS'<276>:'(0,0,0,0,0,0,0,0,0,0,0,0,0,0,0,0,0,0,0,0,0,0,0,0,0,0,0,0,DB73,0)~
';
    'VSS'<275>:'(0,0,0,0,0,0,0,0,0,0,0,0,0,0,0,0,0,0,0,0,0,0,0,0,0,0,0,0,DB77,0)~
';
    'VSS'<274>:'(0,0,0,0,0,0,0,0,0,0,0,0,0,0,0,0,0,0,0,0,0,0,0,0,0,0,0,0,DB83,0)~
';
    'VSS'<273>:'(0,0,0,0,0,0,0,0,0,0,0,0,0,0,0,0,0,0,0,0,0,0,0,0,0,0,0,0,DB85,0)~
';
    'VSS'<272>:'(0,0,0,0,0,0,0,0,0,0,0,0,0,0,0,0,0,0,0,0,0,0,0,0,0,0,0,0,DC14,0)~
';
    'VSS'<271>:'(0,0,0,0,0,0,0,0,0,0,0,0,0,0,0,0,0,0,0,0,0,0,0,0,0,0,0,0,DC24,0)~
';
    'VSS'<270>:'(0,0,0,0,0,0,0,0,0,0,0,0,0,0,0,0,0,0,0,0,0,0,0,0,0,0,0,0,DC26,0)~
';
    'VSS'<269>:'(0,0,0,0,0,0,0,0,0,0,0,0,0,0,0,0,0,0,0,0,0,0,0,0,0,0,0,0,DC32,0)~
';
    'VSS'<268>:'(0,0,0,0,0,0,0,0,0,0,0,0,0,0,0,0,0,0,0,0,0,0,0,0,0,0,0,0,DC38,0)~
';
    'VSS'<267>:'(0,0,0,0,0,0,0,0,0,0,0,0,0,0,0,0,0,0,0,0,0,0,0,0,0,0,0,0,DC42,0)~
';
    'VSS'<266>:'(0,0,0,0,0,0,0,0,0,0,0,0,0,0,0,0,0,0,0,0,0,0,0,0,0,0,0,0,DC64,0)~
';
    'VSS'<265>:'(0,0,0,0,0,0,0,0,0,0,0,0,0,0,0,0,0,0,0,0,0,0,0,0,0,0,0,0,DC66,0)~
';
    'VSS'<264>:'(0,0,0,0,0,0,0,0,0,0,0,0,0,0,0,0,0,0,0,0,0,0,0,0,0,0,0,0,DC68,0)~
';
    'VSS'<263>:'(0,0,0,0,0,0,0,0,0,0,0,0,0,0,0,0,0,0,0,0,0,0,0,0,0,0,0,0,DC70,0)~
';
    'VSS'<262>:'(0,0,0,0,0,0,0,0,0,0,0,0,0,0,0,0,0,0,0,0,0,0,0,0,0,0,0,0,DC78,0)~
';
    'VSS'<261>:'(0,0,0,0,0,0,0,0,0,0,0,0,0,0,0,0,0,0,0,0,0,0,0,0,0,0,0,0,DC84,0)~
';
    'VSS'<260>:'(0,0,0,0,0,0,0,0,0,0,0,0,0,0,0,0,0,0,0,0,0,0,0,0,0,0,0,0,DC86,0)~
';
    'VSS'<259>:'(0,0,0,0,0,0,0,0,0,0,0,0,0,0,0,0,0,0,0,0,0,0,0,0,0,0,0,0,DD11,0)~
';
    'VSS'<258>:'(0,0,0,0,0,0,0,0,0,0,0,0,0,0,0,0,0,0,0,0,0,0,0,0,0,0,0,0,DD23,0)~
';
    'VSS'<257>:'(0,0,0,0,0,0,0,0,0,0,0,0,0,0,0,0,0,0,0,0,0,0,0,0,0,0,0,0,DD27,0)~
';
    'VSS'<256>:'(0,0,0,0,0,0,0,0,0,0,0,0,0,0,0,0,0,0,0,0,0,0,0,0,0,0,0,0,DD31,0)~
';
    'VSS'<255>:'(0,0,0,0,0,0,0,0,0,0,0,0,0,0,0,0,0,0,0,0,0,0,0,0,0,0,0,0,DD33,0)~
';
    'VSS'<254>:'(0,0,0,0,0,0,0,0,0,0,0,0,0,0,0,0,0,0,0,0,0,0,0,0,0,0,0,0,DD37,0)~
';
    'VSS'<253>:'(0,0,0,0,0,0,0,0,0,0,0,0,0,0,0,0,0,0,0,0,0,0,0,0,0,0,0,0,DD71,0)~
';
    'VSS'<252>:'(0,0,0,0,0,0,0,0,0,0,0,0,0,0,0,0,0,0,0,0,0,0,0,0,0,0,0,0,DD73,0)~
';
    'VSS'<251>:'(0,0,0,0,0,0,0,0,0,0,0,0,0,0,0,0,0,0,0,0,0,0,0,0,0,0,0,0,DD75,0)~
';
    'VSS'<250>:'(0,0,0,0,0,0,0,0,0,0,0,0,0,0,0,0,0,0,0,0,0,0,0,0,0,0,0,0,DD81,0)~
';
    'VSS'<249>:'(0,0,0,0,0,0,0,0,0,0,0,0,0,0,0,0,0,0,0,0,0,0,0,0,0,0,0,0,DD83,0)~
';
    'VSS'<248>:'(0,0,0,0,0,0,0,0,0,0,0,0,0,0,0,0,0,0,0,0,0,0,0,0,0,0,0,0,DE6,0)';
    'VSS'<247>:'(0,0,0,0,0,0,0,0,0,0,0,0,0,0,0,0,0,0,0,0,0,0,0,0,0,0,0,0,DE8,0)';
    'VSS'<246>:'(0,0,0,0,0,0,0,0,0,0,0,0,0,0,0,0,0,0,0,0,0,0,0,0,0,0,0,0,DE18,0)~
';
    'VSS'<245>:'(0,0,0,0,0,0,0,0,0,0,0,0,0,0,0,0,0,0,0,0,0,0,0,0,0,0,0,0,DE20,0)~
';
    'VSS'<244>:'(0,0,0,0,0,0,0,0,0,0,0,0,0,0,0,0,0,0,0,0,0,0,0,0,0,0,0,0,DE24,0)~
';
    'VSS'<243>:'(0,0,0,0,0,0,0,0,0,0,0,0,0,0,0,0,0,0,0,0,0,0,0,0,0,0,0,0,DE28,0)~
';
    'VSS'<242>:'(0,0,0,0,0,0,0,0,0,0,0,0,0,0,0,0,0,0,0,0,0,0,0,0,0,0,0,0,DE30,0)~
';
    'VSS'<241>:'(0,0,0,0,0,0,0,0,0,0,0,0,0,0,0,0,0,0,0,0,0,0,0,0,0,0,0,0,DE34,0)~
';
    'VSS'<240>:'(0,0,0,0,0,0,0,0,0,0,0,0,0,0,0,0,0,0,0,0,0,0,0,0,0,0,0,0,DE36,0)~
';
    'VSS'<239>:'(0,0,0,0,0,0,0,0,0,0,0,0,0,0,0,0,0,0,0,0,0,0,0,0,0,0,0,0,DE64,0)~
';
    'VSS'<238>:'(0,0,0,0,0,0,0,0,0,0,0,0,0,0,0,0,0,0,0,0,0,0,0,0,0,0,0,0,DE70,0)~
';
    'VSS'<237>:'(0,0,0,0,0,0,0,0,0,0,0,0,0,0,0,0,0,0,0,0,0,0,0,0,0,0,0,0,DE72,0)~
';
    'VSS'<236>:'(0,0,0,0,0,0,0,0,0,0,0,0,0,0,0,0,0,0,0,0,0,0,0,0,0,0,0,0,DE78,0)~
';
    'VSS'<235>:'(0,0,0,0,0,0,0,0,0,0,0,0,0,0,0,0,0,0,0,0,0,0,0,0,0,0,0,0,DF5,0)';
    'VSS'<234>:'(0,0,0,0,0,0,0,0,0,0,0,0,0,0,0,0,0,0,0,0,0,0,0,0,0,0,0,0,DF7,0)';
    'VSS'<233>:'(0,0,0,0,0,0,0,0,0,0,0,0,0,0,0,0,0,0,0,0,0,0,0,0,0,0,0,0,H51,0)';
    'VSS'<232>:'(0,0,0,0,0,0,0,0,0,0,0,0,0,0,0,0,0,0,0,0,0,0,0,0,0,0,0,0,DF19,0)~
';
    'VSS'<231>:'(0,0,0,0,0,0,0,0,0,0,0,0,0,0,0,0,0,0,0,0,0,0,0,0,0,0,0,0,DF29,0)~
';
    'VSS'<230>:'(0,0,0,0,0,0,0,0,0,0,0,0,0,0,0,0,0,0,0,0,0,0,0,0,0,0,0,0,DF35,0)~
';
    'VSS'<229>:'(0,0,0,0,0,0,0,0,0,0,0,0,0,0,0,0,0,0,0,0,0,0,0,0,0,0,0,0,DF37,0)~
';
    'VSS'<228>:'(0,0,0,0,0,0,0,0,0,0,0,0,0,0,0,0,0,0,0,0,0,0,0,0,0,0,0,0,DF39,0)~
';
    'VSS'<227>:'(0,0,0,0,0,0,0,0,0,0,0,0,0,0,0,0,0,0,0,0,0,0,0,0,0,0,0,0,DF41,0)~
';
    'VSS'<226>:'(0,0,0,0,0,0,0,0,0,0,0,0,0,0,0,0,0,0,0,0,0,0,0,0,0,0,0,0,DF65,0)~
';
    'VSS'<225>:'(0,0,0,0,0,0,0,0,0,0,0,0,0,0,0,0,0,0,0,0,0,0,0,0,0,0,0,0,DF69,0)~
';
    'VSS'<224>:'(0,0,0,0,0,0,0,0,0,0,0,0,0,0,0,0,0,0,0,0,0,0,0,0,0,0,0,0,DF73,0)~
';
    'VSS'<223>:'(0,0,0,0,0,0,0,0,0,0,0,0,0,0,0,0,0,0,0,0,0,0,0,0,0,0,0,0,DF79,0)~
';
    'VSS'<222>:'(0,0,0,0,0,0,0,0,0,0,0,0,0,0,0,0,0,0,0,0,0,0,0,0,0,0,0,0,DF83,0)~
';
    'VSS'<221>:'(0,0,0,0,0,0,0,0,0,0,0,0,0,0,0,0,0,0,0,0,0,0,0,0,0,0,0,0,DF85,0)~
';
    'VSS'<220>:'(0,0,0,0,0,0,0,0,0,0,0,0,0,0,0,0,0,0,0,0,0,0,0,0,0,0,0,0,DG2,0)';
    'VSS'<219>:'(0,0,0,0,0,0,0,0,0,0,0,0,0,0,0,0,0,0,0,0,0,0,0,0,0,0,0,0,H49,0)';
    'VSS'<218>:'(0,0,0,0,0,0,0,0,0,0,0,0,0,0,0,0,0,0,0,0,0,0,0,0,0,0,0,0,DG14,0)~
';
    'VSS'<217>:'(0,0,0,0,0,0,0,0,0,0,0,0,0,0,0,0,0,0,0,0,0,0,0,0,0,0,0,0,DG16,0)~
';
    'VSS'<216>:'(0,0,0,0,0,0,0,0,0,0,0,0,0,0,0,0,0,0,0,0,0,0,0,0,0,0,0,0,DG24,0)~
';
    'VSS'<215>:'(0,0,0,0,0,0,0,0,0,0,0,0,0,0,0,0,0,0,0,0,0,0,0,0,0,0,0,0,DG66,0)~
';
    'VSS'<214>:'(0,0,0,0,0,0,0,0,0,0,0,0,0,0,0,0,0,0,0,0,0,0,0,0,0,0,0,0,DG68,0)~
';
    'VSS'<213>:'(0,0,0,0,0,0,0,0,0,0,0,0,0,0,0,0,0,0,0,0,0,0,0,0,0,0,0,0,DG76,0)~
';
    'VSS'<212>:'(0,0,0,0,0,0,0,0,0,0,0,0,0,0,0,0,0,0,0,0,0,0,0,0,0,0,0,0,DG78,0)~
';
    'VSS'<211>:'(0,0,0,0,0,0,0,0,0,0,0,0,0,0,0,0,0,0,0,0,0,0,0,0,0,0,0,0,DG80,0)~
';
    'VSS'<210>:'(0,0,0,0,0,0,0,0,0,0,0,0,0,0,0,0,0,0,0,0,0,0,0,0,0,0,0,0,DG82,0)~
';
    'VSS'<209>:'(0,0,0,0,0,0,0,0,0,0,0,0,0,0,0,0,0,0,0,0,0,0,0,0,0,0,0,0,DH13,0)~
';
    'VSS'<208>:'(0,0,0,0,0,0,0,0,0,0,0,0,0,0,0,0,0,0,0,0,0,0,0,0,0,0,0,0,DH15,0)~
';
    'VSS'<207>:'(0,0,0,0,0,0,0,0,0,0,0,0,0,0,0,0,0,0,0,0,0,0,0,0,0,0,0,0,DH23,0)~
';
    'VSS'<206>:'(0,0,0,0,0,0,0,0,0,0,0,0,0,0,0,0,0,0,0,0,0,0,0,0,0,0,0,0,DH25,0)~
';
    'VSS'<205>:'(0,0,0,0,0,0,0,0,0,0,0,0,0,0,0,0,0,0,0,0,0,0,0,0,0,0,0,0,DH27,0)~
';
    'VSS'<204>:'(0,0,0,0,0,0,0,0,0,0,0,0,0,0,0,0,0,0,0,0,0,0,0,0,0,0,0,0,DH29,0)~
';
    'VSS'<203>:'(0,0,0,0,0,0,0,0,0,0,0,0,0,0,0,0,0,0,0,0,0,0,0,0,0,0,0,0,DH31,0)~
';
    'VSS'<202>:'(0,0,0,0,0,0,0,0,0,0,0,0,0,0,0,0,0,0,0,0,0,0,0,0,0,0,0,0,DH33,0)~
';
    'VSS'<201>:'(0,0,0,0,0,0,0,0,0,0,0,0,0,0,0,0,0,0,0,0,0,0,0,0,0,0,0,0,DH35,0)~
';
    'VSS'<200>:'(0,0,0,0,0,0,0,0,0,0,0,0,0,0,0,0,0,0,0,0,0,0,0,0,0,0,0,0,DH37,0)~
';
    'VSS'<199>:'(0,0,0,0,0,0,0,0,0,0,0,0,0,0,0,0,0,0,0,0,0,0,0,0,0,0,0,0,DH41,0)~
';
    'VSS'<198>:'(0,0,0,0,0,0,0,0,0,0,0,0,0,0,0,0,0,0,0,0,0,0,0,0,0,0,0,0,DH67,0)~
';
    'VSS'<197>:'(0,0,0,0,0,0,0,0,0,0,0,0,0,0,0,0,0,0,0,0,0,0,0,0,0,0,0,0,DH71,0)~
';
    'VSS'<196>:'(0,0,0,0,0,0,0,0,0,0,0,0,0,0,0,0,0,0,0,0,0,0,0,0,0,0,0,0,DH73,0)~
';
    'VSS'<195>:'(0,0,0,0,0,0,0,0,0,0,0,0,0,0,0,0,0,0,0,0,0,0,0,0,0,0,0,0,DH79,0)~
';
    'VSS'<194>:'(0,0,0,0,0,0,0,0,0,0,0,0,0,0,0,0,0,0,0,0,0,0,0,0,0,0,0,0,DH81,0)~
';
    'VSS'<193>:'(0,0,0,0,0,0,0,0,0,0,0,0,0,0,0,0,0,0,0,0,0,0,0,0,0,0,0,0,DH83,0)~
';
    'VSS'<192>:'(0,0,0,0,0,0,0,0,0,0,0,0,0,0,0,0,0,0,0,0,0,0,0,0,0,0,0,0,DJ2,0)';
    'VSS'<191>:'(0,0,0,0,0,0,0,0,0,0,0,0,0,0,0,0,0,0,0,0,0,0,0,0,0,0,0,0,DJ10,0)~
';
    'VSS'<190>:'(0,0,0,0,0,0,0,0,0,0,0,0,0,0,0,0,0,0,0,0,0,0,0,0,0,0,0,0,H47,0)';
    'VSS'<189>:'(0,0,0,0,0,0,0,0,0,0,0,0,0,0,0,0,0,0,0,0,0,0,0,0,0,0,0,0,DJ22,0)~
';
    'VSS'<188>:'(0,0,0,0,0,0,0,0,0,0,0,0,0,0,0,0,0,0,0,0,0,0,0,0,0,0,0,0,DJ38,0)~
';
    'VSS'<187>:'(0,0,0,0,0,0,0,0,0,0,0,0,0,0,0,0,0,0,0,0,0,0,0,0,0,0,0,0,DJ42,0)~
';
    'VSS'<186>:'(0,0,0,0,0,0,0,0,0,0,0,0,0,0,0,0,0,0,0,0,0,0,0,0,0,0,0,0,DJ68,0)~
';
    'VSS'<185>:'(0,0,0,0,0,0,0,0,0,0,0,0,0,0,0,0,0,0,0,0,0,0,0,0,0,0,0,0,DJ74,0)~
';
    'VSS'<184>:'(0,0,0,0,0,0,0,0,0,0,0,0,0,0,0,0,0,0,0,0,0,0,0,0,0,0,0,0,DJ78,0)~
';
    'VSS'<183>:'(0,0,0,0,0,0,0,0,0,0,0,0,0,0,0,0,0,0,0,0,0,0,0,0,0,0,0,0,DJ82,0)~
';
    'VSS'<182>:'(0,0,0,0,0,0,0,0,0,0,0,0,0,0,0,0,0,0,0,0,0,0,0,0,0,0,0,0,DJ84,0)~
';
    'VSS'<181>:'(0,0,0,0,0,0,0,0,0,0,0,0,0,0,0,0,0,0,0,0,0,0,0,0,0,0,0,0,DK7,0)';
    'VSS'<180>:'(0,0,0,0,0,0,0,0,0,0,0,0,0,0,0,0,0,0,0,0,0,0,0,0,0,0,0,0,DK23,0)~
';
    'VSS'<179>:'(0,0,0,0,0,0,0,0,0,0,0,0,0,0,0,0,0,0,0,0,0,0,0,0,0,0,0,0,DK29,0)~
';
    'VSS'<178>:'(0,0,0,0,0,0,0,0,0,0,0,0,0,0,0,0,0,0,0,0,0,0,0,0,0,0,0,0,DK35,0)~
';
    'VSS'<177>:'(0,0,0,0,0,0,0,0,0,0,0,0,0,0,0,0,0,0,0,0,0,0,0,0,0,0,0,0,DK39,0)~
';
    'VSS'<176>:'(0,0,0,0,0,0,0,0,0,0,0,0,0,0,0,0,0,0,0,0,0,0,0,0,0,0,0,0,DK41,0)~
';
    'VSS'<175>:'(0,0,0,0,0,0,0,0,0,0,0,0,0,0,0,0,0,0,0,0,0,0,0,0,0,0,0,0,DK73,0)~
';
    'VSS'<174>:'(0,0,0,0,0,0,0,0,0,0,0,0,0,0,0,0,0,0,0,0,0,0,0,0,0,0,0,0,DK75,0)~
';
    'VSS'<173>:'(0,0,0,0,0,0,0,0,0,0,0,0,0,0,0,0,0,0,0,0,0,0,0,0,0,0,0,0,DK77,0)~
';
    'VSS'<172>:'(0,0,0,0,0,0,0,0,0,0,0,0,0,0,0,0,0,0,0,0,0,0,0,0,0,0,0,0,DK83,0)~
';
    'VSS'<171>:'(0,0,0,0,0,0,0,0,0,0,0,0,0,0,0,0,0,0,0,0,0,0,0,0,0,0,0,0,DK85,0)~
';
    'VSS'<170>:'(0,0,0,0,0,0,0,0,0,0,0,0,0,0,0,0,0,0,0,0,0,0,0,0,0,0,0,0,DL16,0)~
';
    'VSS'<169>:'(0,0,0,0,0,0,0,0,0,0,0,0,0,0,0,0,0,0,0,0,0,0,0,0,0,0,0,0,DL18,0)~
';
    'VSS'<168>:'(0,0,0,0,0,0,0,0,0,0,0,0,0,0,0,0,0,0,0,0,0,0,0,0,0,0,0,0,DL4,0)';
    'VSS'<167>:'(0,0,0,0,0,0,0,0,0,0,0,0,0,0,0,0,0,0,0,0,0,0,0,0,0,0,0,0,DL22,0)~
';
    'VSS'<166>:'(0,0,0,0,0,0,0,0,0,0,0,0,0,0,0,0,0,0,0,0,0,0,0,0,0,0,0,0,DL24,0)~
';
    'VSS'<165>:'(0,0,0,0,0,0,0,0,0,0,0,0,0,0,0,0,0,0,0,0,0,0,0,0,0,0,0,0,DL28,0)~
';
    'VSS'<164>:'(0,0,0,0,0,0,0,0,0,0,0,0,0,0,0,0,0,0,0,0,0,0,0,0,0,0,0,0,DL30,0)~
';
    'VSS'<163>:'(0,0,0,0,0,0,0,0,0,0,0,0,0,0,0,0,0,0,0,0,0,0,0,0,0,0,0,0,DL34,0)~
';
    'VSS'<162>:'(0,0,0,0,0,0,0,0,0,0,0,0,0,0,0,0,0,0,0,0,0,0,0,0,0,0,0,0,DL36,0)~
';
    'VSS'<161>:'(0,0,0,0,0,0,0,0,0,0,0,0,0,0,0,0,0,0,0,0,0,0,0,0,0,0,0,0,DL40,0)~
';
    'VSS'<160>:'(0,0,0,0,0,0,0,0,0,0,0,0,0,0,0,0,0,0,0,0,0,0,0,0,0,0,0,0,DL68,0)~
';
    'VSS'<159>:'(0,0,0,0,0,0,0,0,0,0,0,0,0,0,0,0,0,0,0,0,0,0,0,0,0,0,0,0,DL70,0)~
';
    'VSS'<158>:'(0,0,0,0,0,0,0,0,0,0,0,0,0,0,0,0,0,0,0,0,0,0,0,0,0,0,0,0,DL74,0)~
';
    'VSS'<157>:'(0,0,0,0,0,0,0,0,0,0,0,0,0,0,0,0,0,0,0,0,0,0,0,0,0,0,0,0,DL76,0)~
';
    'VSS'<156>:'(0,0,0,0,0,0,0,0,0,0,0,0,0,0,0,0,0,0,0,0,0,0,0,0,0,0,0,0,DL78,0)~
';
    'VSS'<155>:'(0,0,0,0,0,0,0,0,0,0,0,0,0,0,0,0,0,0,0,0,0,0,0,0,0,0,0,0,DL80,0)~
';
    'VSS'<154>:'(0,0,0,0,0,0,0,0,0,0,0,0,0,0,0,0,0,0,0,0,0,0,0,0,0,0,0,0,DM15,0)~
';
    'VSS'<153>:'(0,0,0,0,0,0,0,0,0,0,0,0,0,0,0,0,0,0,0,0,0,0,0,0,0,0,0,0,H45,0)';
    'VSS'<152>:'(0,0,0,0,0,0,0,0,0,0,0,0,0,0,0,0,0,0,0,0,0,0,0,0,0,0,0,0,DM25,0)~
';
    'VSS'<151>:'(0,0,0,0,0,0,0,0,0,0,0,0,0,0,0,0,0,0,0,0,0,0,0,0,0,0,0,0,DM27,0)~
';
    'VSS'<150>:'(0,0,0,0,0,0,0,0,0,0,0,0,0,0,0,0,0,0,0,0,0,0,0,0,0,0,0,0,DM31,0)~
';
    'VSS'<149>:'(0,0,0,0,0,0,0,0,0,0,0,0,0,0,0,0,0,0,0,0,0,0,0,0,0,0,0,0,DM33,0)~
';
    'VSS'<148>:'(0,0,0,0,0,0,0,0,0,0,0,0,0,0,0,0,0,0,0,0,0,0,0,0,0,0,0,0,DM37,0)~
';
    'VSS'<147>:'(0,0,0,0,0,0,0,0,0,0,0,0,0,0,0,0,0,0,0,0,0,0,0,0,0,0,0,0,DM39,0)~
';
    'VSS'<146>:'(0,0,0,0,0,0,0,0,0,0,0,0,0,0,0,0,0,0,0,0,0,0,0,0,0,0,0,0,DM65,0)~
';
    'VSS'<145>:'(0,0,0,0,0,0,0,0,0,0,0,0,0,0,0,0,0,0,0,0,0,0,0,0,0,0,0,0,DM73,0)~
';
    'VSS'<144>:'(0,0,0,0,0,0,0,0,0,0,0,0,0,0,0,0,0,0,0,0,0,0,0,0,0,0,0,0,DM77,0)~
';
    'VSS'<143>:'(0,0,0,0,0,0,0,0,0,0,0,0,0,0,0,0,0,0,0,0,0,0,0,0,0,0,0,0,DM83,0)~
';
    'VSS'<142>:'(0,0,0,0,0,0,0,0,0,0,0,0,0,0,0,0,0,0,0,0,0,0,0,0,0,0,0,0,DN2,0)';
    'VSS'<141>:'(0,0,0,0,0,0,0,0,0,0,0,0,0,0,0,0,0,0,0,0,0,0,0,0,0,0,0,0,BH17,0)~
';
    'VSS'<140>:'(0,0,0,0,0,0,0,0,0,0,0,0,0,0,0,0,0,0,0,0,0,0,0,0,0,0,0,0,DN12,0)~
';
    'VSS'<139>:'(0,0,0,0,0,0,0,0,0,0,0,0,0,0,0,0,0,0,0,0,0,0,0,0,0,0,0,0,DN22,0)~
';
    'VSS'<138>:'(0,0,0,0,0,0,0,0,0,0,0,0,0,0,0,0,0,0,0,0,0,0,0,0,0,0,0,0,DN26,0)~
';
    'VSS'<137>:'(0,0,0,0,0,0,0,0,0,0,0,0,0,0,0,0,0,0,0,0,0,0,0,0,0,0,0,0,DN32,0)~
';
    'VSS'<136>:'(0,0,0,0,0,0,0,0,0,0,0,0,0,0,0,0,0,0,0,0,0,0,0,0,0,0,0,0,DN38,0)~
';
    'VSS'<135>:'(0,0,0,0,0,0,0,0,0,0,0,0,0,0,0,0,0,0,0,0,0,0,0,0,0,0,0,0,DN68,0)~
';
    'VSS'<134>:'(0,0,0,0,0,0,0,0,0,0,0,0,0,0,0,0,0,0,0,0,0,0,0,0,0,0,0,0,DN72,0)~
';
    'VSS'<133>:'(0,0,0,0,0,0,0,0,0,0,0,0,0,0,0,0,0,0,0,0,0,0,0,0,0,0,0,0,0,DN78)~
';
    'VSS'<132>:'(0,0,0,0,0,0,0,0,0,0,0,0,0,0,0,0,0,0,0,0,0,0,0,0,0,0,0,0,0,DP67)~
';
    'VSS'<131>:'(0,0,0,0,0,0,0,0,0,0,0,0,0,0,0,0,0,0,0,0,0,0,0,0,0,0,0,0,0,DP69)~
';
    'VSS'<130>:'(0,0,0,0,0,0,0,0,0,0,0,0,0,0,0,0,0,0,0,0,0,0,0,0,0,0,0,0,0,DP71)~
';
    'VSS'<129>:'(0,0,0,0,0,0,0,0,0,0,0,0,0,0,0,0,0,0,0,0,0,0,0,0,0,0,0,0,0,DP81)~
';
    'VSS'<128>:'(0,0,0,0,0,0,0,0,0,0,0,0,0,0,0,0,0,0,0,0,0,0,0,0,0,0,0,0,0,DP83)~
';
    'VSS'<127>:'(0,0,0,0,0,0,0,0,0,0,0,0,0,0,0,0,0,0,0,0,0,0,0,0,0,0,0,0,0,BR26)~
';
    'VSS'<126>:'(0,0,0,0,0,0,0,0,0,0,0,0,0,0,0,0,0,0,0,0,0,0,0,0,0,0,0,0,0,DR6)';
    'VSS'<125>:'(0,0,0,0,0,0,0,0,0,0,0,0,0,0,0,0,0,0,0,0,0,0,0,0,0,0,0,0,0,CA20)~
';
    'VSS'<124>:'(0,0,0,0,0,0,0,0,0,0,0,0,0,0,0,0,0,0,0,0,0,0,0,0,0,0,0,0,0,CL22)~
';
    'VSS'<123>:'(0,0,0,0,0,0,0,0,0,0,0,0,0,0,0,0,0,0,0,0,0,0,0,0,0,0,0,0,0,DR20)~
';
    'VSS'<122>:'(0,0,0,0,0,0,0,0,0,0,0,0,0,0,0,0,0,0,0,0,0,0,0,0,0,0,0,0,0,DR22)~
';
    'VSS'<121>:'(0,0,0,0,0,0,0,0,0,0,0,0,0,0,0,0,0,0,0,0,0,0,0,0,0,0,0,0,0,DR24)~
';
    'VSS'<120>:'(0,0,0,0,0,0,0,0,0,0,0,0,0,0,0,0,0,0,0,0,0,0,0,0,0,0,0,0,0,DR26)~
';
    'VSS'<119>:'(0,0,0,0,0,0,0,0,0,0,0,0,0,0,0,0,0,0,0,0,0,0,0,0,0,0,0,0,0,DR28)~
';
    'VSS'<118>:'(0,0,0,0,0,0,0,0,0,0,0,0,0,0,0,0,0,0,0,0,0,0,0,0,0,0,0,0,0,DR30)~
';
    'VSS'<117>:'(0,0,0,0,0,0,0,0,0,0,0,0,0,0,0,0,0,0,0,0,0,0,0,0,0,0,0,0,0,DR32)~
';
    'VSS'<116>:'(0,0,0,0,0,0,0,0,0,0,0,0,0,0,0,0,0,0,0,0,0,0,0,0,0,0,0,0,0,DR34)~
';
    'VSS'<115>:'(0,0,0,0,0,0,0,0,0,0,0,0,0,0,0,0,0,0,0,0,0,0,0,0,0,0,0,0,0,DR36)~
';
    'VSS'<114>:'(0,0,0,0,0,0,0,0,0,0,0,0,0,0,0,0,0,0,0,0,0,0,0,0,0,0,0,0,0,DR38)~
';
    'VSS'<113>:'(0,0,0,0,0,0,0,0,0,0,0,0,0,0,0,0,0,0,0,0,0,0,0,0,0,0,0,0,0,DR40)~
';
    'VSS'<112>:'(0,0,0,0,0,0,0,0,0,0,0,0,0,0,0,0,0,0,0,0,0,0,0,0,0,0,0,0,0,DR42)~
';
    'VSS'<111>:'(0,0,0,0,0,0,0,0,0,0,0,0,0,0,0,0,0,0,0,0,0,0,0,0,0,0,0,0,0,DR66)~
';
    'VSS'<110>:'(0,0,0,0,0,0,0,0,0,0,0,0,0,0,0,0,0,0,0,0,0,0,0,0,0,0,0,0,0,DR68)~
';
    'VSS'<109>:'(0,0,0,0,0,0,0,0,0,0,0,0,0,0,0,0,0,0,0,0,0,0,0,0,0,0,0,0,0,DR70)~
';
    'VSS'<108>:'(0,0,0,0,0,0,0,0,0,0,0,0,0,0,0,0,0,0,0,0,0,0,0,0,0,0,0,0,0,DR72)~
';
    'VSS'<107>:'(0,0,0,0,0,0,0,0,0,0,0,0,0,0,0,0,0,0,0,0,0,0,0,0,0,0,0,0,0,DR74)~
';
    'VSS'<106>:'(0,0,0,0,0,0,0,0,0,0,0,0,0,0,0,0,0,0,0,0,0,0,0,0,0,0,0,0,0,DR76)~
';
    'VSS'<105>:'(0,0,0,0,0,0,0,0,0,0,0,0,0,0,0,0,0,0,0,0,0,0,0,0,0,0,0,0,0,DR78)~
';
    'VSS'<104>:'(0,0,0,0,0,0,0,0,0,0,0,0,0,0,0,0,0,0,0,0,0,0,0,0,0,0,0,0,0,DT3)';
    'VSS'<103>:'(0,0,0,0,0,0,0,0,0,0,0,0,0,0,0,0,0,0,0,0,0,0,0,0,0,0,0,0,0,DT17)~
';
    'VSS'<102>:'(0,0,0,0,0,0,0,0,0,0,0,0,0,0,0,0,0,0,0,0,0,0,0,0,0,0,0,0,0,DH21)~
';
    'VSS'<101>:'(0,0,0,0,0,0,0,0,0,0,0,0,0,0,0,0,0,0,0,0,0,0,0,0,0,0,0,0,0,DT65)~
';
    'VSS'<100>:'(0,0,0,0,0,0,0,0,0,0,0,0,0,0,0,0,0,0,0,0,0,0,0,0,0,0,0,0,0,DT69)~
';
    'VSS'<99>:'(0,0,0,0,0,0,0,0,0,0,0,0,0,0,0,0,0,0,0,0,0,0,0,0,0,0,0,0,0,DT79)';
    'VSS'<98>:'(0,0,0,0,0,0,0,0,0,0,0,0,0,0,0,0,0,0,0,0,0,0,0,0,0,0,0,0,0,DT83)';
    'VSS'<97>:'(0,0,0,0,0,0,0,0,0,0,0,0,0,0,0,0,0,0,0,0,0,0,0,0,0,0,0,0,0,DT85)';
    'VSS'<96>:'(0,0,0,0,0,0,0,0,0,0,0,0,0,0,0,0,0,0,0,0,0,0,0,0,0,0,0,0,0,DU10)';
    'VSS'<95>:'(0,0,0,0,0,0,0,0,0,0,0,0,0,0,0,0,0,0,0,0,0,0,0,0,0,0,0,0,0,DU14)';
    'VSS'<94>:'(0,0,0,0,0,0,0,0,0,0,0,0,0,0,0,0,0,0,0,0,0,0,0,0,0,0,0,0,0,CN14)';
    'VSS'<93>:'(0,0,0,0,0,0,0,0,0,0,0,0,0,0,0,0,0,0,0,0,0,0,0,0,0,0,0,0,0,DU22)';
    'VSS'<92>:'(0,0,0,0,0,0,0,0,0,0,0,0,0,0,0,0,0,0,0,0,0,0,0,0,0,0,0,0,0,DU26)';
    'VSS'<91>:'(0,0,0,0,0,0,0,0,0,0,0,0,0,0,0,0,0,0,0,0,0,0,0,0,0,0,0,0,0,DU32)';
    'VSS'<90>:'(0,0,0,0,0,0,0,0,0,0,0,0,0,0,0,0,0,0,0,0,0,0,0,0,0,0,0,0,0,DU38)';
    'VSS'<89>:'(0,0,0,0,0,0,0,0,0,0,0,0,0,0,0,0,0,0,0,0,0,0,0,0,0,0,0,0,0,DU70)';
    'VSS'<88>:'(0,0,0,0,0,0,0,0,0,0,0,0,0,0,0,0,0,0,0,0,0,0,0,0,0,0,0,0,0,DU72)';
    'VSS'<87>:'(0,0,0,0,0,0,0,0,0,0,0,0,0,0,0,0,0,0,0,0,0,0,0,0,0,0,0,0,0,DU78)';
    'VSS'<86>:'(0,0,0,0,0,0,0,0,0,0,0,0,0,0,0,0,0,0,0,0,0,0,0,0,0,0,0,0,0,DU80)';
    'VSS'<85>:'(0,0,0,0,0,0,0,0,0,0,0,0,0,0,0,0,0,0,0,0,0,0,0,0,0,0,0,0,0,DU82)';
    'VSS'<84>:'(0,0,0,0,0,0,0,0,0,0,0,0,0,0,0,0,0,0,0,0,0,0,0,0,0,0,0,0,0,DU84)';
    'VSS'<83>:'(0,0,0,0,0,0,0,0,0,0,0,0,0,0,0,0,0,0,0,0,0,0,0,0,0,0,0,0,0,DV21)';
    'VSS'<82>:'(0,0,0,0,0,0,0,0,0,0,0,0,0,0,0,0,0,0,0,0,0,0,0,0,0,0,0,0,0,DV25)';
    'VSS'<81>:'(0,0,0,0,0,0,0,0,0,0,0,0,0,0,0,0,0,0,0,0,0,0,0,0,0,0,0,0,0,DV27)';
    'VSS'<80>:'(0,0,0,0,0,0,0,0,0,0,0,0,0,0,0,0,0,0,0,0,0,0,0,0,0,0,0,0,0,DV31)';
    'VSS'<79>:'(0,0,0,0,0,0,0,0,0,0,0,0,0,0,0,0,0,0,0,0,0,0,0,0,0,0,0,0,0,DV33)';
    'VSS'<78>:'(0,0,0,0,0,0,0,0,0,0,0,0,0,0,0,0,0,0,0,0,0,0,0,0,0,0,0,0,0,DV37)';
    'VSS'<77>:'(0,0,0,0,0,0,0,0,0,0,0,0,0,0,0,0,0,0,0,0,0,0,0,0,0,0,0,0,0,DV39)';
    'VSS'<76>:'(0,0,0,0,0,0,0,0,0,0,0,0,0,0,0,0,0,0,0,0,0,0,0,0,0,0,0,0,0,DV73)';
    'VSS'<75>:'(0,0,0,0,0,0,0,0,0,0,0,0,0,0,0,0,0,0,0,0,0,0,0,0,0,0,0,0,0,DV77)';
    'VSS'<74>:'(0,0,0,0,0,0,0,0,0,0,0,0,0,0,0,0,0,0,0,0,0,0,0,0,0,0,0,0,0,DV81)';
    'VSS'<73>:'(0,0,0,0,0,0,0,0,0,0,0,0,0,0,0,0,0,0,0,0,0,0,0,0,0,0,0,0,0,DW12)';
    'VSS'<72>:'(0,0,0,0,0,0,0,0,0,0,0,0,0,0,0,0,0,0,0,0,0,0,0,0,0,0,0,0,0,DW20)';
    'VSS'<71>:'(0,0,0,0,0,0,0,0,0,0,0,0,0,0,0,0,0,0,0,0,0,0,0,0,0,0,0,0,0,DW24)';
    'VSS'<70>:'(0,0,0,0,0,0,0,0,0,0,0,0,0,0,0,0,0,0,0,0,0,0,0,0,0,0,0,0,0,DW28)';
    'VSS'<69>:'(0,0,0,0,0,0,0,0,0,0,0,0,0,0,0,0,0,0,0,0,0,0,0,0,0,0,0,0,0,DW30)';
    'VSS'<68>:'(0,0,0,0,0,0,0,0,0,0,0,0,0,0,0,0,0,0,0,0,0,0,0,0,0,0,0,0,0,DW34)';
    'VSS'<67>:'(0,0,0,0,0,0,0,0,0,0,0,0,0,0,0,0,0,0,0,0,0,0,0,0,0,0,0,0,0,DW36)';
    'VSS'<66>:'(0,0,0,0,0,0,0,0,0,0,0,0,0,0,0,0,0,0,0,0,0,0,0,0,0,0,0,0,0,DW40)';
    'VSS'<65>:'(0,0,0,0,0,0,0,0,0,0,0,0,0,0,0,0,0,0,0,0,0,0,0,0,0,0,0,0,0,DW64)';
    'VSS'<64>:'(0,0,0,0,0,0,0,0,0,0,0,0,0,0,0,0,0,0,0,0,0,0,0,0,0,0,0,0,0,DW66)';
    'VSS'<63>:'(0,0,0,0,0,0,0,0,0,0,0,0,0,0,0,0,0,0,0,0,0,0,0,0,0,0,0,0,0,DW68)';
    'VSS'<62>:'(0,0,0,0,0,0,0,0,0,0,0,0,0,0,0,0,0,0,0,0,0,0,0,0,0,0,0,0,0,DW70)';
    'VSS'<61>:'(0,0,0,0,0,0,0,0,0,0,0,0,0,0,0,0,0,0,0,0,0,0,0,0,0,0,0,0,0,DW72)';
    'VSS'<60>:'(0,0,0,0,0,0,0,0,0,0,0,0,0,0,0,0,0,0,0,0,0,0,0,0,0,0,0,0,0,DW74)';
    'VSS'<59>:'(0,0,0,0,0,0,0,0,0,0,0,0,0,0,0,0,0,0,0,0,0,0,0,0,0,0,0,0,0,DW76)';
    'VSS'<58>:'(0,0,0,0,0,0,0,0,0,0,0,0,0,0,0,0,0,0,0,0,0,0,0,0,0,0,0,0,0,DW8)';~

    'VSS'<57>:'(0,0,0,0,0,0,0,0,0,0,0,0,0,0,0,0,0,0,0,0,0,0,0,0,0,0,0,0,0,DW82)';
    'VSS'<56>:'(0,0,0,0,0,0,0,0,0,0,0,0,0,0,0,0,0,0,0,0,0,0,0,0,0,0,0,0,0,DW84)';
    'VSS'<55>:'(0,0,0,0,0,0,0,0,0,0,0,0,0,0,0,0,0,0,0,0,0,0,0,0,0,0,0,0,0,DY5)';~

    'VSS'<54>:'(0,0,0,0,0,0,0,0,0,0,0,0,0,0,0,0,0,0,0,0,0,0,0,0,0,0,0,0,0,DY19)';
    'VSS'<53>:'(0,0,0,0,0,0,0,0,0,0,0,0,0,0,0,0,0,0,0,0,0,0,0,0,0,0,0,0,0,DY23)';
    'VSS'<52>:'(0,0,0,0,0,0,0,0,0,0,0,0,0,0,0,0,0,0,0,0,0,0,0,0,0,0,0,0,0,DY29)';
    'VSS'<51>:'(0,0,0,0,0,0,0,0,0,0,0,0,0,0,0,0,0,0,0,0,0,0,0,0,0,0,0,0,0,DY35)';
    'VSS'<50>:'(0,0,0,0,0,0,0,0,0,0,0,0,0,0,0,0,0,0,0,0,0,0,0,0,0,0,0,0,0,DY41)';
    'VSS'<49>:'(0,0,0,0,0,0,0,0,0,0,0,0,0,0,0,0,0,0,0,0,0,0,0,0,0,0,0,0,0,DY71)';
    'VSS'<48>:'(0,0,0,0,0,0,0,0,0,0,0,0,0,0,0,0,0,0,0,0,0,0,0,0,0,0,0,0,0,DY75)';
    'VSS'<47>:'(0,0,0,0,0,0,0,0,0,0,0,0,0,0,0,0,0,0,0,0,0,0,0,0,0,0,0,0,0,EA6)';~

    'VSS'<46>:'(0,0,0,0,0,0,0,0,0,0,0,0,0,0,0,0,0,0,0,0,0,0,0,0,0,0,0,0,0,J16)';~

    'VSS'<45>:'(0,0,0,0,0,0,0,0,0,0,0,0,0,0,0,0,0,0,0,0,0,0,0,0,0,0,0,0,0,EA16)';
    'VSS'<44>:'(0,0,0,0,0,0,0,0,0,0,0,0,0,0,0,0,0,0,0,0,0,0,0,0,0,0,0,0,0,EA20)';
    'VSS'<43>:'(0,0,0,0,0,0,0,0,0,0,0,0,0,0,0,0,0,0,0,0,0,0,0,0,0,0,0,0,0,EA22)';
    'VSS'<42>:'(0,0,0,0,0,0,0,0,0,0,0,0,0,0,0,0,0,0,0,0,0,0,0,0,0,0,0,0,0,EA42)';
    'VSS'<41>:'(0,0,0,0,0,0,0,0,0,0,0,0,0,0,0,0,0,0,0,0,0,0,0,0,0,0,0,0,0,EA64)';
    'VSS'<40>:'(0,0,0,0,0,0,0,0,0,0,0,0,0,0,0,0,0,0,0,0,0,0,0,0,0,0,0,0,0,EA70)';
    'VSS'<39>:'(0,0,0,0,0,0,0,0,0,0,0,0,0,0,0,0,0,0,0,0,0,0,0,0,0,0,0,0,0,EA76)';
    'VSS'<38>:'(0,0,0,0,0,0,0,0,0,0,0,0,0,0,0,0,0,0,0,0,0,0,0,0,0,0,0,0,0,EA78)';
    'VSS'<37>:'(0,0,0,0,0,0,0,0,0,0,0,0,0,0,0,0,0,0,0,0,0,0,0,0,0,0,0,0,0,EA80)';
    'VSS'<36>:'(0,0,0,0,0,0,0,0,0,0,0,0,0,0,0,0,0,0,0,0,0,0,0,0,0,0,0,0,0,EA82)';
    'VSS'<35>:'(0,0,0,0,0,0,0,0,0,0,0,0,0,0,0,0,0,0,0,0,0,0,0,0,0,0,0,0,0,EB13)';
    'VSS'<34>:'(0,0,0,0,0,0,0,0,0,0,0,0,0,0,0,0,0,0,0,0,0,0,0,0,0,0,0,0,0,BR18)';
    'VSS'<33>:'(0,0,0,0,0,0,0,0,0,0,0,0,0,0,0,0,0,0,0,0,0,0,0,0,0,0,0,0,0,EB23)';
    'VSS'<32>:'(0,0,0,0,0,0,0,0,0,0,0,0,0,0,0,0,0,0,0,0,0,0,0,0,0,0,0,0,0,EB25)';
    'VSS'<31>:'(0,0,0,0,0,0,0,0,0,0,0,0,0,0,0,0,0,0,0,0,0,0,0,0,0,0,0,0,0,EB27)';
    'VSS'<30>:'(0,0,0,0,0,0,0,0,0,0,0,0,0,0,0,0,0,0,0,0,0,0,0,0,0,0,0,0,0,EB29)';
    'VSS'<29>:'(0,0,0,0,0,0,0,0,0,0,0,0,0,0,0,0,0,0,0,0,0,0,0,0,0,0,0,0,0,EB31)';
    'VSS'<28>:'(0,0,0,0,0,0,0,0,0,0,0,0,0,0,0,0,0,0,0,0,0,0,0,0,0,0,0,0,0,EB33)';
    'VSS'<27>:'(0,0,0,0,0,0,0,0,0,0,0,0,0,0,0,0,0,0,0,0,0,0,0,0,0,0,0,0,0,EB35)';
    'VSS'<26>:'(0,0,0,0,0,0,0,0,0,0,0,0,0,0,0,0,0,0,0,0,0,0,0,0,0,0,0,0,0,EB37)';
    'VSS'<25>:'(0,0,0,0,0,0,0,0,0,0,0,0,0,0,0,0,0,0,0,0,0,0,0,0,0,0,0,0,0,EB39)';
    'VSS'<24>:'(0,0,0,0,0,0,0,0,0,0,0,0,0,0,0,0,0,0,0,0,0,0,0,0,0,0,0,0,0,EB41)';
    'VSS'<23>:'(0,0,0,0,0,0,0,0,0,0,0,0,0,0,0,0,0,0,0,0,0,0,0,0,0,0,0,0,0,EB65)';
    'VSS'<22>:'(0,0,0,0,0,0,0,0,0,0,0,0,0,0,0,0,0,0,0,0,0,0,0,0,0,0,0,0,0,EB69)';
    'VSS'<21>:'(0,0,0,0,0,0,0,0,0,0,0,0,0,0,0,0,0,0,0,0,0,0,0,0,0,0,0,0,0,EC10)';
    'VSS'<20>:'(0,0,0,0,0,0,0,0,0,0,0,0,0,0,0,0,0,0,0,0,0,0,0,0,0,0,0,0,0,EC70)';
    'VSS'<19>:'(0,0,0,0,0,0,0,0,0,0,0,0,0,0,0,0,0,0,0,0,0,0,0,0,0,0,0,0,0,EC72)';
    'VSS'<18>:'(0,0,0,0,0,0,0,0,0,0,0,0,0,0,0,0,0,0,0,0,0,0,0,0,0,0,0,0,0,EC74)';
    'VSS'<17>:'(0,0,0,0,0,0,0,0,0,0,0,0,0,0,0,0,0,0,0,0,0,0,0,0,0,0,0,0,0,EC76)';
    'VSS'<16>:'(0,0,0,0,0,0,0,0,0,0,0,0,0,0,0,0,0,0,0,0,0,0,0,0,0,0,0,0,0,ED11)';
    'VSS'<15>:'(0,0,0,0,0,0,0,0,0,0,0,0,0,0,0,0,0,0,0,0,0,0,0,0,0,0,0,0,0,ED15)';
    'VSS'<14>:'(0,0,0,0,0,0,0,0,0,0,0,0,0,0,0,0,0,0,0,0,0,0,0,0,0,0,0,0,0,ED23)';
    'VSS'<13>:'(0,0,0,0,0,0,0,0,0,0,0,0,0,0,0,0,0,0,0,0,0,0,0,0,0,0,0,0,0,ED29)';
    'VSS'<12>:'(0,0,0,0,0,0,0,0,0,0,0,0,0,0,0,0,0,0,0,0,0,0,0,0,0,0,0,0,0,ED35)';
    'VSS'<11>:'(0,0,0,0,0,0,0,0,0,0,0,0,0,0,0,0,0,0,0,0,0,0,0,0,0,0,0,0,0,ED77)';
    'VSS'<10>:'(0,0,0,0,0,0,0,0,0,0,0,0,0,0,0,0,0,0,0,0,0,0,0,0,0,0,0,0,0,EE24)';
    'VSS'<9>:'(0,0,0,0,0,0,0,0,0,0,0,0,0,0,0,0,0,0,0,0,0,0,0,0,0,0,0,0,0,EE28)';~

    'VSS'<8>:'(0,0,0,0,0,0,0,0,0,0,0,0,0,0,0,0,0,0,0,0,0,0,0,0,0,0,0,0,0,EE30)';~

    'VSS'<7>:'(0,0,0,0,0,0,0,0,0,0,0,0,0,0,0,0,0,0,0,0,0,0,0,0,0,0,0,0,0,EE34)';~

    'VSS'<6>:'(0,0,0,0,0,0,0,0,0,0,0,0,0,0,0,0,0,0,0,0,0,0,0,0,0,0,0,0,0,EE36)';~

    'VSS'<5>:'(0,0,0,0,0,0,0,0,0,0,0,0,0,0,0,0,0,0,0,0,0,0,0,0,0,0,0,0,0,EE70)';~

    'VSS'<4>:'(0,0,0,0,0,0,0,0,0,0,0,0,0,0,0,0,0,0,0,0,0,0,0,0,0,0,0,0,0,EE76)';~

    'VSS'<3>:'(0,0,0,0,0,0,0,0,0,0,0,0,0,0,0,0,0,0,0,0,0,0,0,0,0,0,0,0,0,EE78)';~

    'VSS'<2>:'(0,0,0,0,0,0,0,0,0,0,0,0,0,0,0,0,0,0,0,0,0,0,0,0,0,0,0,0,0,EF71)';~

    'VSS'<1>:'(0,0,0,0,0,0,0,0,0,0,0,0,0,0,0,0,0,0,0,0,0,0,0,0,0,0,0,0,0,EF75)';~

    'VSS'<0>:'(0,0,0,0,0,0,0,0,0,0,0,0,0,0,0,0,0,0,0,0,0,0,0,0,0,0,0,0,0,EF79)';~

    'VSS_VCCIN_SENSE':'(0,0,0,0,0,0,0,0,0,0,0,0,0,0,0,0,0,0,AY85,0,0,0,0,0,0,0,0~
,0,0,0)';$S;
    'VSS_VCCIO_SENSE':'(0,0,0,0,0,0,0,0,0,0,0,0,0,0,0,0,0,0,0,0,0,BF5,0,0,0,0,0,~
0,0,0)';$S;
    'VSS_VCCSA_SENSE':'(0,0,0,0,0,0,0,0,0,0,0,0,0,0,0,0,0,0,0,0,0,CG76,0,0,0,0,0~
,0,0,0)';$S;
end_primitive;
primitive 'SLG55021_SM-IC,G56246-001';body 'SLG55021';
    'GND':'(4)';
    'THPAD':'(9)';
    'VCC':'(1)';
    'ON':'(2)';IN;
    'SHDN_N':'(3)';IN;
    'D':'(5)';IN;
    'S':'(6)';IN;
    'G':'(7)';OUT;
    'PG':'(8)';OUT;
end_primitive;
primitive 'SMC-CON13-GP_CONN-GC2-SMC-CON1A';body 'SMC-CON13-GP';
    '1':'(1)';
    '2':'(2)';
    '3':'(3)';
    '4':'(4)';
    '5':'(5)';
    '6':'(6)';
    '7':'(7)';
    '8':'(8)';
    '9':'(9)';
    '10':'(10)';
    '11':'(11)';
    '12':'(12)';
    '13':'(13)';
    'PTH1':'(PTH1)';
    'PTH2':'(PTH2)';
end_primitive;
primitive 'SMC-CONN60A-22-GP_CONN-G7-SMC-A';body 'SMC-CONN60A-22-GP';
    '1':'(1)';
    '3':'(3)';
    '5':'(5)';
    '7':'(7)';
    '2':'(2)';
    '4':'(4)';
    '6':'(6)';
    '8':'(8)';
    '9':'(9)';
    '11':'(11)';
    '13':'(13)';
    '15':'(15)';
    '17':'(17)';
    '19':'(19)';
    '21':'(21)';
    '23':'(23)';
    '25':'(25)';
    '27':'(27)';
    '29':'(29)';
    '31':'(31)';
    '33':'(33)';
    '35':'(35)';
    '37':'(37)';
    '39':'(39)';
    '41':'(41)';
    '43':'(43)';
    '45':'(45)';
    '47':'(47)';
    '49':'(49)';
    '51':'(51)';
    '53':'(53)';
    '55':'(55)';
    '57':'(57)';
    '59':'(59)';
    '10':'(10)';
    '12':'(12)';
    '14':'(14)';
    '16':'(16)';
    '18':'(18)';
    '20':'(20)';
    '22':'(22)';
    '24':'(24)';
    '26':'(26)';
    '28':'(28)';
    '30':'(30)';
    '32':'(32)';
    '34':'(34)';
    '36':'(36)';
    '38':'(38)';
    '40':'(40)';
    '42':'(42)';
    '44':'(44)';
    '46':'(46)';
    '48':'(48)';
    '50':'(50)';
    '52':'(52)';
    '54':'(54)';
    '56':'(56)';
    '58':'(58)';
    '60':'(60)';
    'NP1':'(NP1)';
    'NP2':'(NP2)';
    'PTH1':'(PTH1)';
    'PTH2':'(PTH2)';
end_primitive;
primitive 'SN74LVC2G07DCKR-GP_DISCRET-G4-A';body 'SN74LVC2G07DCKR-GP';
    '1A':'(1)';IN;
    'GND':'(2)';
    '2A':'(3)';IN;
    '2Y':'(4)';OUT;
    'VCC':'(5)';
    '1Y':'(6)';OUT;
end_primitive;
primitive 'SOCKET_P_MECH_A_LEFT-P0,PLASTIA';body 'SOCKET_P_MECH_A';
end_primitive;
primitive 'SOCKET_P_MECH_A_RIGHT-P0,PLASTA';body 'SOCKET_P_MECH_A';
end_primitive;
primitive 'SPRINGVILLE_SM1-IC,G47144-004';body 'SPRINGVILLE';
    'CBOT':'(37)';
    'CTOP':'(40)';
    'DEV_OFF_N':'(28)';IN;
    'GND':'(65)';
    'JTAG_CLK':'(19)';IN;
    'JTAG_TDI':'(29)';IN;
    'JTAG_TDO':'(4)';OUT;
    'JTAG_TMS':'(18)';IN;
    'LAN_PWR_GOOD':'(1)';IN;
    'LED0':'(31)';OUT;
    'LED1':'(30)';OUT;
    'LED2':'(33)';OUT;
    'MDI_MINUS0_SFP_I2C_DATA':'(57)';BIDI;
    'MDI_MINUS1_SRDS_SIG_DET':'(54)';BIDI;
    'MDI_MINUS2_SETN':'(52)';BIDI;
    'MDI_MINUS3_SERN':'(49)';BIDI;
    'MDI_PLUS0_NC':'(58)';BIDI;
    'MDI_PLUS1_SFP_I2C_CLK':'(55)';BIDI;
    'MDI_PLUS2_SETP':'(53)';BIDI;
    'MDI_PLUS3_SERP':'(50)';BIDI;
    'NC':'(22)';IN;
    'NC_SI_ARB_IN':'(43)';IN;
    'NC_SI_ARB_OUT':'(44)';OUT;
    'NC_SI_CLK_IN':'(2)';IN;
    'NC_SI_CRS_DV':'(3)';OUT;
    'NC_SI_RXD0':'(6)';OUT;
    'NC_SI_RXD1':'(5)';OUT;
    'NC_SI_TXD0':'(9)';IN;
    'NC_SI_TXD1':'(8)';IN;
    'NC_SI_TX_EN':'(7)';IN;
    'NVM_CS_N':'(15)';OUT;
    'NVM_SI':'(12)';OUT;
    'NVM_SK':'(13)';OUT;
    'NVM_SO':'(14)';IN;
    'PECLKN':'(25)';IN;
    'PECLKP':'(26)';IN;
    'PE_RN':'(23)';IN;
    'PE_RP':'(24)';IN;
    'PE_RST_N':'(17)';IN;
    'PE_TN':'(20)';OUT;
    'PE_TP':'(21)';OUT;
    'PE_WAKE_N':'(16)';BIDI;
    'RSET':'(48)';
    'SDP0':'(63)';BIDI;
    'SDP1_PCIE_DIS_SDP1':'(61)';BIDI;
    'SDP2':'(62)';BIDI;
    'SDP3':'(60)';BIDI;
    'SMB_ALRT_N':'(35)';OUT;
    'SMB_CLK':'(34)';BIDI;
    'SMB_DATA':'(36)';BIDI;
    'VDD0P9'<3>:'(42)';
    'VDD0P9'<2>:'(11)';
    'VDD0P9'<1>:'(32)';
    'VDD0P9'<0>:'(59)';
    'VDD0P9_OUT':'(38)';
    'VDD1P5'<1>:'(47)';
    'VDD1P5'<0>:'(56)';
    'VDD1P5_OUT':'(39)';
    'VDD3P3'<4>:'(10)';
    'VDD3P3'<3>:'(27)';
    'VDD3P3'<2>:'(41)';
    'VDD3P3'<1>:'(51)';
    'VDD3P3'<0>:'(64)';
    'XTAL1':'(46)';IN;
    'XTAL2':'(45)';OUT;
end_primitive;
primitive 'ST220U10VDM-LGP_SMD-TCG-ST220UA';body 'ST220U10VDM-LGP';
    '1':'(1)';
    '2':'(2)';
end_primitive;
primitive 'ST270U2D5VBM-GP_SMD-TCG2-ST270A';body 'ST270U2D5VBM-GP';
    '1':'(1)';
    '2':'(2)';
end_primitive;
primitive 'ST470U6D3VDM-7-GP_SMD-TCG4-ST4A';body 'ST470U6D3VDM-7-GP';
    '1':'(1)';
    '2':'(2)';
end_primitive;
primitive 'STANDOFF_TH1-SO,H72821-001';body 'STANDOFF';
    'IO1':'(1)';BIDI;
end_primitive;
primitive 'STFT363B238R224H453-GP_DISCRETA';body 'STFT363B238R224H453-GP';
    '1':'(1)';
end_primitive;
primitive 'SW-SLIDE75-GP_DISCRET-G6-SW-SLA';body 'SW-SLIDE75-GP';
    '1':'(1)';
    '2':'(2)';
    '3':'(3)';
    '4':'(4)';
    '5':'(5)';
    'NP1':'(NP1)';
    'NP2':'(NP2)';
    '6':'(6)';
    '7':'(7)';
end_primitive;
primitive 'SWITCH_D37771002_SM-IC,D37771-A';body 'SWITCH_D37771002';
    'PIN4':'(4)';
    'PIN3':'(3)';
    'PIN1':'(1)';
    'PIN2':'(2)';
end_primitive;
primitive 'SWITCH_D90553001_SMLF-IC,D9055A';body 'SWITCH_D90553001';
    'A':'(1)';IN;
    'B':'(2)';BIDI;
end_primitive;
primitive 'TC7PZ14FU-GP_DISCRET-GA1-TC7PZA';body 'TC7PZ14FU-GP';
    '1A':'(1)';IN;
    'GND':'(2)';
    '2A':'(3)';IN;
    '2Y':'(4)';OUT;
    'VCC':'(5)';
    '1Y':'(6)';OUT;
end_primitive;
primitive 'TCA9517DGKR-GP_DISCRET-G8-TCA9A';body 'TCA9517DGKR-GP';
    'VCCA':'(1)';
    'SCLA':'(2)';
    'SDAA':'(3)';
    'GND':'(4)';
    'VCCB':'(8)';
    'SCLB':'(7)';
    'SDAB':'(6)';
    'EN':'(5)';
end_primitive;
primitive 'TCA9555PWR-GP_DISCRET-GC1-TCA9A';body 'TCA9555PWR-GP';
    'INT#':'(1)';OUT;
    'A1':'(2)';IN;
    'A2':'(3)';IN;
    'P00':'(4)';BIDI;
    'P01':'(5)';BIDI;
    'P02':'(6)';BIDI;
    'P03':'(7)';BIDI;
    'P04':'(8)';BIDI;
    'P05':'(9)';BIDI;
    'P06':'(10)';BIDI;
    'P07':'(11)';BIDI;
    'GND':'(12)';
    'VCC':'(24)';
    'SDA':'(23)';
    'SCL':'(22)';
    'A0':'(21)';IN;
    'P10':'(13)';BIDI;
    'P11':'(14)';BIDI;
    'P12':'(15)';BIDI;
    'P13':'(16)';BIDI;
    'P14':'(17)';BIDI;
    'P15':'(18)';BIDI;
    'P16':'(19)';BIDI;
    'P17':'(20)';BIDI;
end_primitive;
primitive 'TEST-PAD-12P-1-GP-U_DISCRET-GBA';body 'TEST-PAD-12P-1-GP-U';
    'GND'<0>:'(3)';
    'GND'<1>:'(4)';
    'GND'<2>:'(5)';
    'GND'<3>:'(6)';
    'GND'<4>:'(7)';
    'GND'<5>:'(8)';
    'GND'<6>:'(9)';
    'GND'<7>:'(10)';
    'GND'<8>:'(11)';
    'GND'<9>:'(12)';
    'DP':'(1)';
    'DN':'(2)';
end_primitive;
primitive 'TMP421_TSSOP-IC,G62962-001';body 'TMP421';
    'A'<1>:'(3)';IN;
    'A'<0>:'(4)';IN;
    'DXN':'(2)';IN;
    'DXP':'(1)';IN;
    'GND':'(5)';
    'SCL':'(7)';BIDI;
    'SDA':'(6)';BIDI;
    'VP':'(8)';
end_primitive;
primitive 'TPAD-DIFF-4P-GP_DISCRET-GB3-TPA';body 'TPAD-DIFF-4P-GP';
    '1':'(1)';
    '2':'(2)';
    'GND1':'(GND1)';
    'GND2':'(GND2)';
end_primitive;
primitive 'TPAD-SE-2P-GP_DISCRET-GA1-TPADA';body 'TPAD-SE-2P-GP';
    '1':'(1)';
    'GND1':'(GND1)';
end_primitive;
primitive 'TPS2061_SM-IC,H66405-001';body 'TPS2061';
    'EN_N':'(4)';IN;
    'GND':'(2)';
    'IN':'(5)';IN;
    'OC_N':'(3)';OUT;
    'OUT':'(1)';OUT;
end_primitive;
primitive 'TPS3700_SM-IC,H69492-001';body 'TPS3700';
    'GND':'(5)';
    'INAP':'(4)';BIDI;
    'INBN':'(3)';BIDI;
    'OUTA':'(6)';OUT;
    'OUTB':'(1)';OUT;
    'VDD':'(2)';
end_primitive;
primitive 'TPS54821_LCC-IC,H63269-001';body 'TPS54821';
    'BOOT':'(13)';
    'COMP':'(8)';BIDI;
    'EN':'(10)';IN;
    'GND'<1>:'(3)';
    'GND'<0>:'(2)';
    'PH'<1>:'(12)';OUT;
    'PH'<0>:'(11)';OUT;
    'PVIN'<1>:'(5)';IN;
    'PVIN'<0>:'(4)';IN;
    'PWRGD':'(14)';OUT;
    'RT_CLK':'(1)';IN;
    'SS_TR':'(9)';IN;
    'THPAD':'(15)';
    'VIN':'(6)';IN;
    'VSENSE':'(7)';IN;
end_primitive;
primitive 'TTL08_QFN15-74LVC08A,IC,D90404B';body 'TTL08';
    'Y'<0>:'(11,8,6,3)';$S;OUT;
    'B'<0>:'(13,10,5,2)';$S;IN;
    'A'<0>:'(12,9,4,1)';$S;IN;
end_primitive;
primitive 'TTL1G07_A_SOP-74LVC1G07,IC,C88B';body 'TTL1G07_A';
    'A':'(2)';IN;
    'Y':'(4)';OUT;
end_primitive;
primitive 'TTL1G08_SOTLF-NC7SZ08,IC,D1032B';body 'TTL1G08';
    'Y'<0>:'(4)';OUT;
    'A'<0>:'(1)';IN;
    'B'<0>:'(2)';IN;
end_primitive;
primitive 'TTL1G08_SOTLF-NC7SZ08,IC,D1032C';body 'TTL1G08';
    'Y'<0>:'(4)';OUT;
    'A'<0>:'(1)';IN;
    'B'<0>:'(2)';IN;
end_primitive;
primitive 'TTL1G126_A_SOT-74HC1G126,IC,A7B';body 'TTL1G126_A';
    'OE':'(1)';IN;
    'A':'(2)';IN;
    'Y':'(4)';OUT;
end_primitive;
primitive 'TTL1G32_A_SOT-74LVC1G32,IC,E60B';body 'TTL1G32_A';
    'A':'(1)';IN;
    'B':'(2)';IN;
    'Y':'(4)';OUT;
end_primitive;
primitive 'TTL1G86_SOTLF-74AHCT1G86,IC,D3B';body 'TTL1G86';
    'A':'(1)';IN;
    'B':'(2)';IN;
    'Y':'(4)';OUT;
end_primitive;
primitive 'TTL3126_QFNLF-74CBTLV3126,IC,DB';body 'TTL3126';
    'OE'<0>:'(1,4,10,13)';$S;IN;
    'A'<0>:'(2,5,9,12)';$S;BIDI;
    'B'<0>:'(3,6,8,11)';$S;BIDI;
end_primitive;
primitive 'U74AHCT1G125G-AL5-R-GP-U_TTL-GA';body 'U74AHCT1G125G-AL5-R-GP-U';
    'OE#':'(1)';
    'A':'(2)';
    'GND':'(3)';
    'Y':'(4)';
    'VCC':'(5)';
end_primitive;
primitive 'VERT_BATT_3PIN_PIP-3PVERT,C686A';body 'VERT_BATT_3PIN';
    'N':'(3)';
    'P1':'(1)';
    'P2':'(2)';
end_primitive;
primitive 'W25Q128_SKT16-IC,H12709-001';body 'W25Q128';
    'HOLD_N_IO'<3>:'(1)';BIDI;
    'VCC':'(2)';
    'RESET_N':'(3)';IN;
    'NC'<0>:'(4)';
    'NC'<1>:'(5)';
    'NC'<2>:'(6)';
    'CS_N':'(7)';IN;
    'DO_IO'<1>:'(8)';BIDI;
    'WP_N_IO'<2>:'(9)';BIDI;
    'GND':'(10)';
    'NC'<3>:'(11)';
    'NC'<4>:'(12)';
    'NC'<5>:'(13)';
    'NC'<6>:'(14)';
    'DI_IO'<0>:'(15)';BIDI;
    'CLK':'(16)';IN;
end_primitive;
primitive 'W25Q256FVFIG-GP_MEMORY-G4-W25QA';body 'W25Q256FVFIG-GP';
    'HOLD#/IO3':'(1)';BIDI;
    'VCC':'(2)';
    'RESET#':'(3)';IN;
    'NC#4':'(4)';
    'NC#5':'(5)';
    'NC#6':'(6)';
    'CS#':'(7)';IN;
    'DO/IO1':'(8)';BIDI;
    'WP#/IO2':'(9)';BIDI;
    'GND':'(10)';
    'NC#11':'(11)';
    'NC#12':'(12)';
    'NC#13':'(13)';
    'NC#14':'(14)';
    'DI/IO0':'(15)';BIDI;
    'CLK':'(16)';IN;
end_primitive;
primitive 'W25Q256_XSOI-IC,H25002-001';body 'W25Q256';
    'WP_N_IO'<2>:'(9)';BIDI;
    'NC'<0>:'(14)';
    'NC'<1>:'(13)';
    'NC'<2>:'(12)';
    'NC'<3>:'(11)';
    'NC'<4>:'(6)';
    'NC'<5>:'(5)';
    'NC'<6>:'(4)';
    'GND':'(10)';
    'DO_IO'<1>:'(8)';BIDI;
    'CLK':'(16)';IN;
    'VCC':'(2)';
    'CS_N':'(7)';IN;
    'DI_IO'<0>:'(15)';BIDI;
    'RESET_N':'(3)';IN;
    'HOLD_N_IO'<3>:'(1)';BIDI;
end_primitive;
primitive 'ZENER_SM-13V,IC,H69095-001';body 'ZENER';
    'A':'(2)';
    'C':'(1)';
end_primitive;
END.
